-- pcdb file, Rev:1.0 written by Allegro Design Entry HDL 17.4-2019 S026 (4007227) 1/17/2022 on Thu Sep 14 14:12:01 2023
#ISCELL
  pure_quanta quanta_title_block_c *
  *
#ISCELL
  pure_quanta quanta_title_block_c *
  *
#ISCELL
  pure_quanta quanta_title_block_c *
  *
#ISCELL
  pure_quanta quanta_title_block_c *
  *
#ISCELL
  pure_quanta quanta_title_block_c *
  *
#ISCELL
  pure_quanta quanta_title_block_c *
  *
#ISCELL
  pure_quanta quanta_title_block_c *
  *
#ISCELL
  pure_quanta quanta_title_block_c *
  *
#ISCELL
  pure_quanta quanta_title_block_c *
  *
#ISCELL
  pure_quanta quanta_title_block_c *
  *
#ISCELL
  pure_quanta_power cad_note *
  *
#CELL
  pure_quanta genoa_sp5 *
  page10_i200
#ISCELL
  mstr_standard offpage *
  page10_i682
#ISCELL
  mstr_standard tap *
  page10_i683
#ISCELL
  mstr_standard tap *
  page10_i684
#ISCELL
  mstr_standard tap *
  page10_i685
#ISCELL
  mstr_standard tap *
  page10_i686
#ISCELL
  mstr_standard tap *
  page10_i687
#ISCELL
  mstr_standard tap *
  page10_i688
#ISCELL
  mstr_standard tap *
  page10_i689
#ISCELL
  mstr_standard tap *
  page10_i690
#ISCELL
  mstr_standard tap *
  page10_i691
#ISCELL
  mstr_standard tap *
  page10_i692
#ISCELL
  mstr_standard tap *
  page10_i693
#ISCELL
  mstr_standard tap *
  page10_i694
#ISCELL
  mstr_standard tap *
  page10_i695
#ISCELL
  mstr_standard tap *
  page10_i696
#ISCELL
  mstr_standard tap *
  page10_i697
#ISCELL
  mstr_standard tap *
  page10_i698
#ISCELL
  mstr_standard tap *
  page10_i699
#ISCELL
  mstr_standard tap *
  page10_i700
#ISCELL
  mstr_standard tap *
  page10_i701
#ISCELL
  mstr_standard tap *
  page10_i702
#ISCELL
  mstr_standard offpage *
  page10_i703
#ISCELL
  mstr_standard tap *
  page10_i704
#ISCELL
  mstr_standard tap *
  page10_i705
#ISCELL
  mstr_standard tap *
  page10_i706
#ISCELL
  mstr_standard tap *
  page10_i707
#ISCELL
  mstr_standard tap *
  page10_i708
#ISCELL
  mstr_standard tap *
  page10_i709
#ISCELL
  mstr_standard tap *
  page10_i710
#ISCELL
  mstr_standard tap *
  page10_i711
#ISCELL
  mstr_standard tap *
  page10_i712
#ISCELL
  mstr_standard tap *
  page10_i713
#ISCELL
  mstr_standard tap *
  page10_i714
#ISCELL
  mstr_standard tap *
  page10_i715
#ISCELL
  mstr_standard tap *
  page10_i716
#ISCELL
  mstr_standard tap *
  page10_i717
#ISCELL
  mstr_standard tap *
  page10_i718
#ISCELL
  mstr_standard tap *
  page10_i719
#ISCELL
  mstr_standard tap *
  page10_i720
#ISCELL
  mstr_standard tap *
  page10_i721
#ISCELL
  mstr_standard tap *
  page10_i722
#ISCELL
  mstr_standard tap *
  page10_i723
#ISCELL
  mstr_standard tap *
  page10_i724
#ISCELL
  mstr_standard tap *
  page10_i725
#ISCELL
  mstr_standard tap *
  page10_i726
#ISCELL
  mstr_standard tap *
  page10_i727
#ISCELL
  mstr_standard tap *
  page10_i728
#ISCELL
  mstr_standard tap *
  page10_i729
#ISCELL
  mstr_standard tap *
  page10_i730
#ISCELL
  mstr_standard tap *
  page10_i731
#ISCELL
  mstr_standard tap *
  page10_i732
#ISCELL
  mstr_standard tap *
  page10_i733
#ISCELL
  mstr_standard tap *
  page10_i734
#ISCELL
  mstr_standard tap *
  page10_i735
#ISCELL
  mstr_standard tap *
  page10_i736
#ISCELL
  mstr_standard tap *
  page10_i737
#ISCELL
  mstr_standard tap *
  page10_i738
#ISCELL
  mstr_standard tap *
  page10_i739
#ISCELL
  mstr_standard offpage *
  page10_i740
#ISCELL
  mstr_standard offpage *
  page10_i741
#ISCELL
  mstr_standard tap *
  page10_i742
#ISCELL
  mstr_standard tap *
  page10_i743
#ISCELL
  mstr_standard tap *
  page10_i744
#ISCELL
  mstr_standard tap *
  page10_i745
#ISCELL
  mstr_standard tap *
  page10_i746
#ISCELL
  mstr_standard tap *
  page10_i747
#ISCELL
  mstr_standard tap *
  page10_i748
#ISCELL
  mstr_standard tap *
  page10_i749
#ISCELL
  mstr_standard tap *
  page10_i750
#ISCELL
  mstr_standard tap *
  page10_i751
#ISCELL
  mstr_standard tap *
  page10_i752
#ISCELL
  mstr_standard tap *
  page10_i753
#ISCELL
  mstr_standard tap *
  page10_i754
#ISCELL
  mstr_standard tap *
  page10_i755
#ISCELL
  mstr_standard tap *
  page10_i756
#ISCELL
  mstr_standard tap *
  page10_i757
#ISCELL
  mstr_standard tap *
  page10_i758
#ISCELL
  mstr_standard tap *
  page10_i759
#ISCELL
  mstr_standard tap *
  page10_i760
#ISCELL
  mstr_standard tap *
  page10_i761
#ISCELL
  mstr_standard tap *
  page10_i762
#ISCELL
  mstr_standard tap *
  page10_i763
#ISCELL
  mstr_standard tap *
  page10_i764
#ISCELL
  mstr_standard tap *
  page10_i765
#ISCELL
  mstr_standard tap *
  page10_i766
#ISCELL
  mstr_standard tap *
  page10_i767
#ISCELL
  mstr_standard tap *
  page10_i768
#ISCELL
  mstr_standard tap *
  page10_i769
#ISCELL
  mstr_standard tap *
  page10_i770
#ISCELL
  mstr_standard tap *
  page10_i771
#ISCELL
  mstr_standard tap *
  page10_i772
#ISCELL
  mstr_standard tap *
  page10_i773
#ISCELL
  mstr_standard tap *
  page10_i774
#ISCELL
  mstr_standard tap *
  page10_i775
#ISCELL
  mstr_standard tap *
  page10_i776
#ISCELL
  mstr_standard tap *
  page10_i777
#ISCELL
  mstr_standard tap *
  page10_i778
#ISCELL
  mstr_standard tap *
  page10_i779
#ISCELL
  mstr_standard tap *
  page10_i780
#ISCELL
  mstr_standard tap *
  page10_i781
#ISCELL
  mstr_standard tap *
  page10_i782
#ISCELL
  mstr_standard tap *
  page10_i783
#ISCELL
  mstr_standard tap *
  page10_i784
#ISCELL
  mstr_standard tap *
  page10_i785
#ISCELL
  mstr_standard tap *
  page10_i786
#ISCELL
  mstr_standard tap *
  page10_i787
#ISCELL
  mstr_standard tap *
  page10_i788
#ISCELL
  mstr_standard tap *
  page10_i789
#ISCELL
  mstr_standard tap *
  page10_i790
#ISCELL
  mstr_standard tap *
  page10_i791
#ISCELL
  mstr_standard tap *
  page10_i792
#ISCELL
  mstr_standard tap *
  page10_i793
#ISCELL
  mstr_standard tap *
  page10_i794
#ISCELL
  mstr_standard tap *
  page10_i795
#ISCELL
  mstr_standard tap *
  page10_i796
#ISCELL
  mstr_standard tap *
  page10_i797
#ISCELL
  mstr_standard tap *
  page10_i798
#ISCELL
  mstr_standard tap *
  page10_i799
#ISCELL
  mstr_standard tap *
  page10_i800
#ISCELL
  mstr_standard tap *
  page10_i801
#ISCELL
  mstr_standard tap *
  page10_i802
#ISCELL
  mstr_standard tap *
  page10_i803
#ISCELL
  mstr_standard tap *
  page10_i804
#ISCELL
  mstr_standard tap *
  page10_i805
#ISCELL
  standard offpage *
  page10_i806
#ISCELL
  standard offpage *
  page10_i807
#ISCELL
  standard offpage *
  page10_i808
#ISCELL
  standard offpage *
  page10_i809
#ISCELL
  mstr_standard tap *
  page10_i810
#ISCELL
  mstr_standard tap *
  page10_i811
#ISCELL
  mstr_standard tap *
  page10_i812
#ISCELL
  mstr_standard tap *
  page10_i813
#ISCELL
  mstr_standard tap *
  page10_i814
#ISCELL
  mstr_standard tap *
  page10_i815
#ISCELL
  mstr_standard tap *
  page10_i816
#ISCELL
  mstr_standard tap *
  page10_i817
#ISCELL
  mstr_standard tap *
  page10_i818
#ISCELL
  mstr_standard tap *
  page10_i819
#ISCELL
  mstr_standard tap *
  page10_i820
#ISCELL
  mstr_standard tap *
  page10_i821
#ISCELL
  mstr_standard tap *
  page10_i822
#ISCELL
  mstr_standard tap *
  page10_i823
#ISCELL
  standard offpage *
  page10_i824
#ISCELL
  standard offpage *
  page10_i825
#ISCELL
  standard offpage *
  page10_i826
#ISCELL
  standard offpage *
  page10_i827
#ISCELL
  standard offpage *
  page10_i828
#ISCELL
  standard offpage *
  page10_i829
#ISCELL
  standard offpage *
  page10_i830
#ISCELL
  standard offpage *
  page10_i831
#ISCELL
  mstr_standard offpage *
  page10_i832
#ISCELL
  standard offpage *
  page10_i833
#ISCELL
  standard offpage *
  page10_i834
#ISCELL
  standard offpage *
  page10_i835
#ISCELL
  standard offpage *
  page10_i836
#CELL
  pure_quanta q_res *
  page10_i837
#ISCELL
  mstr_standard offpage *
  page10_i838
#ISCELL
  pure_quanta quanta_title_block_c *
  *
#ISCELL
  pure_quanta_power cad_note *
  *
#CELL
  pure_quanta genoa_sp5 *
  page11_i171
#ISCELL
  mstr_standard offpage *
  page11_i172
#ISCELL
  mstr_standard tap *
  page11_i173
#ISCELL
  mstr_standard tap *
  page11_i174
#ISCELL
  mstr_standard tap *
  page11_i175
#ISCELL
  mstr_standard tap *
  page11_i176
#ISCELL
  mstr_standard tap *
  page11_i177
#ISCELL
  mstr_standard tap *
  page11_i178
#ISCELL
  mstr_standard tap *
  page11_i179
#ISCELL
  mstr_standard tap *
  page11_i180
#ISCELL
  mstr_standard tap *
  page11_i181
#ISCELL
  mstr_standard tap *
  page11_i182
#ISCELL
  mstr_standard tap *
  page11_i183
#ISCELL
  mstr_standard tap *
  page11_i184
#ISCELL
  mstr_standard tap *
  page11_i185
#ISCELL
  mstr_standard tap *
  page11_i186
#ISCELL
  mstr_standard tap *
  page11_i187
#ISCELL
  mstr_standard tap *
  page11_i188
#ISCELL
  mstr_standard tap *
  page11_i189
#ISCELL
  mstr_standard tap *
  page11_i190
#ISCELL
  mstr_standard tap *
  page11_i191
#ISCELL
  mstr_standard tap *
  page11_i192
#ISCELL
  mstr_standard tap *
  page11_i193
#ISCELL
  mstr_standard tap *
  page11_i194
#ISCELL
  mstr_standard tap *
  page11_i195
#ISCELL
  mstr_standard tap *
  page11_i196
#ISCELL
  mstr_standard tap *
  page11_i197
#ISCELL
  mstr_standard tap *
  page11_i198
#ISCELL
  mstr_standard tap *
  page11_i199
#ISCELL
  mstr_standard tap *
  page11_i200
#ISCELL
  mstr_standard tap *
  page11_i201
#ISCELL
  mstr_standard tap *
  page11_i202
#ISCELL
  mstr_standard tap *
  page11_i203
#ISCELL
  mstr_standard tap *
  page11_i204
#ISCELL
  mstr_standard offpage *
  page11_i205
#ISCELL
  mstr_standard offpage *
  page11_i206
#ISCELL
  mstr_standard tap *
  page11_i207
#ISCELL
  mstr_standard tap *
  page11_i208
#ISCELL
  mstr_standard tap *
  page11_i209
#ISCELL
  mstr_standard tap *
  page11_i210
#ISCELL
  mstr_standard tap *
  page11_i211
#ISCELL
  mstr_standard tap *
  page11_i212
#ISCELL
  mstr_standard tap *
  page11_i213
#ISCELL
  mstr_standard tap *
  page11_i214
#ISCELL
  mstr_standard tap *
  page11_i215
#ISCELL
  mstr_standard tap *
  page11_i216
#ISCELL
  mstr_standard tap *
  page11_i217
#ISCELL
  mstr_standard tap *
  page11_i218
#ISCELL
  mstr_standard tap *
  page11_i219
#ISCELL
  mstr_standard tap *
  page11_i220
#ISCELL
  mstr_standard tap *
  page11_i221
#ISCELL
  mstr_standard tap *
  page11_i222
#ISCELL
  mstr_standard tap *
  page11_i223
#ISCELL
  mstr_standard tap *
  page11_i224
#ISCELL
  mstr_standard tap *
  page11_i225
#ISCELL
  mstr_standard tap *
  page11_i226
#ISCELL
  mstr_standard tap *
  page11_i227
#ISCELL
  mstr_standard tap *
  page11_i228
#ISCELL
  mstr_standard tap *
  page11_i229
#ISCELL
  mstr_standard tap *
  page11_i230
#ISCELL
  mstr_standard tap *
  page11_i231
#ISCELL
  mstr_standard tap *
  page11_i232
#ISCELL
  mstr_standard tap *
  page11_i233
#ISCELL
  mstr_standard tap *
  page11_i234
#ISCELL
  mstr_standard tap *
  page11_i235
#ISCELL
  mstr_standard tap *
  page11_i236
#ISCELL
  mstr_standard tap *
  page11_i237
#ISCELL
  mstr_standard tap *
  page11_i238
#ISCELL
  mstr_standard tap *
  page11_i239
#ISCELL
  mstr_standard tap *
  page11_i240
#ISCELL
  mstr_standard tap *
  page11_i241
#ISCELL
  mstr_standard tap *
  page11_i242
#ISCELL
  mstr_standard tap *
  page11_i243
#ISCELL
  mstr_standard offpage *
  page11_i244
#ISCELL
  mstr_standard tap *
  page11_i245
#ISCELL
  mstr_standard tap *
  page11_i246
#ISCELL
  mstr_standard tap *
  page11_i247
#ISCELL
  mstr_standard tap *
  page11_i248
#ISCELL
  mstr_standard tap *
  page11_i249
#ISCELL
  mstr_standard tap *
  page11_i250
#ISCELL
  mstr_standard tap *
  page11_i251
#ISCELL
  mstr_standard tap *
  page11_i252
#ISCELL
  mstr_standard tap *
  page11_i253
#ISCELL
  mstr_standard tap *
  page11_i254
#ISCELL
  mstr_standard tap *
  page11_i255
#ISCELL
  mstr_standard tap *
  page11_i256
#ISCELL
  mstr_standard tap *
  page11_i257
#ISCELL
  mstr_standard tap *
  page11_i258
#ISCELL
  mstr_standard tap *
  page11_i259
#ISCELL
  mstr_standard tap *
  page11_i260
#ISCELL
  mstr_standard tap *
  page11_i261
#ISCELL
  mstr_standard tap *
  page11_i262
#ISCELL
  mstr_standard tap *
  page11_i263
#ISCELL
  mstr_standard tap *
  page11_i264
#ISCELL
  mstr_standard tap *
  page11_i265
#ISCELL
  mstr_standard tap *
  page11_i266
#ISCELL
  mstr_standard tap *
  page11_i267
#ISCELL
  mstr_standard tap *
  page11_i268
#ISCELL
  mstr_standard tap *
  page11_i269
#ISCELL
  mstr_standard tap *
  page11_i270
#ISCELL
  mstr_standard tap *
  page11_i271
#ISCELL
  mstr_standard tap *
  page11_i272
#ISCELL
  mstr_standard tap *
  page11_i273
#ISCELL
  mstr_standard tap *
  page11_i274
#ISCELL
  mstr_standard tap *
  page11_i275
#ISCELL
  mstr_standard tap *
  page11_i276
#ISCELL
  mstr_standard tap *
  page11_i277
#ISCELL
  mstr_standard tap *
  page11_i278
#ISCELL
  mstr_standard tap *
  page11_i279
#ISCELL
  mstr_standard tap *
  page11_i280
#ISCELL
  mstr_standard tap *
  page11_i281
#ISCELL
  mstr_standard tap *
  page11_i282
#ISCELL
  mstr_standard tap *
  page11_i283
#ISCELL
  mstr_standard tap *
  page11_i284
#ISCELL
  mstr_standard tap *
  page11_i285
#ISCELL
  mstr_standard tap *
  page11_i286
#ISCELL
  mstr_standard tap *
  page11_i287
#ISCELL
  mstr_standard tap *
  page11_i288
#ISCELL
  mstr_standard tap *
  page11_i289
#ISCELL
  mstr_standard tap *
  page11_i290
#ISCELL
  standard offpage *
  page11_i291
#ISCELL
  standard offpage *
  page11_i292
#ISCELL
  standard offpage *
  page11_i293
#ISCELL
  standard offpage *
  page11_i294
#ISCELL
  mstr_standard tap *
  page11_i295
#ISCELL
  mstr_standard tap *
  page11_i296
#ISCELL
  mstr_standard tap *
  page11_i297
#ISCELL
  mstr_standard tap *
  page11_i298
#ISCELL
  mstr_standard tap *
  page11_i299
#ISCELL
  mstr_standard tap *
  page11_i300
#ISCELL
  mstr_standard tap *
  page11_i301
#ISCELL
  mstr_standard tap *
  page11_i302
#ISCELL
  mstr_standard tap *
  page11_i303
#ISCELL
  mstr_standard tap *
  page11_i304
#ISCELL
  mstr_standard tap *
  page11_i305
#ISCELL
  mstr_standard tap *
  page11_i306
#ISCELL
  mstr_standard tap *
  page11_i307
#ISCELL
  mstr_standard tap *
  page11_i308
#ISCELL
  mstr_standard tap *
  page11_i309
#ISCELL
  mstr_standard tap *
  page11_i310
#ISCELL
  mstr_standard tap *
  page11_i311
#ISCELL
  mstr_standard tap *
  page11_i312
#ISCELL
  mstr_standard tap *
  page11_i313
#ISCELL
  standard offpage *
  page11_i314
#ISCELL
  standard offpage *
  page11_i315
#ISCELL
  standard offpage *
  page11_i316
#ISCELL
  standard offpage *
  page11_i317
#ISCELL
  standard offpage *
  page11_i318
#ISCELL
  standard offpage *
  page11_i319
#ISCELL
  mstr_standard offpage *
  page11_i320
#ISCELL
  standard offpage *
  page11_i321
#ISCELL
  standard offpage *
  page11_i322
#ISCELL
  standard offpage *
  page11_i323
#ISCELL
  standard offpage *
  page11_i324
#ISCELL
  standard offpage *
  page11_i325
#ISCELL
  standard offpage *
  page11_i326
#CELL
  pure_quanta q_res *
  page11_i327
#ISCELL
  mstr_standard offpage *
  page11_i328
#ISCELL
  pure_quanta quanta_title_block_c *
  *
#ISCELL
  pure_quanta_power cad_note *
  *
#CELL
  pure_quanta genoa_sp5 *
  page12_i159
#ISCELL
  mstr_standard offpage *
  page12_i160
#ISCELL
  mstr_standard offpage *
  page12_i161
#ISCELL
  mstr_standard tap *
  page12_i162
#ISCELL
  mstr_standard tap *
  page12_i163
#ISCELL
  mstr_standard tap *
  page12_i164
#ISCELL
  mstr_standard tap *
  page12_i165
#ISCELL
  mstr_standard tap *
  page12_i166
#ISCELL
  mstr_standard tap *
  page12_i167
#ISCELL
  mstr_standard tap *
  page12_i168
#ISCELL
  mstr_standard tap *
  page12_i169
#ISCELL
  mstr_standard tap *
  page12_i170
#ISCELL
  mstr_standard tap *
  page12_i171
#ISCELL
  mstr_standard tap *
  page12_i172
#ISCELL
  mstr_standard tap *
  page12_i173
#ISCELL
  mstr_standard tap *
  page12_i174
#ISCELL
  mstr_standard tap *
  page12_i175
#ISCELL
  mstr_standard tap *
  page12_i176
#ISCELL
  mstr_standard tap *
  page12_i177
#ISCELL
  mstr_standard tap *
  page12_i178
#ISCELL
  mstr_standard tap *
  page12_i179
#ISCELL
  mstr_standard tap *
  page12_i180
#ISCELL
  mstr_standard tap *
  page12_i181
#ISCELL
  mstr_standard tap *
  page12_i182
#ISCELL
  mstr_standard tap *
  page12_i183
#ISCELL
  mstr_standard tap *
  page12_i184
#ISCELL
  mstr_standard tap *
  page12_i185
#ISCELL
  mstr_standard tap *
  page12_i186
#ISCELL
  mstr_standard tap *
  page12_i187
#ISCELL
  mstr_standard tap *
  page12_i188
#ISCELL
  mstr_standard tap *
  page12_i189
#ISCELL
  mstr_standard tap *
  page12_i190
#ISCELL
  mstr_standard tap *
  page12_i191
#ISCELL
  mstr_standard tap *
  page12_i192
#ISCELL
  mstr_standard tap *
  page12_i193
#ISCELL
  mstr_standard tap *
  page12_i194
#ISCELL
  mstr_standard tap *
  page12_i195
#ISCELL
  mstr_standard offpage *
  page12_i196
#ISCELL
  mstr_standard tap *
  page12_i197
#ISCELL
  mstr_standard tap *
  page12_i198
#ISCELL
  mstr_standard tap *
  page12_i199
#ISCELL
  mstr_standard tap *
  page12_i200
#ISCELL
  mstr_standard tap *
  page12_i201
#ISCELL
  mstr_standard tap *
  page12_i202
#ISCELL
  mstr_standard tap *
  page12_i203
#ISCELL
  mstr_standard tap *
  page12_i204
#ISCELL
  mstr_standard tap *
  page12_i205
#ISCELL
  mstr_standard tap *
  page12_i206
#ISCELL
  mstr_standard tap *
  page12_i207
#ISCELL
  mstr_standard tap *
  page12_i208
#ISCELL
  mstr_standard tap *
  page12_i209
#ISCELL
  mstr_standard tap *
  page12_i210
#ISCELL
  mstr_standard tap *
  page12_i211
#ISCELL
  mstr_standard tap *
  page12_i212
#ISCELL
  mstr_standard tap *
  page12_i213
#ISCELL
  mstr_standard tap *
  page12_i214
#ISCELL
  mstr_standard tap *
  page12_i215
#ISCELL
  mstr_standard tap *
  page12_i216
#ISCELL
  mstr_standard tap *
  page12_i217
#ISCELL
  mstr_standard tap *
  page12_i218
#ISCELL
  mstr_standard tap *
  page12_i219
#ISCELL
  mstr_standard tap *
  page12_i220
#ISCELL
  mstr_standard tap *
  page12_i221
#ISCELL
  mstr_standard tap *
  page12_i222
#ISCELL
  mstr_standard tap *
  page12_i223
#ISCELL
  mstr_standard tap *
  page12_i224
#ISCELL
  mstr_standard tap *
  page12_i225
#ISCELL
  mstr_standard tap *
  page12_i226
#ISCELL
  mstr_standard tap *
  page12_i227
#ISCELL
  mstr_standard tap *
  page12_i228
#ISCELL
  mstr_standard tap *
  page12_i229
#ISCELL
  mstr_standard tap *
  page12_i230
#ISCELL
  mstr_standard tap *
  page12_i231
#ISCELL
  mstr_standard tap *
  page12_i232
#ISCELL
  mstr_standard tap *
  page12_i233
#ISCELL
  mstr_standard offpage *
  page12_i234
#ISCELL
  mstr_standard tap *
  page12_i235
#ISCELL
  mstr_standard tap *
  page12_i236
#ISCELL
  mstr_standard tap *
  page12_i237
#ISCELL
  mstr_standard tap *
  page12_i238
#ISCELL
  mstr_standard tap *
  page12_i239
#ISCELL
  mstr_standard tap *
  page12_i240
#ISCELL
  mstr_standard tap *
  page12_i241
#ISCELL
  mstr_standard tap *
  page12_i242
#ISCELL
  mstr_standard tap *
  page12_i243
#ISCELL
  mstr_standard tap *
  page12_i244
#ISCELL
  mstr_standard tap *
  page12_i245
#ISCELL
  mstr_standard tap *
  page12_i246
#ISCELL
  mstr_standard tap *
  page12_i247
#ISCELL
  mstr_standard tap *
  page12_i248
#ISCELL
  mstr_standard tap *
  page12_i249
#ISCELL
  mstr_standard tap *
  page12_i250
#ISCELL
  mstr_standard tap *
  page12_i251
#ISCELL
  mstr_standard tap *
  page12_i252
#ISCELL
  mstr_standard tap *
  page12_i253
#ISCELL
  mstr_standard tap *
  page12_i254
#ISCELL
  mstr_standard tap *
  page12_i255
#ISCELL
  mstr_standard tap *
  page12_i256
#ISCELL
  mstr_standard tap *
  page12_i257
#ISCELL
  mstr_standard tap *
  page12_i258
#ISCELL
  mstr_standard tap *
  page12_i259
#ISCELL
  mstr_standard tap *
  page12_i260
#ISCELL
  mstr_standard tap *
  page12_i261
#ISCELL
  mstr_standard tap *
  page12_i262
#ISCELL
  mstr_standard tap *
  page12_i263
#ISCELL
  mstr_standard tap *
  page12_i264
#ISCELL
  mstr_standard tap *
  page12_i265
#ISCELL
  mstr_standard tap *
  page12_i266
#ISCELL
  mstr_standard tap *
  page12_i267
#ISCELL
  mstr_standard tap *
  page12_i268
#ISCELL
  mstr_standard tap *
  page12_i269
#ISCELL
  mstr_standard tap *
  page12_i270
#ISCELL
  mstr_standard tap *
  page12_i271
#ISCELL
  standard offpage *
  page12_i272
#ISCELL
  standard offpage *
  page12_i273
#ISCELL
  mstr_standard tap *
  page12_i274
#ISCELL
  mstr_standard tap *
  page12_i275
#ISCELL
  mstr_standard tap *
  page12_i276
#ISCELL
  mstr_standard tap *
  page12_i277
#ISCELL
  mstr_standard tap *
  page12_i278
#ISCELL
  mstr_standard tap *
  page12_i279
#ISCELL
  mstr_standard tap *
  page12_i280
#ISCELL
  mstr_standard tap *
  page12_i281
#ISCELL
  mstr_standard tap *
  page12_i282
#ISCELL
  standard offpage *
  page12_i283
#ISCELL
  standard offpage *
  page12_i284
#ISCELL
  mstr_standard tap *
  page12_i285
#ISCELL
  mstr_standard tap *
  page12_i286
#ISCELL
  mstr_standard tap *
  page12_i287
#ISCELL
  mstr_standard tap *
  page12_i288
#ISCELL
  mstr_standard tap *
  page12_i289
#ISCELL
  mstr_standard tap *
  page12_i290
#ISCELL
  mstr_standard tap *
  page12_i291
#ISCELL
  mstr_standard tap *
  page12_i292
#ISCELL
  mstr_standard tap *
  page12_i293
#ISCELL
  mstr_standard tap *
  page12_i294
#ISCELL
  mstr_standard tap *
  page12_i295
#ISCELL
  mstr_standard tap *
  page12_i296
#ISCELL
  mstr_standard tap *
  page12_i297
#ISCELL
  mstr_standard tap *
  page12_i298
#ISCELL
  mstr_standard tap *
  page12_i299
#ISCELL
  mstr_standard tap *
  page12_i300
#ISCELL
  mstr_standard tap *
  page12_i301
#ISCELL
  standard offpage *
  page12_i302
#ISCELL
  standard offpage *
  page12_i303
#ISCELL
  standard offpage *
  page12_i304
#ISCELL
  standard offpage *
  page12_i305
#ISCELL
  standard offpage *
  page12_i306
#ISCELL
  standard offpage *
  page12_i307
#ISCELL
  standard offpage *
  page12_i308
#ISCELL
  mstr_standard offpage *
  page12_i309
#ISCELL
  standard offpage *
  page12_i310
#ISCELL
  standard offpage *
  page12_i311
#ISCELL
  standard offpage *
  page12_i312
#ISCELL
  standard offpage *
  page12_i313
#CELL
  pure_quanta q_res *
  page12_i314
#ISCELL
  mstr_standard offpage *
  page12_i315
#ISCELL
  standard offpage *
  page12_i316
#ISCELL
  pure_quanta quanta_title_block_c *
  *
#ISCELL
  pure_quanta_power cad_note *
  *
#CELL
  pure_quanta genoa_sp5 *
  page13_i159
#ISCELL
  mstr_standard offpage *
  page13_i160
#ISCELL
  mstr_standard offpage *
  page13_i161
#ISCELL
  mstr_standard tap *
  page13_i162
#ISCELL
  mstr_standard tap *
  page13_i163
#ISCELL
  mstr_standard tap *
  page13_i164
#ISCELL
  mstr_standard tap *
  page13_i165
#ISCELL
  mstr_standard tap *
  page13_i166
#ISCELL
  mstr_standard tap *
  page13_i167
#ISCELL
  mstr_standard tap *
  page13_i168
#ISCELL
  mstr_standard tap *
  page13_i169
#ISCELL
  mstr_standard tap *
  page13_i170
#ISCELL
  mstr_standard tap *
  page13_i171
#ISCELL
  mstr_standard tap *
  page13_i172
#ISCELL
  mstr_standard tap *
  page13_i173
#ISCELL
  mstr_standard tap *
  page13_i174
#ISCELL
  mstr_standard tap *
  page13_i175
#ISCELL
  mstr_standard tap *
  page13_i176
#ISCELL
  mstr_standard tap *
  page13_i177
#ISCELL
  mstr_standard tap *
  page13_i178
#ISCELL
  mstr_standard tap *
  page13_i179
#ISCELL
  mstr_standard tap *
  page13_i180
#ISCELL
  mstr_standard tap *
  page13_i181
#ISCELL
  mstr_standard tap *
  page13_i182
#ISCELL
  mstr_standard tap *
  page13_i183
#ISCELL
  mstr_standard tap *
  page13_i184
#ISCELL
  mstr_standard tap *
  page13_i185
#ISCELL
  mstr_standard tap *
  page13_i186
#ISCELL
  mstr_standard tap *
  page13_i187
#ISCELL
  mstr_standard tap *
  page13_i188
#ISCELL
  mstr_standard tap *
  page13_i189
#ISCELL
  mstr_standard tap *
  page13_i190
#ISCELL
  mstr_standard tap *
  page13_i191
#ISCELL
  mstr_standard tap *
  page13_i192
#ISCELL
  mstr_standard tap *
  page13_i193
#ISCELL
  mstr_standard tap *
  page13_i194
#ISCELL
  mstr_standard tap *
  page13_i195
#ISCELL
  mstr_standard tap *
  page13_i196
#ISCELL
  mstr_standard offpage *
  page13_i197
#ISCELL
  mstr_standard tap *
  page13_i198
#ISCELL
  mstr_standard tap *
  page13_i199
#ISCELL
  mstr_standard tap *
  page13_i200
#ISCELL
  mstr_standard tap *
  page13_i201
#ISCELL
  mstr_standard tap *
  page13_i202
#ISCELL
  mstr_standard tap *
  page13_i203
#ISCELL
  mstr_standard tap *
  page13_i204
#ISCELL
  mstr_standard tap *
  page13_i205
#ISCELL
  mstr_standard tap *
  page13_i206
#ISCELL
  mstr_standard tap *
  page13_i207
#ISCELL
  mstr_standard tap *
  page13_i208
#ISCELL
  mstr_standard tap *
  page13_i209
#ISCELL
  mstr_standard tap *
  page13_i210
#ISCELL
  mstr_standard tap *
  page13_i211
#ISCELL
  mstr_standard tap *
  page13_i212
#ISCELL
  mstr_standard tap *
  page13_i213
#ISCELL
  mstr_standard tap *
  page13_i214
#ISCELL
  mstr_standard tap *
  page13_i215
#ISCELL
  mstr_standard tap *
  page13_i216
#ISCELL
  mstr_standard tap *
  page13_i217
#ISCELL
  mstr_standard tap *
  page13_i218
#ISCELL
  mstr_standard tap *
  page13_i219
#ISCELL
  mstr_standard tap *
  page13_i220
#ISCELL
  mstr_standard tap *
  page13_i221
#ISCELL
  mstr_standard tap *
  page13_i222
#ISCELL
  mstr_standard tap *
  page13_i223
#ISCELL
  mstr_standard tap *
  page13_i224
#ISCELL
  mstr_standard tap *
  page13_i225
#ISCELL
  mstr_standard tap *
  page13_i226
#ISCELL
  mstr_standard tap *
  page13_i227
#ISCELL
  mstr_standard tap *
  page13_i228
#ISCELL
  mstr_standard tap *
  page13_i229
#ISCELL
  mstr_standard tap *
  page13_i230
#ISCELL
  mstr_standard tap *
  page13_i231
#ISCELL
  mstr_standard tap *
  page13_i232
#ISCELL
  mstr_standard tap *
  page13_i233
#ISCELL
  mstr_standard tap *
  page13_i234
#ISCELL
  mstr_standard offpage *
  page13_i235
#ISCELL
  mstr_standard tap *
  page13_i236
#ISCELL
  mstr_standard tap *
  page13_i237
#ISCELL
  mstr_standard tap *
  page13_i238
#ISCELL
  mstr_standard tap *
  page13_i239
#ISCELL
  mstr_standard tap *
  page13_i240
#ISCELL
  mstr_standard tap *
  page13_i241
#ISCELL
  mstr_standard tap *
  page13_i242
#ISCELL
  mstr_standard tap *
  page13_i243
#ISCELL
  mstr_standard tap *
  page13_i244
#ISCELL
  mstr_standard tap *
  page13_i245
#ISCELL
  mstr_standard tap *
  page13_i246
#ISCELL
  mstr_standard tap *
  page13_i247
#ISCELL
  mstr_standard tap *
  page13_i248
#ISCELL
  mstr_standard tap *
  page13_i249
#ISCELL
  mstr_standard tap *
  page13_i250
#ISCELL
  mstr_standard tap *
  page13_i251
#ISCELL
  mstr_standard tap *
  page13_i252
#ISCELL
  mstr_standard tap *
  page13_i253
#ISCELL
  mstr_standard tap *
  page13_i254
#ISCELL
  mstr_standard tap *
  page13_i255
#ISCELL
  mstr_standard tap *
  page13_i256
#ISCELL
  mstr_standard tap *
  page13_i257
#ISCELL
  mstr_standard tap *
  page13_i258
#ISCELL
  mstr_standard tap *
  page13_i259
#ISCELL
  mstr_standard tap *
  page13_i260
#ISCELL
  mstr_standard tap *
  page13_i261
#ISCELL
  mstr_standard tap *
  page13_i262
#ISCELL
  mstr_standard tap *
  page13_i263
#ISCELL
  mstr_standard tap *
  page13_i264
#ISCELL
  mstr_standard tap *
  page13_i265
#ISCELL
  mstr_standard tap *
  page13_i266
#ISCELL
  mstr_standard tap *
  page13_i267
#ISCELL
  mstr_standard tap *
  page13_i268
#ISCELL
  mstr_standard tap *
  page13_i269
#ISCELL
  mstr_standard tap *
  page13_i270
#ISCELL
  mstr_standard tap *
  page13_i271
#ISCELL
  mstr_standard tap *
  page13_i272
#ISCELL
  mstr_standard tap *
  page13_i273
#ISCELL
  mstr_standard tap *
  page13_i274
#ISCELL
  mstr_standard tap *
  page13_i275
#ISCELL
  mstr_standard tap *
  page13_i276
#ISCELL
  mstr_standard tap *
  page13_i277
#ISCELL
  mstr_standard tap *
  page13_i278
#ISCELL
  mstr_standard tap *
  page13_i279
#ISCELL
  mstr_standard tap *
  page13_i280
#ISCELL
  mstr_standard tap *
  page13_i281
#ISCELL
  standard offpage *
  page13_i282
#ISCELL
  standard offpage *
  page13_i283
#ISCELL
  standard offpage *
  page13_i284
#ISCELL
  standard offpage *
  page13_i285
#ISCELL
  mstr_standard tap *
  page13_i286
#ISCELL
  mstr_standard tap *
  page13_i287
#ISCELL
  mstr_standard tap *
  page13_i288
#ISCELL
  mstr_standard tap *
  page13_i289
#ISCELL
  mstr_standard tap *
  page13_i290
#ISCELL
  mstr_standard tap *
  page13_i291
#ISCELL
  mstr_standard tap *
  page13_i292
#ISCELL
  mstr_standard tap *
  page13_i293
#ISCELL
  mstr_standard tap *
  page13_i294
#ISCELL
  mstr_standard tap *
  page13_i295
#ISCELL
  mstr_standard tap *
  page13_i296
#ISCELL
  mstr_standard tap *
  page13_i297
#ISCELL
  mstr_standard tap *
  page13_i298
#ISCELL
  mstr_standard tap *
  page13_i299
#ISCELL
  mstr_standard tap *
  page13_i300
#ISCELL
  mstr_standard tap *
  page13_i301
#ISCELL
  standard offpage *
  page13_i302
#ISCELL
  standard offpage *
  page13_i303
#ISCELL
  standard offpage *
  page13_i304
#ISCELL
  standard offpage *
  page13_i305
#ISCELL
  standard offpage *
  page13_i306
#ISCELL
  standard offpage *
  page13_i307
#ISCELL
  standard offpage *
  page13_i308
#ISCELL
  mstr_standard offpage *
  page13_i309
#ISCELL
  standard offpage *
  page13_i310
#ISCELL
  standard offpage *
  page13_i311
#ISCELL
  standard offpage *
  page13_i312
#ISCELL
  standard offpage *
  page13_i313
#CELL
  pure_quanta q_res *
  page13_i314
#ISCELL
  mstr_standard offpage *
  page13_i315
#ISCELL
  standard offpage *
  page13_i316
#ISCELL
  pure_quanta quanta_title_block_c *
  *
#ISCELL
  pure_quanta_power cad_note *
  *
#CELL
  pure_quanta genoa_sp5 *
  page14_i159
#ISCELL
  mstr_standard offpage *
  page14_i160
#ISCELL
  mstr_standard offpage *
  page14_i161
#ISCELL
  mstr_standard tap *
  page14_i162
#ISCELL
  mstr_standard tap *
  page14_i163
#ISCELL
  mstr_standard tap *
  page14_i164
#ISCELL
  mstr_standard tap *
  page14_i165
#ISCELL
  mstr_standard tap *
  page14_i166
#ISCELL
  mstr_standard tap *
  page14_i167
#ISCELL
  mstr_standard tap *
  page14_i168
#ISCELL
  mstr_standard tap *
  page14_i169
#ISCELL
  mstr_standard tap *
  page14_i170
#ISCELL
  mstr_standard tap *
  page14_i171
#ISCELL
  mstr_standard tap *
  page14_i172
#ISCELL
  mstr_standard tap *
  page14_i173
#ISCELL
  mstr_standard tap *
  page14_i174
#ISCELL
  mstr_standard tap *
  page14_i175
#ISCELL
  mstr_standard tap *
  page14_i176
#ISCELL
  mstr_standard tap *
  page14_i177
#ISCELL
  mstr_standard tap *
  page14_i178
#ISCELL
  mstr_standard tap *
  page14_i179
#ISCELL
  mstr_standard tap *
  page14_i180
#ISCELL
  mstr_standard tap *
  page14_i181
#ISCELL
  mstr_standard tap *
  page14_i182
#ISCELL
  mstr_standard tap *
  page14_i183
#ISCELL
  mstr_standard tap *
  page14_i184
#ISCELL
  mstr_standard tap *
  page14_i185
#ISCELL
  mstr_standard tap *
  page14_i186
#ISCELL
  mstr_standard tap *
  page14_i187
#ISCELL
  mstr_standard tap *
  page14_i188
#ISCELL
  mstr_standard tap *
  page14_i189
#ISCELL
  mstr_standard tap *
  page14_i190
#ISCELL
  mstr_standard tap *
  page14_i191
#ISCELL
  mstr_standard tap *
  page14_i192
#ISCELL
  mstr_standard tap *
  page14_i193
#ISCELL
  mstr_standard tap *
  page14_i194
#ISCELL
  mstr_standard tap *
  page14_i195
#ISCELL
  mstr_standard tap *
  page14_i196
#ISCELL
  mstr_standard tap *
  page14_i197
#ISCELL
  mstr_standard offpage *
  page14_i198
#ISCELL
  mstr_standard tap *
  page14_i199
#ISCELL
  mstr_standard tap *
  page14_i200
#ISCELL
  mstr_standard tap *
  page14_i201
#ISCELL
  mstr_standard tap *
  page14_i202
#ISCELL
  mstr_standard tap *
  page14_i203
#ISCELL
  mstr_standard tap *
  page14_i204
#ISCELL
  mstr_standard tap *
  page14_i205
#ISCELL
  mstr_standard tap *
  page14_i206
#ISCELL
  mstr_standard tap *
  page14_i207
#ISCELL
  mstr_standard tap *
  page14_i208
#ISCELL
  mstr_standard tap *
  page14_i209
#ISCELL
  mstr_standard tap *
  page14_i210
#ISCELL
  mstr_standard tap *
  page14_i211
#ISCELL
  mstr_standard tap *
  page14_i212
#ISCELL
  mstr_standard tap *
  page14_i213
#ISCELL
  mstr_standard tap *
  page14_i214
#ISCELL
  mstr_standard tap *
  page14_i215
#ISCELL
  mstr_standard tap *
  page14_i216
#ISCELL
  mstr_standard tap *
  page14_i217
#ISCELL
  mstr_standard tap *
  page14_i218
#ISCELL
  mstr_standard tap *
  page14_i219
#ISCELL
  mstr_standard tap *
  page14_i220
#ISCELL
  mstr_standard tap *
  page14_i221
#ISCELL
  mstr_standard tap *
  page14_i222
#ISCELL
  mstr_standard tap *
  page14_i223
#ISCELL
  mstr_standard tap *
  page14_i224
#ISCELL
  mstr_standard tap *
  page14_i225
#ISCELL
  mstr_standard tap *
  page14_i226
#ISCELL
  mstr_standard tap *
  page14_i227
#ISCELL
  mstr_standard tap *
  page14_i228
#ISCELL
  mstr_standard tap *
  page14_i229
#ISCELL
  mstr_standard tap *
  page14_i230
#ISCELL
  mstr_standard tap *
  page14_i231
#ISCELL
  mstr_standard tap *
  page14_i232
#ISCELL
  mstr_standard tap *
  page14_i233
#ISCELL
  mstr_standard tap *
  page14_i234
#ISCELL
  mstr_standard offpage *
  page14_i235
#ISCELL
  mstr_standard tap *
  page14_i236
#ISCELL
  mstr_standard tap *
  page14_i237
#ISCELL
  mstr_standard tap *
  page14_i238
#ISCELL
  mstr_standard tap *
  page14_i239
#ISCELL
  mstr_standard tap *
  page14_i240
#ISCELL
  mstr_standard tap *
  page14_i241
#ISCELL
  mstr_standard tap *
  page14_i242
#ISCELL
  mstr_standard tap *
  page14_i243
#ISCELL
  mstr_standard tap *
  page14_i244
#ISCELL
  mstr_standard tap *
  page14_i245
#ISCELL
  mstr_standard tap *
  page14_i246
#ISCELL
  mstr_standard tap *
  page14_i247
#ISCELL
  mstr_standard tap *
  page14_i248
#ISCELL
  mstr_standard tap *
  page14_i249
#ISCELL
  mstr_standard tap *
  page14_i250
#ISCELL
  mstr_standard tap *
  page14_i251
#ISCELL
  mstr_standard tap *
  page14_i252
#ISCELL
  mstr_standard tap *
  page14_i253
#ISCELL
  mstr_standard tap *
  page14_i254
#ISCELL
  mstr_standard tap *
  page14_i255
#ISCELL
  mstr_standard tap *
  page14_i256
#ISCELL
  mstr_standard tap *
  page14_i257
#ISCELL
  mstr_standard tap *
  page14_i258
#ISCELL
  mstr_standard tap *
  page14_i259
#ISCELL
  mstr_standard tap *
  page14_i260
#ISCELL
  mstr_standard tap *
  page14_i261
#ISCELL
  mstr_standard tap *
  page14_i262
#ISCELL
  mstr_standard tap *
  page14_i263
#ISCELL
  mstr_standard tap *
  page14_i264
#ISCELL
  mstr_standard tap *
  page14_i265
#ISCELL
  mstr_standard tap *
  page14_i266
#ISCELL
  mstr_standard tap *
  page14_i267
#ISCELL
  mstr_standard tap *
  page14_i268
#ISCELL
  mstr_standard tap *
  page14_i269
#ISCELL
  mstr_standard tap *
  page14_i270
#ISCELL
  mstr_standard tap *
  page14_i271
#ISCELL
  mstr_standard tap *
  page14_i272
#ISCELL
  mstr_standard tap *
  page14_i273
#ISCELL
  mstr_standard tap *
  page14_i274
#ISCELL
  mstr_standard tap *
  page14_i275
#ISCELL
  mstr_standard tap *
  page14_i276
#ISCELL
  mstr_standard tap *
  page14_i277
#ISCELL
  mstr_standard tap *
  page14_i278
#ISCELL
  mstr_standard tap *
  page14_i279
#ISCELL
  mstr_standard tap *
  page14_i280
#ISCELL
  mstr_standard tap *
  page14_i281
#ISCELL
  mstr_standard tap *
  page14_i282
#ISCELL
  standard offpage *
  page14_i283
#ISCELL
  standard offpage *
  page14_i284
#ISCELL
  standard offpage *
  page14_i285
#ISCELL
  standard offpage *
  page14_i286
#ISCELL
  mstr_standard tap *
  page14_i287
#ISCELL
  mstr_standard tap *
  page14_i288
#ISCELL
  mstr_standard tap *
  page14_i289
#ISCELL
  mstr_standard tap *
  page14_i290
#ISCELL
  mstr_standard tap *
  page14_i291
#ISCELL
  mstr_standard tap *
  page14_i292
#ISCELL
  mstr_standard tap *
  page14_i293
#ISCELL
  mstr_standard tap *
  page14_i294
#ISCELL
  mstr_standard tap *
  page14_i295
#ISCELL
  mstr_standard tap *
  page14_i296
#ISCELL
  mstr_standard tap *
  page14_i297
#ISCELL
  mstr_standard tap *
  page14_i298
#ISCELL
  mstr_standard tap *
  page14_i299
#ISCELL
  mstr_standard tap *
  page14_i300
#ISCELL
  mstr_standard tap *
  page14_i301
#ISCELL
  standard offpage *
  page14_i302
#ISCELL
  standard offpage *
  page14_i303
#ISCELL
  standard offpage *
  page14_i304
#ISCELL
  standard offpage *
  page14_i305
#ISCELL
  standard offpage *
  page14_i306
#ISCELL
  standard offpage *
  page14_i307
#ISCELL
  standard offpage *
  page14_i308
#ISCELL
  standard offpage *
  page14_i309
#ISCELL
  standard offpage *
  page14_i310
#ISCELL
  standard offpage *
  page14_i311
#ISCELL
  mstr_standard offpage *
  page14_i312
#ISCELL
  standard offpage *
  page14_i313
#ISCELL
  standard offpage *
  page14_i314
#CELL
  pure_quanta q_res *
  page14_i315
#ISCELL
  mstr_standard offpage *
  page14_i316
#ISCELL
  pure_quanta quanta_title_block_c *
  *
#ISCELL
  pure_quanta_power cad_note *
  *
#CELL
  pure_quanta genoa_sp5 *
  page15_i159
#ISCELL
  mstr_standard offpage *
  page15_i160
#ISCELL
  mstr_standard offpage *
  page15_i161
#ISCELL
  mstr_standard tap *
  page15_i162
#ISCELL
  mstr_standard tap *
  page15_i163
#ISCELL
  mstr_standard tap *
  page15_i164
#ISCELL
  mstr_standard tap *
  page15_i165
#ISCELL
  mstr_standard tap *
  page15_i166
#ISCELL
  mstr_standard tap *
  page15_i167
#ISCELL
  mstr_standard tap *
  page15_i168
#ISCELL
  mstr_standard tap *
  page15_i169
#ISCELL
  mstr_standard tap *
  page15_i170
#ISCELL
  mstr_standard tap *
  page15_i171
#ISCELL
  mstr_standard tap *
  page15_i172
#ISCELL
  mstr_standard tap *
  page15_i173
#ISCELL
  mstr_standard tap *
  page15_i174
#ISCELL
  mstr_standard tap *
  page15_i175
#ISCELL
  mstr_standard tap *
  page15_i176
#ISCELL
  mstr_standard tap *
  page15_i177
#ISCELL
  mstr_standard tap *
  page15_i178
#ISCELL
  mstr_standard tap *
  page15_i179
#ISCELL
  mstr_standard tap *
  page15_i180
#ISCELL
  mstr_standard tap *
  page15_i181
#ISCELL
  mstr_standard tap *
  page15_i182
#ISCELL
  mstr_standard tap *
  page15_i183
#ISCELL
  mstr_standard tap *
  page15_i184
#ISCELL
  mstr_standard tap *
  page15_i185
#ISCELL
  mstr_standard tap *
  page15_i186
#ISCELL
  mstr_standard tap *
  page15_i187
#ISCELL
  mstr_standard tap *
  page15_i188
#ISCELL
  mstr_standard tap *
  page15_i189
#ISCELL
  mstr_standard tap *
  page15_i190
#ISCELL
  mstr_standard tap *
  page15_i191
#ISCELL
  mstr_standard tap *
  page15_i192
#ISCELL
  mstr_standard tap *
  page15_i193
#ISCELL
  mstr_standard tap *
  page15_i194
#ISCELL
  mstr_standard tap *
  page15_i195
#ISCELL
  mstr_standard offpage *
  page15_i196
#ISCELL
  mstr_standard tap *
  page15_i197
#ISCELL
  mstr_standard tap *
  page15_i198
#ISCELL
  mstr_standard tap *
  page15_i199
#ISCELL
  mstr_standard tap *
  page15_i200
#ISCELL
  mstr_standard tap *
  page15_i201
#ISCELL
  mstr_standard tap *
  page15_i202
#ISCELL
  mstr_standard tap *
  page15_i203
#ISCELL
  mstr_standard tap *
  page15_i204
#ISCELL
  mstr_standard tap *
  page15_i205
#ISCELL
  mstr_standard tap *
  page15_i206
#ISCELL
  mstr_standard tap *
  page15_i207
#ISCELL
  mstr_standard tap *
  page15_i208
#ISCELL
  mstr_standard tap *
  page15_i209
#ISCELL
  mstr_standard tap *
  page15_i210
#ISCELL
  mstr_standard tap *
  page15_i211
#ISCELL
  mstr_standard tap *
  page15_i212
#ISCELL
  mstr_standard tap *
  page15_i213
#ISCELL
  mstr_standard tap *
  page15_i214
#ISCELL
  mstr_standard tap *
  page15_i215
#ISCELL
  mstr_standard tap *
  page15_i216
#ISCELL
  mstr_standard tap *
  page15_i217
#ISCELL
  mstr_standard tap *
  page15_i218
#ISCELL
  mstr_standard tap *
  page15_i219
#ISCELL
  mstr_standard tap *
  page15_i220
#ISCELL
  mstr_standard tap *
  page15_i221
#ISCELL
  mstr_standard tap *
  page15_i222
#ISCELL
  mstr_standard tap *
  page15_i223
#ISCELL
  mstr_standard tap *
  page15_i224
#ISCELL
  mstr_standard tap *
  page15_i225
#ISCELL
  mstr_standard tap *
  page15_i226
#ISCELL
  mstr_standard tap *
  page15_i227
#ISCELL
  mstr_standard tap *
  page15_i228
#ISCELL
  mstr_standard tap *
  page15_i229
#ISCELL
  mstr_standard tap *
  page15_i230
#ISCELL
  mstr_standard tap *
  page15_i231
#ISCELL
  mstr_standard tap *
  page15_i232
#ISCELL
  mstr_standard tap *
  page15_i233
#ISCELL
  mstr_standard offpage *
  page15_i234
#ISCELL
  mstr_standard tap *
  page15_i235
#ISCELL
  mstr_standard tap *
  page15_i236
#ISCELL
  mstr_standard tap *
  page15_i237
#ISCELL
  mstr_standard tap *
  page15_i238
#ISCELL
  mstr_standard tap *
  page15_i239
#ISCELL
  mstr_standard tap *
  page15_i240
#ISCELL
  mstr_standard tap *
  page15_i241
#ISCELL
  mstr_standard tap *
  page15_i242
#ISCELL
  mstr_standard tap *
  page15_i243
#ISCELL
  mstr_standard tap *
  page15_i244
#ISCELL
  mstr_standard tap *
  page15_i245
#ISCELL
  mstr_standard tap *
  page15_i246
#ISCELL
  mstr_standard tap *
  page15_i247
#ISCELL
  mstr_standard tap *
  page15_i248
#ISCELL
  mstr_standard tap *
  page15_i249
#ISCELL
  mstr_standard tap *
  page15_i250
#ISCELL
  mstr_standard tap *
  page15_i251
#ISCELL
  mstr_standard tap *
  page15_i252
#ISCELL
  mstr_standard tap *
  page15_i253
#ISCELL
  mstr_standard tap *
  page15_i254
#ISCELL
  mstr_standard tap *
  page15_i255
#ISCELL
  mstr_standard tap *
  page15_i256
#ISCELL
  mstr_standard tap *
  page15_i257
#ISCELL
  mstr_standard tap *
  page15_i258
#ISCELL
  mstr_standard tap *
  page15_i259
#ISCELL
  mstr_standard tap *
  page15_i260
#ISCELL
  mstr_standard tap *
  page15_i261
#ISCELL
  mstr_standard tap *
  page15_i262
#ISCELL
  mstr_standard tap *
  page15_i263
#ISCELL
  mstr_standard tap *
  page15_i264
#ISCELL
  mstr_standard tap *
  page15_i265
#ISCELL
  mstr_standard tap *
  page15_i266
#ISCELL
  mstr_standard tap *
  page15_i267
#ISCELL
  mstr_standard tap *
  page15_i268
#ISCELL
  mstr_standard tap *
  page15_i269
#ISCELL
  mstr_standard tap *
  page15_i270
#ISCELL
  mstr_standard tap *
  page15_i271
#ISCELL
  mstr_standard tap *
  page15_i272
#ISCELL
  mstr_standard tap *
  page15_i273
#ISCELL
  mstr_standard tap *
  page15_i274
#ISCELL
  mstr_standard tap *
  page15_i275
#ISCELL
  mstr_standard tap *
  page15_i276
#ISCELL
  mstr_standard tap *
  page15_i277
#ISCELL
  mstr_standard tap *
  page15_i278
#ISCELL
  mstr_standard tap *
  page15_i279
#ISCELL
  mstr_standard tap *
  page15_i280
#ISCELL
  standard offpage *
  page15_i281
#ISCELL
  standard offpage *
  page15_i282
#ISCELL
  standard offpage *
  page15_i283
#ISCELL
  standard offpage *
  page15_i284
#ISCELL
  mstr_standard tap *
  page15_i285
#ISCELL
  mstr_standard tap *
  page15_i286
#ISCELL
  mstr_standard tap *
  page15_i287
#ISCELL
  mstr_standard tap *
  page15_i288
#ISCELL
  mstr_standard tap *
  page15_i289
#ISCELL
  mstr_standard tap *
  page15_i290
#ISCELL
  mstr_standard tap *
  page15_i291
#ISCELL
  mstr_standard tap *
  page15_i292
#ISCELL
  mstr_standard tap *
  page15_i293
#ISCELL
  mstr_standard tap *
  page15_i294
#ISCELL
  mstr_standard tap *
  page15_i295
#ISCELL
  mstr_standard tap *
  page15_i296
#ISCELL
  mstr_standard tap *
  page15_i297
#ISCELL
  mstr_standard tap *
  page15_i298
#ISCELL
  mstr_standard tap *
  page15_i299
#ISCELL
  mstr_standard tap *
  page15_i300
#ISCELL
  mstr_standard tap *
  page15_i301
#ISCELL
  standard offpage *
  page15_i302
#ISCELL
  standard offpage *
  page15_i303
#ISCELL
  standard offpage *
  page15_i304
#ISCELL
  standard offpage *
  page15_i305
#ISCELL
  standard offpage *
  page15_i306
#ISCELL
  standard offpage *
  page15_i307
#ISCELL
  standard offpage *
  page15_i308
#ISCELL
  standard offpage *
  page15_i309
#ISCELL
  mstr_standard offpage *
  page15_i310
#ISCELL
  standard offpage *
  page15_i311
#ISCELL
  standard offpage *
  page15_i312
#ISCELL
  standard offpage *
  page15_i313
#CELL
  pure_quanta q_res *
  page15_i314
#ISCELL
  mstr_standard offpage *
  page15_i315
#ISCELL
  standard offpage *
  page15_i316
#ISCELL
  pure_quanta quanta_title_block_c *
  *
#ISCELL
  pure_quanta_power cad_note *
  *
#CELL
  pure_quanta genoa_sp5 *
  page16_i167
#ISCELL
  mstr_standard offpage *
  page16_i168
#ISCELL
  mstr_standard offpage *
  page16_i169
#ISCELL
  mstr_standard tap *
  page16_i170
#ISCELL
  mstr_standard tap *
  page16_i171
#ISCELL
  mstr_standard tap *
  page16_i172
#ISCELL
  mstr_standard tap *
  page16_i173
#ISCELL
  mstr_standard tap *
  page16_i174
#ISCELL
  mstr_standard tap *
  page16_i175
#ISCELL
  mstr_standard tap *
  page16_i176
#ISCELL
  mstr_standard tap *
  page16_i177
#ISCELL
  mstr_standard tap *
  page16_i178
#ISCELL
  mstr_standard tap *
  page16_i179
#ISCELL
  mstr_standard tap *
  page16_i180
#ISCELL
  mstr_standard tap *
  page16_i181
#ISCELL
  mstr_standard tap *
  page16_i182
#ISCELL
  mstr_standard tap *
  page16_i183
#ISCELL
  mstr_standard tap *
  page16_i184
#ISCELL
  mstr_standard tap *
  page16_i185
#ISCELL
  mstr_standard tap *
  page16_i186
#ISCELL
  mstr_standard tap *
  page16_i187
#ISCELL
  mstr_standard tap *
  page16_i188
#ISCELL
  mstr_standard tap *
  page16_i189
#ISCELL
  mstr_standard tap *
  page16_i190
#ISCELL
  mstr_standard tap *
  page16_i191
#ISCELL
  mstr_standard tap *
  page16_i192
#ISCELL
  mstr_standard tap *
  page16_i193
#ISCELL
  mstr_standard tap *
  page16_i194
#ISCELL
  mstr_standard tap *
  page16_i195
#ISCELL
  mstr_standard tap *
  page16_i196
#ISCELL
  mstr_standard tap *
  page16_i197
#ISCELL
  mstr_standard tap *
  page16_i198
#ISCELL
  mstr_standard tap *
  page16_i199
#ISCELL
  mstr_standard tap *
  page16_i200
#ISCELL
  mstr_standard tap *
  page16_i201
#ISCELL
  mstr_standard tap *
  page16_i202
#ISCELL
  mstr_standard tap *
  page16_i203
#ISCELL
  mstr_standard tap *
  page16_i204
#ISCELL
  mstr_standard tap *
  page16_i205
#ISCELL
  mstr_standard offpage *
  page16_i206
#ISCELL
  mstr_standard tap *
  page16_i207
#ISCELL
  mstr_standard tap *
  page16_i208
#ISCELL
  mstr_standard tap *
  page16_i209
#ISCELL
  mstr_standard tap *
  page16_i210
#ISCELL
  mstr_standard tap *
  page16_i211
#ISCELL
  mstr_standard tap *
  page16_i212
#ISCELL
  mstr_standard tap *
  page16_i213
#ISCELL
  mstr_standard tap *
  page16_i214
#ISCELL
  mstr_standard tap *
  page16_i215
#ISCELL
  mstr_standard tap *
  page16_i216
#ISCELL
  mstr_standard tap *
  page16_i217
#ISCELL
  mstr_standard tap *
  page16_i218
#ISCELL
  mstr_standard tap *
  page16_i219
#ISCELL
  mstr_standard tap *
  page16_i220
#ISCELL
  mstr_standard tap *
  page16_i221
#ISCELL
  mstr_standard tap *
  page16_i222
#ISCELL
  mstr_standard tap *
  page16_i223
#ISCELL
  mstr_standard tap *
  page16_i224
#ISCELL
  mstr_standard tap *
  page16_i225
#ISCELL
  mstr_standard tap *
  page16_i226
#ISCELL
  mstr_standard tap *
  page16_i227
#ISCELL
  mstr_standard tap *
  page16_i228
#ISCELL
  mstr_standard tap *
  page16_i229
#ISCELL
  mstr_standard tap *
  page16_i230
#ISCELL
  mstr_standard tap *
  page16_i231
#ISCELL
  mstr_standard tap *
  page16_i232
#ISCELL
  mstr_standard tap *
  page16_i233
#ISCELL
  mstr_standard tap *
  page16_i234
#ISCELL
  mstr_standard tap *
  page16_i235
#ISCELL
  mstr_standard tap *
  page16_i236
#ISCELL
  mstr_standard tap *
  page16_i237
#ISCELL
  mstr_standard tap *
  page16_i238
#ISCELL
  mstr_standard tap *
  page16_i239
#ISCELL
  mstr_standard tap *
  page16_i240
#ISCELL
  mstr_standard tap *
  page16_i241
#ISCELL
  mstr_standard tap *
  page16_i242
#ISCELL
  mstr_standard offpage *
  page16_i243
#ISCELL
  mstr_standard tap *
  page16_i244
#ISCELL
  mstr_standard tap *
  page16_i245
#ISCELL
  mstr_standard tap *
  page16_i246
#ISCELL
  mstr_standard tap *
  page16_i247
#ISCELL
  mstr_standard tap *
  page16_i248
#ISCELL
  mstr_standard tap *
  page16_i249
#ISCELL
  mstr_standard tap *
  page16_i250
#ISCELL
  mstr_standard tap *
  page16_i251
#ISCELL
  mstr_standard tap *
  page16_i252
#ISCELL
  mstr_standard tap *
  page16_i253
#ISCELL
  mstr_standard tap *
  page16_i254
#ISCELL
  mstr_standard tap *
  page16_i255
#ISCELL
  mstr_standard tap *
  page16_i256
#ISCELL
  mstr_standard tap *
  page16_i257
#ISCELL
  mstr_standard tap *
  page16_i258
#ISCELL
  mstr_standard tap *
  page16_i259
#ISCELL
  mstr_standard tap *
  page16_i260
#ISCELL
  mstr_standard tap *
  page16_i261
#ISCELL
  mstr_standard tap *
  page16_i262
#ISCELL
  mstr_standard tap *
  page16_i263
#ISCELL
  mstr_standard tap *
  page16_i264
#ISCELL
  mstr_standard tap *
  page16_i265
#ISCELL
  mstr_standard tap *
  page16_i266
#ISCELL
  mstr_standard tap *
  page16_i267
#ISCELL
  mstr_standard tap *
  page16_i268
#ISCELL
  mstr_standard tap *
  page16_i269
#ISCELL
  mstr_standard tap *
  page16_i270
#ISCELL
  mstr_standard tap *
  page16_i271
#ISCELL
  mstr_standard tap *
  page16_i272
#ISCELL
  mstr_standard tap *
  page16_i273
#ISCELL
  mstr_standard tap *
  page16_i274
#ISCELL
  mstr_standard tap *
  page16_i275
#ISCELL
  mstr_standard tap *
  page16_i276
#ISCELL
  mstr_standard tap *
  page16_i277
#ISCELL
  mstr_standard tap *
  page16_i278
#ISCELL
  mstr_standard tap *
  page16_i279
#ISCELL
  mstr_standard tap *
  page16_i280
#ISCELL
  mstr_standard tap *
  page16_i281
#ISCELL
  mstr_standard tap *
  page16_i282
#ISCELL
  mstr_standard tap *
  page16_i283
#ISCELL
  mstr_standard tap *
  page16_i284
#ISCELL
  mstr_standard tap *
  page16_i285
#ISCELL
  mstr_standard tap *
  page16_i286
#ISCELL
  mstr_standard tap *
  page16_i287
#ISCELL
  mstr_standard tap *
  page16_i288
#ISCELL
  mstr_standard tap *
  page16_i289
#ISCELL
  mstr_standard tap *
  page16_i290
#ISCELL
  standard offpage *
  page16_i291
#ISCELL
  standard offpage *
  page16_i292
#ISCELL
  standard offpage *
  page16_i293
#ISCELL
  standard offpage *
  page16_i294
#ISCELL
  mstr_standard tap *
  page16_i295
#ISCELL
  mstr_standard tap *
  page16_i296
#ISCELL
  mstr_standard tap *
  page16_i297
#ISCELL
  mstr_standard tap *
  page16_i298
#ISCELL
  mstr_standard tap *
  page16_i299
#ISCELL
  mstr_standard tap *
  page16_i300
#ISCELL
  mstr_standard tap *
  page16_i301
#ISCELL
  mstr_standard tap *
  page16_i302
#ISCELL
  mstr_standard tap *
  page16_i303
#ISCELL
  mstr_standard tap *
  page16_i304
#ISCELL
  mstr_standard tap *
  page16_i305
#ISCELL
  mstr_standard tap *
  page16_i306
#ISCELL
  mstr_standard tap *
  page16_i307
#ISCELL
  mstr_standard tap *
  page16_i308
#ISCELL
  mstr_standard tap *
  page16_i309
#ISCELL
  standard offpage *
  page16_i310
#ISCELL
  standard offpage *
  page16_i311
#ISCELL
  standard offpage *
  page16_i312
#ISCELL
  standard offpage *
  page16_i313
#ISCELL
  standard offpage *
  page16_i314
#ISCELL
  standard offpage *
  page16_i315
#ISCELL
  mstr_standard offpage *
  page16_i316
#ISCELL
  standard offpage *
  page16_i317
#ISCELL
  standard offpage *
  page16_i318
#ISCELL
  standard offpage *
  page16_i319
#ISCELL
  standard offpage *
  page16_i320
#ISCELL
  standard offpage *
  page16_i321
#ISCELL
  standard offpage *
  page16_i322
#CELL
  pure_quanta q_res *
  page16_i323
#ISCELL
  mstr_standard offpage *
  page16_i324
#ISCELL
  pure_quanta quanta_title_block_c *
  *
#ISCELL
  pure_quanta_power cad_note *
  *
#CELL
  pure_quanta genoa_sp5 *
  page17_i159
#ISCELL
  mstr_standard offpage *
  page17_i160
#ISCELL
  mstr_standard offpage *
  page17_i161
#ISCELL
  mstr_standard tap *
  page17_i162
#ISCELL
  mstr_standard tap *
  page17_i163
#ISCELL
  mstr_standard tap *
  page17_i164
#ISCELL
  mstr_standard tap *
  page17_i165
#ISCELL
  mstr_standard tap *
  page17_i166
#ISCELL
  mstr_standard tap *
  page17_i167
#ISCELL
  mstr_standard tap *
  page17_i168
#ISCELL
  mstr_standard tap *
  page17_i169
#ISCELL
  mstr_standard tap *
  page17_i170
#ISCELL
  mstr_standard tap *
  page17_i171
#ISCELL
  mstr_standard tap *
  page17_i172
#ISCELL
  mstr_standard tap *
  page17_i173
#ISCELL
  mstr_standard tap *
  page17_i174
#ISCELL
  mstr_standard tap *
  page17_i175
#ISCELL
  mstr_standard tap *
  page17_i176
#ISCELL
  mstr_standard tap *
  page17_i177
#ISCELL
  mstr_standard tap *
  page17_i178
#ISCELL
  mstr_standard tap *
  page17_i179
#ISCELL
  mstr_standard tap *
  page17_i180
#ISCELL
  mstr_standard tap *
  page17_i181
#ISCELL
  mstr_standard tap *
  page17_i182
#ISCELL
  mstr_standard tap *
  page17_i183
#ISCELL
  mstr_standard tap *
  page17_i184
#ISCELL
  mstr_standard tap *
  page17_i185
#ISCELL
  mstr_standard tap *
  page17_i186
#ISCELL
  mstr_standard tap *
  page17_i187
#ISCELL
  mstr_standard tap *
  page17_i188
#ISCELL
  mstr_standard tap *
  page17_i189
#ISCELL
  mstr_standard tap *
  page17_i190
#ISCELL
  mstr_standard tap *
  page17_i191
#ISCELL
  mstr_standard tap *
  page17_i192
#ISCELL
  mstr_standard tap *
  page17_i193
#ISCELL
  mstr_standard tap *
  page17_i194
#ISCELL
  mstr_standard tap *
  page17_i195
#ISCELL
  mstr_standard offpage *
  page17_i196
#ISCELL
  mstr_standard tap *
  page17_i197
#ISCELL
  mstr_standard tap *
  page17_i198
#ISCELL
  mstr_standard tap *
  page17_i199
#ISCELL
  mstr_standard tap *
  page17_i200
#ISCELL
  mstr_standard tap *
  page17_i201
#ISCELL
  mstr_standard tap *
  page17_i202
#ISCELL
  mstr_standard tap *
  page17_i203
#ISCELL
  mstr_standard tap *
  page17_i204
#ISCELL
  mstr_standard tap *
  page17_i205
#ISCELL
  mstr_standard tap *
  page17_i206
#ISCELL
  mstr_standard tap *
  page17_i207
#ISCELL
  mstr_standard tap *
  page17_i208
#ISCELL
  mstr_standard tap *
  page17_i209
#ISCELL
  mstr_standard tap *
  page17_i210
#ISCELL
  mstr_standard tap *
  page17_i211
#ISCELL
  mstr_standard tap *
  page17_i212
#ISCELL
  mstr_standard tap *
  page17_i213
#ISCELL
  mstr_standard tap *
  page17_i214
#ISCELL
  mstr_standard tap *
  page17_i215
#ISCELL
  mstr_standard tap *
  page17_i216
#ISCELL
  mstr_standard tap *
  page17_i217
#ISCELL
  mstr_standard tap *
  page17_i218
#ISCELL
  mstr_standard tap *
  page17_i219
#ISCELL
  mstr_standard tap *
  page17_i220
#ISCELL
  mstr_standard tap *
  page17_i221
#ISCELL
  mstr_standard tap *
  page17_i222
#ISCELL
  mstr_standard tap *
  page17_i223
#ISCELL
  mstr_standard tap *
  page17_i224
#ISCELL
  mstr_standard tap *
  page17_i225
#ISCELL
  mstr_standard tap *
  page17_i226
#ISCELL
  mstr_standard tap *
  page17_i227
#ISCELL
  mstr_standard tap *
  page17_i228
#ISCELL
  mstr_standard tap *
  page17_i229
#ISCELL
  mstr_standard tap *
  page17_i230
#ISCELL
  mstr_standard tap *
  page17_i231
#ISCELL
  mstr_standard tap *
  page17_i232
#ISCELL
  mstr_standard tap *
  page17_i233
#ISCELL
  mstr_standard offpage *
  page17_i234
#ISCELL
  mstr_standard tap *
  page17_i235
#ISCELL
  mstr_standard tap *
  page17_i236
#ISCELL
  mstr_standard tap *
  page17_i237
#ISCELL
  mstr_standard tap *
  page17_i238
#ISCELL
  mstr_standard tap *
  page17_i239
#ISCELL
  mstr_standard tap *
  page17_i240
#ISCELL
  mstr_standard tap *
  page17_i241
#ISCELL
  mstr_standard tap *
  page17_i242
#ISCELL
  mstr_standard tap *
  page17_i243
#ISCELL
  mstr_standard tap *
  page17_i244
#ISCELL
  mstr_standard tap *
  page17_i245
#ISCELL
  mstr_standard tap *
  page17_i246
#ISCELL
  mstr_standard tap *
  page17_i247
#ISCELL
  mstr_standard tap *
  page17_i248
#ISCELL
  mstr_standard tap *
  page17_i249
#ISCELL
  mstr_standard tap *
  page17_i250
#ISCELL
  mstr_standard tap *
  page17_i251
#ISCELL
  mstr_standard tap *
  page17_i252
#ISCELL
  mstr_standard tap *
  page17_i253
#ISCELL
  mstr_standard tap *
  page17_i254
#ISCELL
  mstr_standard tap *
  page17_i255
#ISCELL
  mstr_standard tap *
  page17_i256
#ISCELL
  mstr_standard tap *
  page17_i257
#ISCELL
  mstr_standard tap *
  page17_i258
#ISCELL
  mstr_standard tap *
  page17_i259
#ISCELL
  mstr_standard tap *
  page17_i260
#ISCELL
  mstr_standard tap *
  page17_i261
#ISCELL
  mstr_standard tap *
  page17_i262
#ISCELL
  mstr_standard tap *
  page17_i263
#ISCELL
  mstr_standard tap *
  page17_i264
#ISCELL
  mstr_standard tap *
  page17_i265
#ISCELL
  mstr_standard tap *
  page17_i266
#ISCELL
  mstr_standard tap *
  page17_i267
#ISCELL
  mstr_standard tap *
  page17_i268
#ISCELL
  mstr_standard tap *
  page17_i269
#ISCELL
  mstr_standard tap *
  page17_i270
#ISCELL
  mstr_standard tap *
  page17_i271
#ISCELL
  mstr_standard tap *
  page17_i272
#ISCELL
  mstr_standard tap *
  page17_i273
#ISCELL
  mstr_standard tap *
  page17_i274
#ISCELL
  mstr_standard tap *
  page17_i275
#ISCELL
  mstr_standard tap *
  page17_i276
#ISCELL
  mstr_standard tap *
  page17_i277
#ISCELL
  mstr_standard tap *
  page17_i278
#ISCELL
  mstr_standard tap *
  page17_i279
#ISCELL
  mstr_standard tap *
  page17_i280
#ISCELL
  standard offpage *
  page17_i281
#ISCELL
  standard offpage *
  page17_i282
#ISCELL
  standard offpage *
  page17_i283
#ISCELL
  standard offpage *
  page17_i284
#ISCELL
  mstr_standard tap *
  page17_i285
#ISCELL
  mstr_standard tap *
  page17_i286
#ISCELL
  mstr_standard tap *
  page17_i287
#ISCELL
  mstr_standard tap *
  page17_i288
#ISCELL
  mstr_standard tap *
  page17_i289
#ISCELL
  mstr_standard tap *
  page17_i290
#ISCELL
  mstr_standard tap *
  page17_i291
#ISCELL
  mstr_standard tap *
  page17_i292
#ISCELL
  mstr_standard tap *
  page17_i293
#ISCELL
  mstr_standard tap *
  page17_i294
#ISCELL
  mstr_standard tap *
  page17_i295
#ISCELL
  mstr_standard tap *
  page17_i296
#ISCELL
  mstr_standard tap *
  page17_i297
#ISCELL
  mstr_standard tap *
  page17_i298
#ISCELL
  mstr_standard tap *
  page17_i299
#ISCELL
  mstr_standard tap *
  page17_i300
#ISCELL
  mstr_standard tap *
  page17_i301
#ISCELL
  standard offpage *
  page17_i302
#ISCELL
  standard offpage *
  page17_i303
#ISCELL
  standard offpage *
  page17_i304
#ISCELL
  standard offpage *
  page17_i305
#ISCELL
  standard offpage *
  page17_i306
#ISCELL
  standard offpage *
  page17_i307
#ISCELL
  standard offpage *
  page17_i308
#ISCELL
  mstr_standard offpage *
  page17_i309
#ISCELL
  standard offpage *
  page17_i310
#ISCELL
  standard offpage *
  page17_i311
#ISCELL
  standard offpage *
  page17_i312
#ISCELL
  standard offpage *
  page17_i313
#CELL
  pure_quanta q_res *
  page17_i314
#ISCELL
  mstr_standard offpage *
  page17_i315
#ISCELL
  standard offpage *
  page17_i316
#ISCELL
  pure_quanta quanta_title_block_c *
  *
#ISCELL
  pure_quanta_power cad_note *
  *
#CELL
  pure_quanta genoa_sp5 *
  page18_i159
#ISCELL
  mstr_standard offpage *
  page18_i160
#ISCELL
  mstr_standard offpage *
  page18_i161
#ISCELL
  mstr_standard tap *
  page18_i162
#ISCELL
  mstr_standard tap *
  page18_i163
#ISCELL
  mstr_standard tap *
  page18_i164
#ISCELL
  mstr_standard tap *
  page18_i165
#ISCELL
  mstr_standard tap *
  page18_i166
#ISCELL
  mstr_standard tap *
  page18_i167
#ISCELL
  mstr_standard tap *
  page18_i168
#ISCELL
  mstr_standard tap *
  page18_i169
#ISCELL
  mstr_standard tap *
  page18_i170
#ISCELL
  mstr_standard tap *
  page18_i171
#ISCELL
  mstr_standard tap *
  page18_i172
#ISCELL
  mstr_standard tap *
  page18_i173
#ISCELL
  mstr_standard tap *
  page18_i174
#ISCELL
  mstr_standard tap *
  page18_i175
#ISCELL
  mstr_standard tap *
  page18_i176
#ISCELL
  mstr_standard tap *
  page18_i177
#ISCELL
  mstr_standard tap *
  page18_i178
#ISCELL
  mstr_standard tap *
  page18_i179
#ISCELL
  mstr_standard tap *
  page18_i180
#ISCELL
  mstr_standard tap *
  page18_i181
#ISCELL
  mstr_standard tap *
  page18_i182
#ISCELL
  mstr_standard tap *
  page18_i183
#ISCELL
  mstr_standard tap *
  page18_i184
#ISCELL
  mstr_standard tap *
  page18_i185
#ISCELL
  mstr_standard tap *
  page18_i186
#ISCELL
  mstr_standard tap *
  page18_i187
#ISCELL
  mstr_standard tap *
  page18_i188
#ISCELL
  mstr_standard tap *
  page18_i189
#ISCELL
  mstr_standard tap *
  page18_i190
#ISCELL
  mstr_standard tap *
  page18_i191
#ISCELL
  mstr_standard tap *
  page18_i192
#ISCELL
  mstr_standard tap *
  page18_i193
#ISCELL
  mstr_standard tap *
  page18_i194
#ISCELL
  mstr_standard tap *
  page18_i195
#ISCELL
  mstr_standard offpage *
  page18_i196
#ISCELL
  mstr_standard tap *
  page18_i197
#ISCELL
  mstr_standard tap *
  page18_i198
#ISCELL
  mstr_standard tap *
  page18_i199
#ISCELL
  mstr_standard tap *
  page18_i200
#ISCELL
  mstr_standard tap *
  page18_i201
#ISCELL
  mstr_standard tap *
  page18_i202
#ISCELL
  mstr_standard tap *
  page18_i203
#ISCELL
  mstr_standard tap *
  page18_i204
#ISCELL
  mstr_standard tap *
  page18_i205
#ISCELL
  mstr_standard tap *
  page18_i206
#ISCELL
  mstr_standard tap *
  page18_i207
#ISCELL
  mstr_standard tap *
  page18_i208
#ISCELL
  mstr_standard tap *
  page18_i209
#ISCELL
  mstr_standard tap *
  page18_i210
#ISCELL
  mstr_standard tap *
  page18_i211
#ISCELL
  mstr_standard tap *
  page18_i212
#ISCELL
  mstr_standard tap *
  page18_i213
#ISCELL
  mstr_standard tap *
  page18_i214
#ISCELL
  mstr_standard tap *
  page18_i215
#ISCELL
  mstr_standard tap *
  page18_i216
#ISCELL
  mstr_standard tap *
  page18_i217
#ISCELL
  mstr_standard tap *
  page18_i218
#ISCELL
  mstr_standard tap *
  page18_i219
#ISCELL
  mstr_standard tap *
  page18_i220
#ISCELL
  mstr_standard tap *
  page18_i221
#ISCELL
  mstr_standard tap *
  page18_i222
#ISCELL
  mstr_standard tap *
  page18_i223
#ISCELL
  mstr_standard tap *
  page18_i224
#ISCELL
  mstr_standard tap *
  page18_i225
#ISCELL
  mstr_standard tap *
  page18_i226
#ISCELL
  mstr_standard tap *
  page18_i227
#ISCELL
  mstr_standard tap *
  page18_i228
#ISCELL
  mstr_standard tap *
  page18_i229
#ISCELL
  mstr_standard tap *
  page18_i230
#ISCELL
  mstr_standard tap *
  page18_i231
#ISCELL
  mstr_standard tap *
  page18_i232
#ISCELL
  mstr_standard tap *
  page18_i233
#ISCELL
  mstr_standard offpage *
  page18_i234
#ISCELL
  mstr_standard tap *
  page18_i235
#ISCELL
  mstr_standard tap *
  page18_i236
#ISCELL
  mstr_standard tap *
  page18_i237
#ISCELL
  mstr_standard tap *
  page18_i238
#ISCELL
  mstr_standard tap *
  page18_i239
#ISCELL
  mstr_standard tap *
  page18_i240
#ISCELL
  mstr_standard tap *
  page18_i241
#ISCELL
  mstr_standard tap *
  page18_i242
#ISCELL
  mstr_standard tap *
  page18_i243
#ISCELL
  mstr_standard tap *
  page18_i244
#ISCELL
  mstr_standard tap *
  page18_i245
#ISCELL
  mstr_standard tap *
  page18_i246
#ISCELL
  mstr_standard tap *
  page18_i247
#ISCELL
  mstr_standard tap *
  page18_i248
#ISCELL
  mstr_standard tap *
  page18_i249
#ISCELL
  mstr_standard tap *
  page18_i250
#ISCELL
  mstr_standard tap *
  page18_i251
#ISCELL
  mstr_standard tap *
  page18_i252
#ISCELL
  mstr_standard tap *
  page18_i253
#ISCELL
  mstr_standard tap *
  page18_i254
#ISCELL
  mstr_standard tap *
  page18_i255
#ISCELL
  mstr_standard tap *
  page18_i256
#ISCELL
  mstr_standard tap *
  page18_i257
#ISCELL
  mstr_standard tap *
  page18_i258
#ISCELL
  mstr_standard tap *
  page18_i259
#ISCELL
  mstr_standard tap *
  page18_i260
#ISCELL
  mstr_standard tap *
  page18_i261
#ISCELL
  mstr_standard tap *
  page18_i262
#ISCELL
  mstr_standard tap *
  page18_i263
#ISCELL
  mstr_standard tap *
  page18_i264
#ISCELL
  mstr_standard tap *
  page18_i265
#ISCELL
  mstr_standard tap *
  page18_i266
#ISCELL
  mstr_standard tap *
  page18_i267
#ISCELL
  mstr_standard tap *
  page18_i268
#ISCELL
  mstr_standard tap *
  page18_i269
#ISCELL
  mstr_standard tap *
  page18_i270
#ISCELL
  mstr_standard tap *
  page18_i271
#ISCELL
  mstr_standard tap *
  page18_i272
#ISCELL
  mstr_standard tap *
  page18_i273
#ISCELL
  mstr_standard tap *
  page18_i274
#ISCELL
  mstr_standard tap *
  page18_i275
#ISCELL
  mstr_standard tap *
  page18_i276
#ISCELL
  mstr_standard tap *
  page18_i277
#ISCELL
  mstr_standard tap *
  page18_i278
#ISCELL
  mstr_standard tap *
  page18_i279
#ISCELL
  mstr_standard tap *
  page18_i280
#ISCELL
  standard offpage *
  page18_i281
#ISCELL
  standard offpage *
  page18_i282
#ISCELL
  standard offpage *
  page18_i283
#ISCELL
  standard offpage *
  page18_i284
#ISCELL
  mstr_standard tap *
  page18_i285
#ISCELL
  mstr_standard tap *
  page18_i286
#ISCELL
  mstr_standard tap *
  page18_i287
#ISCELL
  mstr_standard tap *
  page18_i288
#ISCELL
  mstr_standard tap *
  page18_i289
#ISCELL
  mstr_standard tap *
  page18_i290
#ISCELL
  mstr_standard tap *
  page18_i291
#ISCELL
  mstr_standard tap *
  page18_i292
#ISCELL
  mstr_standard tap *
  page18_i293
#ISCELL
  mstr_standard tap *
  page18_i294
#ISCELL
  mstr_standard tap *
  page18_i295
#ISCELL
  mstr_standard tap *
  page18_i296
#ISCELL
  mstr_standard tap *
  page18_i297
#ISCELL
  mstr_standard tap *
  page18_i298
#ISCELL
  mstr_standard tap *
  page18_i299
#ISCELL
  mstr_standard tap *
  page18_i300
#ISCELL
  mstr_standard tap *
  page18_i301
#ISCELL
  standard offpage *
  page18_i302
#ISCELL
  standard offpage *
  page18_i303
#ISCELL
  standard offpage *
  page18_i304
#ISCELL
  standard offpage *
  page18_i305
#ISCELL
  standard offpage *
  page18_i306
#ISCELL
  standard offpage *
  page18_i307
#ISCELL
  standard offpage *
  page18_i308
#ISCELL
  mstr_standard offpage *
  page18_i309
#ISCELL
  standard offpage *
  page18_i310
#ISCELL
  standard offpage *
  page18_i311
#ISCELL
  standard offpage *
  page18_i312
#ISCELL
  standard offpage *
  page18_i313
#CELL
  pure_quanta q_res *
  page18_i314
#ISCELL
  mstr_standard offpage *
  page18_i315
#ISCELL
  standard offpage *
  page18_i316
#ISCELL
  pure_quanta quanta_title_block_c *
  *
#ISCELL
  pure_quanta_power cad_note *
  *
#CELL
  pure_quanta genoa_sp5 *
  page19_i159
#ISCELL
  mstr_standard offpage *
  page19_i160
#ISCELL
  mstr_standard offpage *
  page19_i161
#ISCELL
  mstr_standard tap *
  page19_i162
#ISCELL
  mstr_standard tap *
  page19_i163
#ISCELL
  mstr_standard tap *
  page19_i164
#ISCELL
  mstr_standard tap *
  page19_i165
#ISCELL
  mstr_standard tap *
  page19_i166
#ISCELL
  mstr_standard tap *
  page19_i167
#ISCELL
  mstr_standard tap *
  page19_i168
#ISCELL
  mstr_standard tap *
  page19_i169
#ISCELL
  mstr_standard tap *
  page19_i170
#ISCELL
  mstr_standard tap *
  page19_i171
#ISCELL
  mstr_standard tap *
  page19_i172
#ISCELL
  mstr_standard tap *
  page19_i173
#ISCELL
  mstr_standard tap *
  page19_i174
#ISCELL
  mstr_standard tap *
  page19_i175
#ISCELL
  mstr_standard tap *
  page19_i176
#ISCELL
  mstr_standard tap *
  page19_i177
#ISCELL
  mstr_standard tap *
  page19_i178
#ISCELL
  mstr_standard tap *
  page19_i179
#ISCELL
  mstr_standard tap *
  page19_i180
#ISCELL
  mstr_standard tap *
  page19_i181
#ISCELL
  mstr_standard tap *
  page19_i182
#ISCELL
  mstr_standard tap *
  page19_i183
#ISCELL
  mstr_standard tap *
  page19_i184
#ISCELL
  mstr_standard tap *
  page19_i185
#ISCELL
  mstr_standard tap *
  page19_i186
#ISCELL
  mstr_standard tap *
  page19_i187
#ISCELL
  mstr_standard tap *
  page19_i188
#ISCELL
  mstr_standard tap *
  page19_i189
#ISCELL
  mstr_standard tap *
  page19_i190
#ISCELL
  mstr_standard tap *
  page19_i191
#ISCELL
  mstr_standard tap *
  page19_i192
#ISCELL
  mstr_standard tap *
  page19_i193
#ISCELL
  mstr_standard tap *
  page19_i194
#ISCELL
  mstr_standard tap *
  page19_i195
#ISCELL
  mstr_standard tap *
  page19_i196
#ISCELL
  mstr_standard offpage *
  page19_i197
#ISCELL
  mstr_standard tap *
  page19_i198
#ISCELL
  mstr_standard tap *
  page19_i199
#ISCELL
  mstr_standard tap *
  page19_i200
#ISCELL
  mstr_standard tap *
  page19_i201
#ISCELL
  mstr_standard tap *
  page19_i202
#ISCELL
  mstr_standard tap *
  page19_i203
#ISCELL
  mstr_standard tap *
  page19_i204
#ISCELL
  mstr_standard tap *
  page19_i205
#ISCELL
  mstr_standard tap *
  page19_i206
#ISCELL
  mstr_standard tap *
  page19_i207
#ISCELL
  mstr_standard tap *
  page19_i208
#ISCELL
  mstr_standard tap *
  page19_i209
#ISCELL
  mstr_standard tap *
  page19_i210
#ISCELL
  mstr_standard tap *
  page19_i211
#ISCELL
  mstr_standard tap *
  page19_i212
#ISCELL
  mstr_standard tap *
  page19_i213
#ISCELL
  mstr_standard tap *
  page19_i214
#ISCELL
  mstr_standard tap *
  page19_i215
#ISCELL
  mstr_standard tap *
  page19_i216
#ISCELL
  mstr_standard tap *
  page19_i217
#ISCELL
  mstr_standard tap *
  page19_i218
#ISCELL
  mstr_standard tap *
  page19_i219
#ISCELL
  mstr_standard tap *
  page19_i220
#ISCELL
  mstr_standard tap *
  page19_i221
#ISCELL
  mstr_standard tap *
  page19_i222
#ISCELL
  mstr_standard tap *
  page19_i223
#ISCELL
  mstr_standard tap *
  page19_i224
#ISCELL
  mstr_standard tap *
  page19_i225
#ISCELL
  mstr_standard tap *
  page19_i226
#ISCELL
  mstr_standard tap *
  page19_i227
#ISCELL
  mstr_standard tap *
  page19_i228
#ISCELL
  mstr_standard tap *
  page19_i229
#ISCELL
  mstr_standard tap *
  page19_i230
#ISCELL
  mstr_standard tap *
  page19_i231
#ISCELL
  mstr_standard tap *
  page19_i232
#ISCELL
  mstr_standard tap *
  page19_i233
#ISCELL
  mstr_standard tap *
  page19_i234
#ISCELL
  mstr_standard offpage *
  page19_i235
#ISCELL
  mstr_standard tap *
  page19_i236
#ISCELL
  mstr_standard tap *
  page19_i237
#ISCELL
  mstr_standard tap *
  page19_i238
#ISCELL
  mstr_standard tap *
  page19_i239
#ISCELL
  mstr_standard tap *
  page19_i240
#ISCELL
  mstr_standard tap *
  page19_i241
#ISCELL
  mstr_standard tap *
  page19_i242
#ISCELL
  mstr_standard tap *
  page19_i243
#ISCELL
  mstr_standard tap *
  page19_i244
#ISCELL
  mstr_standard tap *
  page19_i245
#ISCELL
  mstr_standard tap *
  page19_i246
#ISCELL
  mstr_standard tap *
  page19_i247
#ISCELL
  mstr_standard tap *
  page19_i248
#ISCELL
  mstr_standard tap *
  page19_i249
#ISCELL
  mstr_standard tap *
  page19_i250
#ISCELL
  mstr_standard tap *
  page19_i251
#ISCELL
  mstr_standard tap *
  page19_i252
#ISCELL
  mstr_standard tap *
  page19_i253
#ISCELL
  mstr_standard tap *
  page19_i254
#ISCELL
  mstr_standard tap *
  page19_i255
#ISCELL
  mstr_standard tap *
  page19_i256
#ISCELL
  mstr_standard tap *
  page19_i257
#ISCELL
  mstr_standard tap *
  page19_i258
#ISCELL
  mstr_standard tap *
  page19_i259
#ISCELL
  mstr_standard tap *
  page19_i260
#ISCELL
  mstr_standard tap *
  page19_i261
#ISCELL
  mstr_standard tap *
  page19_i262
#ISCELL
  mstr_standard tap *
  page19_i263
#ISCELL
  mstr_standard tap *
  page19_i264
#ISCELL
  mstr_standard tap *
  page19_i265
#ISCELL
  mstr_standard tap *
  page19_i266
#ISCELL
  mstr_standard tap *
  page19_i267
#ISCELL
  mstr_standard tap *
  page19_i268
#ISCELL
  mstr_standard tap *
  page19_i269
#ISCELL
  mstr_standard tap *
  page19_i270
#ISCELL
  mstr_standard tap *
  page19_i271
#ISCELL
  mstr_standard tap *
  page19_i272
#ISCELL
  mstr_standard tap *
  page19_i273
#ISCELL
  mstr_standard tap *
  page19_i274
#ISCELL
  mstr_standard tap *
  page19_i275
#ISCELL
  mstr_standard tap *
  page19_i276
#ISCELL
  mstr_standard tap *
  page19_i277
#ISCELL
  mstr_standard tap *
  page19_i278
#ISCELL
  mstr_standard tap *
  page19_i279
#ISCELL
  mstr_standard tap *
  page19_i280
#ISCELL
  mstr_standard tap *
  page19_i281
#ISCELL
  standard offpage *
  page19_i282
#ISCELL
  standard offpage *
  page19_i283
#ISCELL
  standard offpage *
  page19_i284
#ISCELL
  standard offpage *
  page19_i285
#ISCELL
  mstr_standard tap *
  page19_i286
#ISCELL
  mstr_standard tap *
  page19_i287
#ISCELL
  mstr_standard tap *
  page19_i288
#ISCELL
  mstr_standard tap *
  page19_i289
#ISCELL
  mstr_standard tap *
  page19_i290
#ISCELL
  mstr_standard tap *
  page19_i291
#ISCELL
  mstr_standard tap *
  page19_i292
#ISCELL
  mstr_standard tap *
  page19_i293
#ISCELL
  mstr_standard tap *
  page19_i294
#ISCELL
  mstr_standard tap *
  page19_i295
#ISCELL
  mstr_standard tap *
  page19_i296
#ISCELL
  mstr_standard tap *
  page19_i297
#ISCELL
  mstr_standard tap *
  page19_i298
#ISCELL
  mstr_standard tap *
  page19_i299
#ISCELL
  mstr_standard tap *
  page19_i300
#ISCELL
  mstr_standard tap *
  page19_i301
#ISCELL
  standard offpage *
  page19_i302
#ISCELL
  standard offpage *
  page19_i303
#ISCELL
  standard offpage *
  page19_i304
#ISCELL
  standard offpage *
  page19_i305
#ISCELL
  standard offpage *
  page19_i306
#ISCELL
  mstr_standard offpage *
  page19_i307
#ISCELL
  standard offpage *
  page19_i308
#ISCELL
  standard offpage *
  page19_i309
#ISCELL
  standard offpage *
  page19_i310
#ISCELL
  standard offpage *
  page19_i311
#ISCELL
  standard offpage *
  page19_i312
#ISCELL
  standard offpage *
  page19_i313
#CELL
  pure_quanta q_res *
  page19_i314
#ISCELL
  mstr_standard offpage *
  page19_i315
#ISCELL
  standard offpage *
  page19_i316
#ISCELL
  pure_quanta quanta_title_block_c *
  *
#ISCELL
  pure_quanta_power cad_note *
  *
#CELL
  pure_quanta genoa_sp5 *
  page20_i159
#ISCELL
  mstr_standard offpage *
  page20_i160
#ISCELL
  mstr_standard offpage *
  page20_i161
#ISCELL
  mstr_standard tap *
  page20_i162
#ISCELL
  mstr_standard tap *
  page20_i163
#ISCELL
  mstr_standard tap *
  page20_i164
#ISCELL
  mstr_standard tap *
  page20_i165
#ISCELL
  mstr_standard tap *
  page20_i166
#ISCELL
  mstr_standard tap *
  page20_i167
#ISCELL
  mstr_standard tap *
  page20_i168
#ISCELL
  mstr_standard tap *
  page20_i169
#ISCELL
  mstr_standard tap *
  page20_i170
#ISCELL
  mstr_standard tap *
  page20_i171
#ISCELL
  mstr_standard tap *
  page20_i172
#ISCELL
  mstr_standard tap *
  page20_i173
#ISCELL
  mstr_standard tap *
  page20_i174
#ISCELL
  mstr_standard tap *
  page20_i175
#ISCELL
  mstr_standard tap *
  page20_i176
#ISCELL
  mstr_standard tap *
  page20_i177
#ISCELL
  mstr_standard tap *
  page20_i178
#ISCELL
  mstr_standard tap *
  page20_i179
#ISCELL
  mstr_standard tap *
  page20_i180
#ISCELL
  mstr_standard tap *
  page20_i181
#ISCELL
  mstr_standard tap *
  page20_i182
#ISCELL
  mstr_standard tap *
  page20_i183
#ISCELL
  mstr_standard tap *
  page20_i184
#ISCELL
  mstr_standard tap *
  page20_i185
#ISCELL
  mstr_standard tap *
  page20_i186
#ISCELL
  mstr_standard tap *
  page20_i187
#ISCELL
  mstr_standard tap *
  page20_i188
#ISCELL
  mstr_standard tap *
  page20_i189
#ISCELL
  mstr_standard tap *
  page20_i190
#ISCELL
  mstr_standard tap *
  page20_i191
#ISCELL
  mstr_standard tap *
  page20_i192
#ISCELL
  mstr_standard tap *
  page20_i193
#ISCELL
  mstr_standard tap *
  page20_i194
#ISCELL
  mstr_standard tap *
  page20_i195
#ISCELL
  mstr_standard offpage *
  page20_i196
#ISCELL
  mstr_standard tap *
  page20_i197
#ISCELL
  mstr_standard tap *
  page20_i198
#ISCELL
  mstr_standard tap *
  page20_i199
#ISCELL
  mstr_standard tap *
  page20_i200
#ISCELL
  mstr_standard tap *
  page20_i201
#ISCELL
  mstr_standard tap *
  page20_i202
#ISCELL
  mstr_standard tap *
  page20_i203
#ISCELL
  mstr_standard tap *
  page20_i204
#ISCELL
  mstr_standard tap *
  page20_i205
#ISCELL
  mstr_standard tap *
  page20_i206
#ISCELL
  mstr_standard tap *
  page20_i207
#ISCELL
  mstr_standard tap *
  page20_i208
#ISCELL
  mstr_standard tap *
  page20_i209
#ISCELL
  mstr_standard tap *
  page20_i210
#ISCELL
  mstr_standard tap *
  page20_i211
#ISCELL
  mstr_standard tap *
  page20_i212
#ISCELL
  mstr_standard tap *
  page20_i213
#ISCELL
  mstr_standard tap *
  page20_i214
#ISCELL
  mstr_standard tap *
  page20_i215
#ISCELL
  mstr_standard tap *
  page20_i216
#ISCELL
  mstr_standard tap *
  page20_i217
#ISCELL
  mstr_standard tap *
  page20_i218
#ISCELL
  mstr_standard tap *
  page20_i219
#ISCELL
  mstr_standard tap *
  page20_i220
#ISCELL
  mstr_standard tap *
  page20_i221
#ISCELL
  mstr_standard tap *
  page20_i222
#ISCELL
  mstr_standard tap *
  page20_i223
#ISCELL
  mstr_standard tap *
  page20_i224
#ISCELL
  mstr_standard tap *
  page20_i225
#ISCELL
  mstr_standard tap *
  page20_i226
#ISCELL
  mstr_standard tap *
  page20_i227
#ISCELL
  mstr_standard tap *
  page20_i228
#ISCELL
  mstr_standard tap *
  page20_i229
#ISCELL
  mstr_standard tap *
  page20_i230
#ISCELL
  mstr_standard tap *
  page20_i231
#ISCELL
  mstr_standard tap *
  page20_i232
#ISCELL
  mstr_standard tap *
  page20_i233
#ISCELL
  mstr_standard offpage *
  page20_i234
#ISCELL
  mstr_standard tap *
  page20_i235
#ISCELL
  mstr_standard tap *
  page20_i236
#ISCELL
  mstr_standard tap *
  page20_i237
#ISCELL
  mstr_standard tap *
  page20_i238
#ISCELL
  mstr_standard tap *
  page20_i239
#ISCELL
  mstr_standard tap *
  page20_i240
#ISCELL
  mstr_standard tap *
  page20_i241
#ISCELL
  mstr_standard tap *
  page20_i242
#ISCELL
  mstr_standard tap *
  page20_i243
#ISCELL
  mstr_standard tap *
  page20_i244
#ISCELL
  mstr_standard tap *
  page20_i245
#ISCELL
  mstr_standard tap *
  page20_i246
#ISCELL
  mstr_standard tap *
  page20_i247
#ISCELL
  mstr_standard tap *
  page20_i248
#ISCELL
  mstr_standard tap *
  page20_i249
#ISCELL
  mstr_standard tap *
  page20_i250
#ISCELL
  mstr_standard tap *
  page20_i251
#ISCELL
  mstr_standard tap *
  page20_i252
#ISCELL
  mstr_standard tap *
  page20_i253
#ISCELL
  mstr_standard tap *
  page20_i254
#ISCELL
  mstr_standard tap *
  page20_i255
#ISCELL
  mstr_standard tap *
  page20_i256
#ISCELL
  mstr_standard tap *
  page20_i257
#ISCELL
  mstr_standard tap *
  page20_i258
#ISCELL
  mstr_standard tap *
  page20_i259
#ISCELL
  mstr_standard tap *
  page20_i260
#ISCELL
  mstr_standard tap *
  page20_i261
#ISCELL
  mstr_standard tap *
  page20_i262
#ISCELL
  mstr_standard tap *
  page20_i263
#ISCELL
  mstr_standard tap *
  page20_i264
#ISCELL
  mstr_standard tap *
  page20_i265
#ISCELL
  mstr_standard tap *
  page20_i266
#ISCELL
  mstr_standard tap *
  page20_i267
#ISCELL
  mstr_standard tap *
  page20_i268
#ISCELL
  mstr_standard tap *
  page20_i269
#ISCELL
  mstr_standard tap *
  page20_i270
#ISCELL
  mstr_standard tap *
  page20_i271
#ISCELL
  mstr_standard tap *
  page20_i272
#ISCELL
  mstr_standard tap *
  page20_i273
#ISCELL
  mstr_standard tap *
  page20_i274
#ISCELL
  mstr_standard tap *
  page20_i275
#ISCELL
  mstr_standard tap *
  page20_i276
#ISCELL
  mstr_standard tap *
  page20_i277
#ISCELL
  mstr_standard tap *
  page20_i278
#ISCELL
  mstr_standard tap *
  page20_i279
#ISCELL
  mstr_standard tap *
  page20_i280
#ISCELL
  standard offpage *
  page20_i281
#ISCELL
  standard offpage *
  page20_i282
#ISCELL
  standard offpage *
  page20_i283
#ISCELL
  standard offpage *
  page20_i284
#ISCELL
  mstr_standard tap *
  page20_i285
#ISCELL
  mstr_standard tap *
  page20_i286
#ISCELL
  mstr_standard tap *
  page20_i287
#ISCELL
  mstr_standard tap *
  page20_i288
#ISCELL
  mstr_standard tap *
  page20_i289
#ISCELL
  mstr_standard tap *
  page20_i290
#ISCELL
  mstr_standard tap *
  page20_i291
#ISCELL
  mstr_standard tap *
  page20_i292
#ISCELL
  mstr_standard tap *
  page20_i293
#ISCELL
  mstr_standard tap *
  page20_i294
#ISCELL
  mstr_standard tap *
  page20_i295
#ISCELL
  mstr_standard tap *
  page20_i296
#ISCELL
  mstr_standard tap *
  page20_i297
#ISCELL
  mstr_standard tap *
  page20_i298
#ISCELL
  mstr_standard tap *
  page20_i299
#ISCELL
  mstr_standard tap *
  page20_i300
#ISCELL
  mstr_standard tap *
  page20_i301
#ISCELL
  standard offpage *
  page20_i302
#ISCELL
  standard offpage *
  page20_i303
#ISCELL
  standard offpage *
  page20_i304
#ISCELL
  standard offpage *
  page20_i305
#ISCELL
  standard offpage *
  page20_i306
#ISCELL
  standard offpage *
  page20_i307
#ISCELL
  standard offpage *
  page20_i308
#ISCELL
  mstr_standard offpage *
  page20_i309
#ISCELL
  standard offpage *
  page20_i310
#ISCELL
  standard offpage *
  page20_i311
#ISCELL
  standard offpage *
  page20_i312
#ISCELL
  standard offpage *
  page20_i313
#CELL
  pure_quanta q_res *
  page20_i314
#ISCELL
  mstr_standard offpage *
  page20_i315
#ISCELL
  standard offpage *
  page20_i316
#ISCELL
  pure_quanta quanta_title_block_c *
  *
#ISCELL
  pure_quanta_power cad_note *
  *
#CELL
  pure_quanta genoa_sp5 *
  page21_i159
#ISCELL
  mstr_standard offpage *
  page21_i160
#ISCELL
  mstr_standard offpage *
  page21_i161
#ISCELL
  mstr_standard tap *
  page21_i162
#ISCELL
  mstr_standard tap *
  page21_i163
#ISCELL
  mstr_standard tap *
  page21_i164
#ISCELL
  mstr_standard tap *
  page21_i165
#ISCELL
  mstr_standard tap *
  page21_i166
#ISCELL
  mstr_standard tap *
  page21_i167
#ISCELL
  mstr_standard tap *
  page21_i168
#ISCELL
  mstr_standard tap *
  page21_i169
#ISCELL
  mstr_standard tap *
  page21_i170
#ISCELL
  mstr_standard tap *
  page21_i171
#ISCELL
  mstr_standard tap *
  page21_i172
#ISCELL
  mstr_standard tap *
  page21_i173
#ISCELL
  mstr_standard tap *
  page21_i174
#ISCELL
  mstr_standard tap *
  page21_i175
#ISCELL
  mstr_standard tap *
  page21_i176
#ISCELL
  mstr_standard tap *
  page21_i177
#ISCELL
  mstr_standard tap *
  page21_i178
#ISCELL
  mstr_standard tap *
  page21_i179
#ISCELL
  mstr_standard tap *
  page21_i180
#ISCELL
  mstr_standard tap *
  page21_i181
#ISCELL
  mstr_standard tap *
  page21_i182
#ISCELL
  mstr_standard tap *
  page21_i183
#ISCELL
  mstr_standard tap *
  page21_i184
#ISCELL
  mstr_standard tap *
  page21_i185
#ISCELL
  mstr_standard tap *
  page21_i186
#ISCELL
  mstr_standard tap *
  page21_i187
#ISCELL
  mstr_standard tap *
  page21_i188
#ISCELL
  mstr_standard tap *
  page21_i189
#ISCELL
  mstr_standard tap *
  page21_i190
#ISCELL
  mstr_standard tap *
  page21_i191
#ISCELL
  mstr_standard tap *
  page21_i192
#ISCELL
  mstr_standard tap *
  page21_i193
#ISCELL
  mstr_standard tap *
  page21_i194
#ISCELL
  mstr_standard tap *
  page21_i195
#ISCELL
  mstr_standard tap *
  page21_i196
#ISCELL
  mstr_standard offpage *
  page21_i197
#ISCELL
  mstr_standard tap *
  page21_i198
#ISCELL
  mstr_standard tap *
  page21_i199
#ISCELL
  mstr_standard tap *
  page21_i200
#ISCELL
  mstr_standard tap *
  page21_i201
#ISCELL
  mstr_standard tap *
  page21_i202
#ISCELL
  mstr_standard tap *
  page21_i203
#ISCELL
  mstr_standard tap *
  page21_i204
#ISCELL
  mstr_standard tap *
  page21_i205
#ISCELL
  mstr_standard tap *
  page21_i206
#ISCELL
  mstr_standard tap *
  page21_i207
#ISCELL
  mstr_standard tap *
  page21_i208
#ISCELL
  mstr_standard tap *
  page21_i209
#ISCELL
  mstr_standard tap *
  page21_i210
#ISCELL
  mstr_standard tap *
  page21_i211
#ISCELL
  mstr_standard tap *
  page21_i212
#ISCELL
  mstr_standard tap *
  page21_i213
#ISCELL
  mstr_standard tap *
  page21_i214
#ISCELL
  mstr_standard tap *
  page21_i215
#ISCELL
  mstr_standard tap *
  page21_i216
#ISCELL
  mstr_standard tap *
  page21_i217
#ISCELL
  mstr_standard tap *
  page21_i218
#ISCELL
  mstr_standard tap *
  page21_i219
#ISCELL
  mstr_standard tap *
  page21_i220
#ISCELL
  mstr_standard tap *
  page21_i221
#ISCELL
  mstr_standard tap *
  page21_i222
#ISCELL
  mstr_standard tap *
  page21_i223
#ISCELL
  mstr_standard tap *
  page21_i224
#ISCELL
  mstr_standard tap *
  page21_i225
#ISCELL
  mstr_standard tap *
  page21_i226
#ISCELL
  mstr_standard tap *
  page21_i227
#ISCELL
  mstr_standard tap *
  page21_i228
#ISCELL
  mstr_standard tap *
  page21_i229
#ISCELL
  mstr_standard tap *
  page21_i230
#ISCELL
  mstr_standard tap *
  page21_i231
#ISCELL
  mstr_standard tap *
  page21_i232
#ISCELL
  mstr_standard tap *
  page21_i233
#ISCELL
  mstr_standard tap *
  page21_i234
#ISCELL
  mstr_standard offpage *
  page21_i235
#ISCELL
  mstr_standard tap *
  page21_i236
#ISCELL
  mstr_standard tap *
  page21_i237
#ISCELL
  mstr_standard tap *
  page21_i238
#ISCELL
  mstr_standard tap *
  page21_i239
#ISCELL
  mstr_standard tap *
  page21_i240
#ISCELL
  mstr_standard tap *
  page21_i241
#ISCELL
  mstr_standard tap *
  page21_i242
#ISCELL
  mstr_standard tap *
  page21_i243
#ISCELL
  mstr_standard tap *
  page21_i244
#ISCELL
  mstr_standard tap *
  page21_i245
#ISCELL
  mstr_standard tap *
  page21_i246
#ISCELL
  mstr_standard tap *
  page21_i247
#ISCELL
  mstr_standard tap *
  page21_i248
#ISCELL
  mstr_standard tap *
  page21_i249
#ISCELL
  mstr_standard tap *
  page21_i250
#ISCELL
  mstr_standard tap *
  page21_i251
#ISCELL
  mstr_standard tap *
  page21_i252
#ISCELL
  mstr_standard tap *
  page21_i253
#ISCELL
  mstr_standard tap *
  page21_i254
#ISCELL
  mstr_standard tap *
  page21_i255
#ISCELL
  mstr_standard tap *
  page21_i256
#ISCELL
  mstr_standard tap *
  page21_i257
#ISCELL
  mstr_standard tap *
  page21_i258
#ISCELL
  mstr_standard tap *
  page21_i259
#ISCELL
  mstr_standard tap *
  page21_i260
#ISCELL
  mstr_standard tap *
  page21_i261
#ISCELL
  mstr_standard tap *
  page21_i262
#ISCELL
  mstr_standard tap *
  page21_i263
#ISCELL
  mstr_standard tap *
  page21_i264
#ISCELL
  mstr_standard tap *
  page21_i265
#ISCELL
  mstr_standard tap *
  page21_i266
#ISCELL
  mstr_standard tap *
  page21_i267
#ISCELL
  mstr_standard tap *
  page21_i268
#ISCELL
  mstr_standard tap *
  page21_i269
#ISCELL
  mstr_standard tap *
  page21_i270
#ISCELL
  mstr_standard tap *
  page21_i271
#ISCELL
  mstr_standard tap *
  page21_i272
#ISCELL
  mstr_standard tap *
  page21_i273
#ISCELL
  mstr_standard tap *
  page21_i274
#ISCELL
  mstr_standard tap *
  page21_i275
#ISCELL
  mstr_standard tap *
  page21_i276
#ISCELL
  mstr_standard tap *
  page21_i277
#ISCELL
  mstr_standard tap *
  page21_i278
#ISCELL
  mstr_standard tap *
  page21_i279
#ISCELL
  mstr_standard tap *
  page21_i280
#ISCELL
  mstr_standard tap *
  page21_i281
#ISCELL
  standard offpage *
  page21_i282
#ISCELL
  standard offpage *
  page21_i283
#ISCELL
  standard offpage *
  page21_i284
#ISCELL
  standard offpage *
  page21_i285
#ISCELL
  mstr_standard tap *
  page21_i286
#ISCELL
  mstr_standard tap *
  page21_i287
#ISCELL
  mstr_standard tap *
  page21_i288
#ISCELL
  mstr_standard tap *
  page21_i289
#ISCELL
  mstr_standard tap *
  page21_i290
#ISCELL
  mstr_standard tap *
  page21_i291
#ISCELL
  mstr_standard tap *
  page21_i292
#ISCELL
  mstr_standard tap *
  page21_i293
#ISCELL
  mstr_standard tap *
  page21_i294
#ISCELL
  mstr_standard tap *
  page21_i295
#ISCELL
  mstr_standard tap *
  page21_i296
#ISCELL
  mstr_standard tap *
  page21_i297
#ISCELL
  mstr_standard tap *
  page21_i298
#ISCELL
  mstr_standard tap *
  page21_i299
#ISCELL
  mstr_standard tap *
  page21_i300
#ISCELL
  mstr_standard tap *
  page21_i301
#ISCELL
  standard offpage *
  page21_i302
#ISCELL
  standard offpage *
  page21_i303
#ISCELL
  standard offpage *
  page21_i304
#ISCELL
  standard offpage *
  page21_i305
#ISCELL
  standard offpage *
  page21_i306
#ISCELL
  mstr_standard offpage *
  page21_i307
#ISCELL
  standard offpage *
  page21_i308
#ISCELL
  standard offpage *
  page21_i309
#ISCELL
  standard offpage *
  page21_i310
#ISCELL
  standard offpage *
  page21_i311
#ISCELL
  standard offpage *
  page21_i312
#ISCELL
  standard offpage *
  page21_i313
#CELL
  pure_quanta q_res *
  page21_i314
#ISCELL
  mstr_standard offpage *
  page21_i315
#ISCELL
  standard offpage *
  page21_i316
#ISCELL
  pure_quanta quanta_title_block_c *
  *
#CELL
  pure_quanta genoa_sp5 *
  page22_i207
#CELL
  pure_quanta genoa_sp5 *
  page22_i208
#ISCELL
  standard offpage *
  page22_i243
#ISCELL
  standard offpage *
  page22_i244
#ISCELL
  mstr_standard tap *
  page22_i245
#ISCELL
  mstr_standard tap *
  page22_i246
#ISCELL
  mstr_standard tap *
  page22_i247
#ISCELL
  standard tap *
  page22_i248
#ISCELL
  standard tap *
  page22_i249
#ISCELL
  mstr_standard tap *
  page22_i250
#ISCELL
  standard tap *
  page22_i251
#ISCELL
  standard tap *
  page22_i252
#ISCELL
  standard tap *
  page22_i253
#ISCELL
  standard tap *
  page22_i254
#ISCELL
  standard tap *
  page22_i255
#ISCELL
  standard tap *
  page22_i256
#ISCELL
  standard tap *
  page22_i257
#ISCELL
  standard tap *
  page22_i258
#ISCELL
  standard tap *
  page22_i259
#ISCELL
  standard tap *
  page22_i260
#ISCELL
  standard tap *
  page22_i261
#ISCELL
  standard tap *
  page22_i262
#ISCELL
  standard tap *
  page22_i263
#ISCELL
  standard tap *
  page22_i264
#ISCELL
  standard tap *
  page22_i265
#ISCELL
  standard tap *
  page22_i266
#ISCELL
  standard tap *
  page22_i267
#ISCELL
  standard tap *
  page22_i268
#ISCELL
  standard tap *
  page22_i269
#ISCELL
  standard tap *
  page22_i270
#ISCELL
  standard tap *
  page22_i271
#ISCELL
  standard tap *
  page22_i272
#ISCELL
  standard tap *
  page22_i273
#ISCELL
  standard tap *
  page22_i274
#ISCELL
  standard tap *
  page22_i275
#ISCELL
  standard tap *
  page22_i276
#ISCELL
  mstr_standard tap *
  page22_i277
#ISCELL
  mstr_standard tap *
  page22_i278
#ISCELL
  mstr_standard tap *
  page22_i279
#ISCELL
  mstr_standard tap *
  page22_i280
#ISCELL
  mstr_standard tap *
  page22_i281
#ISCELL
  standard tap *
  page22_i282
#ISCELL
  standard tap *
  page22_i283
#ISCELL
  standard tap *
  page22_i284
#ISCELL
  standard tap *
  page22_i285
#ISCELL
  standard tap *
  page22_i286
#ISCELL
  standard tap *
  page22_i287
#ISCELL
  standard tap *
  page22_i288
#ISCELL
  standard tap *
  page22_i289
#ISCELL
  standard tap *
  page22_i290
#ISCELL
  standard tap *
  page22_i291
#ISCELL
  standard tap *
  page22_i292
#ISCELL
  standard tap *
  page22_i293
#ISCELL
  standard tap *
  page22_i294
#ISCELL
  standard tap *
  page22_i295
#ISCELL
  standard tap *
  page22_i296
#ISCELL
  standard tap *
  page22_i297
#ISCELL
  standard tap *
  page22_i298
#ISCELL
  standard tap *
  page22_i299
#ISCELL
  standard tap *
  page22_i300
#ISCELL
  standard tap *
  page22_i301
#ISCELL
  standard tap *
  page22_i302
#ISCELL
  standard tap *
  page22_i303
#ISCELL
  standard tap *
  page22_i304
#ISCELL
  standard tap *
  page22_i305
#ISCELL
  standard tap *
  page22_i306
#ISCELL
  standard tap *
  page22_i307
#ISCELL
  standard tap *
  page22_i308
#ISCELL
  standard offpage *
  page22_i309
#ISCELL
  standard offpage *
  page22_i310
#ISCELL
  standard offpage *
  page22_i311
#ISCELL
  standard offpage *
  page22_i312
#ISCELL
  mstr_standard tap *
  page22_i313
#ISCELL
  mstr_standard tap *
  page22_i314
#ISCELL
  mstr_standard tap *
  page22_i315
#ISCELL
  mstr_standard tap *
  page22_i316
#ISCELL
  standard tap *
  page22_i317
#ISCELL
  standard tap *
  page22_i318
#ISCELL
  standard tap *
  page22_i319
#ISCELL
  standard tap *
  page22_i320
#ISCELL
  standard tap *
  page22_i321
#ISCELL
  standard tap *
  page22_i322
#ISCELL
  standard tap *
  page22_i323
#ISCELL
  standard tap *
  page22_i324
#ISCELL
  standard tap *
  page22_i325
#ISCELL
  standard tap *
  page22_i326
#ISCELL
  standard tap *
  page22_i327
#ISCELL
  standard tap *
  page22_i328
#ISCELL
  standard tap *
  page22_i329
#ISCELL
  standard tap *
  page22_i330
#ISCELL
  standard tap *
  page22_i331
#ISCELL
  standard tap *
  page22_i332
#ISCELL
  standard tap *
  page22_i333
#ISCELL
  standard tap *
  page22_i334
#ISCELL
  standard tap *
  page22_i335
#ISCELL
  standard tap *
  page22_i336
#ISCELL
  standard tap *
  page22_i337
#ISCELL
  standard tap *
  page22_i338
#ISCELL
  standard tap *
  page22_i339
#ISCELL
  standard tap *
  page22_i340
#ISCELL
  standard tap *
  page22_i341
#ISCELL
  standard tap *
  page22_i342
#ISCELL
  standard tap *
  page22_i343
#ISCELL
  standard tap *
  page22_i344
#ISCELL
  mstr_standard tap *
  page22_i345
#ISCELL
  mstr_standard tap *
  page22_i346
#ISCELL
  mstr_standard tap *
  page22_i347
#ISCELL
  mstr_standard tap *
  page22_i348
#ISCELL
  standard tap *
  page22_i349
#ISCELL
  standard tap *
  page22_i350
#ISCELL
  mstr_standard tap *
  page22_i351
#ISCELL
  standard tap *
  page22_i352
#ISCELL
  standard tap *
  page22_i353
#ISCELL
  standard tap *
  page22_i354
#ISCELL
  standard tap *
  page22_i355
#ISCELL
  standard tap *
  page22_i356
#ISCELL
  standard tap *
  page22_i357
#ISCELL
  standard tap *
  page22_i358
#ISCELL
  standard tap *
  page22_i359
#ISCELL
  standard tap *
  page22_i360
#ISCELL
  standard tap *
  page22_i361
#ISCELL
  standard tap *
  page22_i362
#ISCELL
  standard tap *
  page22_i363
#ISCELL
  standard offpage *
  page22_i364
#ISCELL
  standard offpage *
  page22_i365
#ISCELL
  standard tap *
  page22_i366
#ISCELL
  standard tap *
  page22_i367
#ISCELL
  standard tap *
  page22_i368
#ISCELL
  standard tap *
  page22_i369
#ISCELL
  standard tap *
  page22_i370
#ISCELL
  standard tap *
  page22_i371
#ISCELL
  standard tap *
  page22_i372
#ISCELL
  standard tap *
  page22_i373
#ISCELL
  standard tap *
  page22_i374
#ISCELL
  standard tap *
  page22_i375
#ISCELL
  standard tap *
  page22_i376
#ISCELL
  standard tap *
  page22_i377
#ISCELL
  standard tap *
  page22_i378
#ISCELL
  pure_quanta quanta_title_block_c *
  *
#CELL
  pure_quanta genoa_sp5 *
  page23_i215
#CELL
  pure_quanta genoa_sp5 *
  page23_i216
#ISCELL
  standard offpage *
  page23_i217
#ISCELL
  standard offpage *
  page23_i218
#ISCELL
  mstr_standard tap *
  page23_i219
#ISCELL
  mstr_standard tap *
  page23_i220
#ISCELL
  mstr_standard tap *
  page23_i221
#ISCELL
  mstr_standard tap *
  page23_i222
#ISCELL
  standard tap *
  page23_i223
#ISCELL
  standard tap *
  page23_i224
#ISCELL
  standard tap *
  page23_i225
#ISCELL
  standard tap *
  page23_i226
#ISCELL
  standard tap *
  page23_i227
#ISCELL
  standard tap *
  page23_i228
#ISCELL
  standard tap *
  page23_i229
#ISCELL
  standard tap *
  page23_i230
#ISCELL
  standard tap *
  page23_i231
#ISCELL
  standard tap *
  page23_i232
#ISCELL
  standard tap *
  page23_i233
#ISCELL
  standard tap *
  page23_i234
#ISCELL
  standard tap *
  page23_i235
#ISCELL
  standard tap *
  page23_i236
#ISCELL
  standard tap *
  page23_i237
#ISCELL
  standard tap *
  page23_i238
#ISCELL
  standard tap *
  page23_i239
#ISCELL
  standard tap *
  page23_i240
#ISCELL
  standard tap *
  page23_i241
#ISCELL
  standard tap *
  page23_i242
#ISCELL
  standard tap *
  page23_i243
#ISCELL
  standard tap *
  page23_i244
#ISCELL
  standard tap *
  page23_i245
#ISCELL
  standard tap *
  page23_i246
#ISCELL
  standard tap *
  page23_i247
#ISCELL
  standard tap *
  page23_i248
#ISCELL
  standard tap *
  page23_i249
#ISCELL
  standard tap *
  page23_i250
#ISCELL
  mstr_standard tap *
  page23_i251
#ISCELL
  mstr_standard tap *
  page23_i252
#ISCELL
  mstr_standard tap *
  page23_i253
#ISCELL
  mstr_standard tap *
  page23_i254
#ISCELL
  standard tap *
  page23_i255
#ISCELL
  mstr_standard tap *
  page23_i256
#ISCELL
  standard tap *
  page23_i257
#ISCELL
  standard tap *
  page23_i258
#ISCELL
  standard tap *
  page23_i259
#ISCELL
  standard tap *
  page23_i260
#ISCELL
  standard tap *
  page23_i261
#ISCELL
  standard tap *
  page23_i262
#ISCELL
  standard tap *
  page23_i263
#ISCELL
  standard tap *
  page23_i264
#ISCELL
  standard tap *
  page23_i265
#ISCELL
  standard tap *
  page23_i266
#ISCELL
  standard tap *
  page23_i267
#ISCELL
  standard tap *
  page23_i268
#ISCELL
  standard tap *
  page23_i269
#ISCELL
  standard tap *
  page23_i270
#ISCELL
  standard tap *
  page23_i271
#ISCELL
  standard tap *
  page23_i272
#ISCELL
  standard tap *
  page23_i273
#ISCELL
  standard tap *
  page23_i274
#ISCELL
  standard tap *
  page23_i275
#ISCELL
  standard tap *
  page23_i276
#ISCELL
  standard tap *
  page23_i277
#ISCELL
  standard tap *
  page23_i278
#ISCELL
  standard tap *
  page23_i279
#ISCELL
  standard tap *
  page23_i280
#ISCELL
  standard tap *
  page23_i281
#ISCELL
  standard tap *
  page23_i282
#ISCELL
  standard offpage *
  page23_i283
#ISCELL
  standard offpage *
  page23_i284
#ISCELL
  standard tap *
  page23_i285
#ISCELL
  standard tap *
  page23_i286
#ISCELL
  standard tap *
  page23_i287
#ISCELL
  standard tap *
  page23_i288
#ISCELL
  standard tap *
  page23_i289
#ISCELL
  standard offpage *
  page23_i290
#ISCELL
  standard offpage *
  page23_i291
#ISCELL
  mstr_standard tap *
  page23_i292
#ISCELL
  mstr_standard tap *
  page23_i293
#ISCELL
  mstr_standard tap *
  page23_i294
#ISCELL
  standard tap *
  page23_i295
#ISCELL
  mstr_standard tap *
  page23_i296
#ISCELL
  standard tap *
  page23_i297
#ISCELL
  standard tap *
  page23_i298
#ISCELL
  standard tap *
  page23_i299
#ISCELL
  standard tap *
  page23_i300
#ISCELL
  standard tap *
  page23_i301
#ISCELL
  standard tap *
  page23_i302
#ISCELL
  standard tap *
  page23_i303
#ISCELL
  standard tap *
  page23_i304
#ISCELL
  standard tap *
  page23_i305
#ISCELL
  standard tap *
  page23_i306
#ISCELL
  standard tap *
  page23_i307
#ISCELL
  standard tap *
  page23_i308
#ISCELL
  standard tap *
  page23_i309
#ISCELL
  standard tap *
  page23_i310
#ISCELL
  standard tap *
  page23_i311
#ISCELL
  standard tap *
  page23_i312
#ISCELL
  standard tap *
  page23_i313
#ISCELL
  standard tap *
  page23_i314
#ISCELL
  standard tap *
  page23_i315
#ISCELL
  standard tap *
  page23_i316
#ISCELL
  standard tap *
  page23_i317
#ISCELL
  standard tap *
  page23_i318
#ISCELL
  mstr_standard tap *
  page23_i319
#ISCELL
  mstr_standard tap *
  page23_i320
#ISCELL
  mstr_standard tap *
  page23_i321
#ISCELL
  mstr_standard tap *
  page23_i322
#ISCELL
  standard tap *
  page23_i323
#ISCELL
  mstr_standard tap *
  page23_i324
#ISCELL
  standard tap *
  page23_i325
#ISCELL
  standard tap *
  page23_i326
#ISCELL
  standard tap *
  page23_i327
#ISCELL
  standard tap *
  page23_i328
#ISCELL
  standard tap *
  page23_i329
#ISCELL
  standard tap *
  page23_i330
#ISCELL
  standard tap *
  page23_i331
#ISCELL
  standard tap *
  page23_i332
#ISCELL
  standard tap *
  page23_i333
#ISCELL
  standard tap *
  page23_i334
#ISCELL
  standard tap *
  page23_i335
#ISCELL
  standard tap *
  page23_i336
#ISCELL
  standard tap *
  page23_i337
#ISCELL
  standard offpage *
  page23_i338
#ISCELL
  standard offpage *
  page23_i339
#ISCELL
  standard tap *
  page23_i340
#ISCELL
  standard tap *
  page23_i341
#ISCELL
  standard tap *
  page23_i342
#ISCELL
  standard tap *
  page23_i343
#ISCELL
  standard tap *
  page23_i344
#ISCELL
  standard tap *
  page23_i345
#ISCELL
  standard tap *
  page23_i346
#ISCELL
  standard tap *
  page23_i347
#ISCELL
  standard tap *
  page23_i348
#ISCELL
  standard tap *
  page23_i349
#ISCELL
  standard tap *
  page23_i350
#ISCELL
  standard tap *
  page23_i351
#ISCELL
  standard tap *
  page23_i352
#ISCELL
  pure_quanta quanta_title_block_c *
  *
#CELL
  pure_quanta genoa_sp5 *
  page24_i148
#CELL
  pure_quanta genoa_sp5 *
  page24_i149
#ISCELL
  standard offpage *
  page24_i218
#ISCELL
  standard offpage *
  page24_i219
#ISCELL
  mstr_standard tap *
  page24_i220
#ISCELL
  mstr_standard tap *
  page24_i221
#ISCELL
  mstr_standard tap *
  page24_i222
#ISCELL
  mstr_standard tap *
  page24_i223
#ISCELL
  standard tap *
  page24_i224
#ISCELL
  standard tap *
  page24_i225
#ISCELL
  standard tap *
  page24_i226
#ISCELL
  standard tap *
  page24_i227
#ISCELL
  standard tap *
  page24_i228
#ISCELL
  standard tap *
  page24_i229
#ISCELL
  standard tap *
  page24_i230
#ISCELL
  standard tap *
  page24_i231
#ISCELL
  standard tap *
  page24_i232
#ISCELL
  standard tap *
  page24_i233
#ISCELL
  standard tap *
  page24_i234
#ISCELL
  standard tap *
  page24_i235
#ISCELL
  standard tap *
  page24_i236
#ISCELL
  standard tap *
  page24_i237
#ISCELL
  standard tap *
  page24_i238
#ISCELL
  standard tap *
  page24_i239
#ISCELL
  standard tap *
  page24_i240
#ISCELL
  standard tap *
  page24_i241
#ISCELL
  standard tap *
  page24_i242
#ISCELL
  standard tap *
  page24_i243
#ISCELL
  standard tap *
  page24_i244
#ISCELL
  standard tap *
  page24_i245
#ISCELL
  standard tap *
  page24_i246
#ISCELL
  standard tap *
  page24_i247
#ISCELL
  standard tap *
  page24_i248
#ISCELL
  standard tap *
  page24_i249
#ISCELL
  standard tap *
  page24_i250
#ISCELL
  standard tap *
  page24_i251
#ISCELL
  standard tap *
  page24_i292
#ISCELL
  standard tap *
  page24_i293
#ISCELL
  standard tap *
  page24_i294
#ISCELL
  standard tap *
  page24_i295
#ISCELL
  standard tap *
  page24_i296
#ISCELL
  standard tap *
  page24_i297
#ISCELL
  standard tap *
  page24_i298
#ISCELL
  standard tap *
  page24_i299
#ISCELL
  standard tap *
  page24_i300
#ISCELL
  standard tap *
  page24_i301
#ISCELL
  standard tap *
  page24_i302
#ISCELL
  standard tap *
  page24_i303
#ISCELL
  standard tap *
  page24_i304
#ISCELL
  standard tap *
  page24_i305
#ISCELL
  standard offpage *
  page24_i306
#ISCELL
  standard offpage *
  page24_i307
#ISCELL
  standard tap *
  page24_i308
#ISCELL
  standard tap *
  page24_i309
#ISCELL
  standard tap *
  page24_i310
#ISCELL
  standard tap *
  page24_i311
#ISCELL
  standard tap *
  page24_i312
#ISCELL
  standard tap *
  page24_i313
#ISCELL
  standard tap *
  page24_i314
#ISCELL
  standard tap *
  page24_i315
#ISCELL
  standard tap *
  page24_i316
#ISCELL
  standard tap *
  page24_i317
#ISCELL
  standard tap *
  page24_i318
#ISCELL
  standard tap *
  page24_i319
#ISCELL
  mstr_standard tap *
  page24_i320
#ISCELL
  standard tap *
  page24_i321
#ISCELL
  mstr_standard tap *
  page24_i322
#ISCELL
  mstr_standard tap *
  page24_i323
#ISCELL
  mstr_standard tap *
  page24_i324
#ISCELL
  mstr_standard tap *
  page24_i325
#ISCELL
  standard tap *
  page24_i326
#ISCELL
  standard tap *
  page24_i327
#ISCELL
  mstr_standard tap *
  page24_i328
#ISCELL
  mstr_standard tap *
  page24_i329
#ISCELL
  mstr_standard tap *
  page24_i330
#ISCELL
  standard tap *
  page24_i331
#ISCELL
  mstr_standard tap *
  page24_i332
#ISCELL
  mstr_standard tap *
  page24_i333
#ISCELL
  standard tap *
  page24_i334
#ISCELL
  standard tap *
  page24_i335
#ISCELL
  standard tap *
  page24_i336
#ISCELL
  standard tap *
  page24_i337
#ISCELL
  standard tap *
  page24_i338
#ISCELL
  standard tap *
  page24_i339
#ISCELL
  standard tap *
  page24_i340
#ISCELL
  standard tap *
  page24_i341
#ISCELL
  standard tap *
  page24_i342
#ISCELL
  standard tap *
  page24_i343
#ISCELL
  standard tap *
  page24_i344
#ISCELL
  standard tap *
  page24_i345
#ISCELL
  standard tap *
  page24_i346
#ISCELL
  standard tap *
  page24_i347
#ISCELL
  standard tap *
  page24_i348
#ISCELL
  standard tap *
  page24_i349
#ISCELL
  standard tap *
  page24_i350
#ISCELL
  standard tap *
  page24_i351
#ISCELL
  standard tap *
  page24_i352
#ISCELL
  standard tap *
  page24_i353
#ISCELL
  standard tap *
  page24_i354
#ISCELL
  standard tap *
  page24_i355
#ISCELL
  standard tap *
  page24_i356
#ISCELL
  standard tap *
  page24_i357
#ISCELL
  standard offpage *
  page24_i358
#ISCELL
  standard offpage *
  page24_i359
#ISCELL
  mstr_standard tap *
  page24_i360
#ISCELL
  mstr_standard tap *
  page24_i361
#ISCELL
  standard tap *
  page24_i362
#ISCELL
  mstr_standard tap *
  page24_i363
#ISCELL
  mstr_standard tap *
  page24_i364
#ISCELL
  standard tap *
  page24_i365
#ISCELL
  standard tap *
  page24_i366
#ISCELL
  standard tap *
  page24_i367
#ISCELL
  standard tap *
  page24_i368
#ISCELL
  standard tap *
  page24_i369
#ISCELL
  standard tap *
  page24_i370
#ISCELL
  standard tap *
  page24_i371
#ISCELL
  standard tap *
  page24_i372
#ISCELL
  standard tap *
  page24_i373
#ISCELL
  standard tap *
  page24_i374
#ISCELL
  standard tap *
  page24_i375
#ISCELL
  standard tap *
  page24_i376
#ISCELL
  standard tap *
  page24_i377
#ISCELL
  standard tap *
  page24_i378
#ISCELL
  standard tap *
  page24_i379
#ISCELL
  standard tap *
  page24_i380
#ISCELL
  standard tap *
  page24_i381
#ISCELL
  standard tap *
  page24_i382
#ISCELL
  standard tap *
  page24_i383
#ISCELL
  standard tap *
  page24_i384
#ISCELL
  standard tap *
  page24_i385
#ISCELL
  standard tap *
  page24_i386
#ISCELL
  standard tap *
  page24_i387
#ISCELL
  standard tap *
  page24_i388
#ISCELL
  standard tap *
  page24_i389
#ISCELL
  standard tap *
  page24_i390
#ISCELL
  standard tap *
  page24_i391
#ISCELL
  standard offpage *
  page24_i392
#ISCELL
  standard offpage *
  page24_i393
#ISCELL
  pure_quanta quanta_title_block_c *
  *
#CELL
  pure_quanta genoa_sp5 *
  page25_i147
#CELL
  pure_quanta genoa_sp5 *
  page25_i148
#ISCELL
  standard offpage *
  page25_i149
#ISCELL
  standard offpage *
  page25_i150
#ISCELL
  mstr_standard tap *
  page25_i151
#ISCELL
  mstr_standard tap *
  page25_i152
#ISCELL
  mstr_standard tap *
  page25_i153
#ISCELL
  mstr_standard tap *
  page25_i154
#ISCELL
  standard tap *
  page25_i155
#ISCELL
  standard tap *
  page25_i156
#ISCELL
  standard tap *
  page25_i157
#ISCELL
  standard tap *
  page25_i158
#ISCELL
  standard tap *
  page25_i159
#ISCELL
  standard tap *
  page25_i160
#ISCELL
  standard tap *
  page25_i161
#ISCELL
  standard tap *
  page25_i162
#ISCELL
  standard tap *
  page25_i163
#ISCELL
  standard tap *
  page25_i164
#ISCELL
  standard tap *
  page25_i165
#ISCELL
  standard tap *
  page25_i166
#ISCELL
  standard tap *
  page25_i167
#ISCELL
  standard tap *
  page25_i168
#ISCELL
  standard tap *
  page25_i169
#ISCELL
  standard tap *
  page25_i170
#ISCELL
  standard tap *
  page25_i171
#ISCELL
  standard tap *
  page25_i172
#ISCELL
  standard tap *
  page25_i173
#ISCELL
  standard tap *
  page25_i174
#ISCELL
  standard tap *
  page25_i175
#ISCELL
  standard tap *
  page25_i176
#ISCELL
  standard tap *
  page25_i177
#ISCELL
  standard tap *
  page25_i178
#ISCELL
  standard tap *
  page25_i179
#ISCELL
  standard tap *
  page25_i180
#ISCELL
  standard tap *
  page25_i181
#ISCELL
  standard tap *
  page25_i182
#ISCELL
  mstr_standard tap *
  page25_i325
#ISCELL
  mstr_standard tap *
  page25_i326
#ISCELL
  mstr_standard tap *
  page25_i327
#ISCELL
  mstr_standard tap *
  page25_i328
#ISCELL
  mstr_standard tap *
  page25_i329
#ISCELL
  standard tap *
  page25_i330
#ISCELL
  standard tap *
  page25_i331
#ISCELL
  standard tap *
  page25_i332
#ISCELL
  standard tap *
  page25_i333
#ISCELL
  standard tap *
  page25_i334
#ISCELL
  standard tap *
  page25_i335
#ISCELL
  standard tap *
  page25_i336
#ISCELL
  standard tap *
  page25_i337
#ISCELL
  standard tap *
  page25_i338
#ISCELL
  standard tap *
  page25_i339
#ISCELL
  standard tap *
  page25_i340
#ISCELL
  standard tap *
  page25_i341
#ISCELL
  standard tap *
  page25_i342
#ISCELL
  standard tap *
  page25_i343
#ISCELL
  standard tap *
  page25_i344
#ISCELL
  standard tap *
  page25_i345
#ISCELL
  standard tap *
  page25_i346
#ISCELL
  standard tap *
  page25_i347
#ISCELL
  standard tap *
  page25_i348
#ISCELL
  standard tap *
  page25_i349
#ISCELL
  standard tap *
  page25_i350
#ISCELL
  standard tap *
  page25_i351
#ISCELL
  standard tap *
  page25_i352
#ISCELL
  standard tap *
  page25_i353
#ISCELL
  standard tap *
  page25_i354
#ISCELL
  standard tap *
  page25_i355
#ISCELL
  standard tap *
  page25_i356
#ISCELL
  standard offpage *
  page25_i357
#ISCELL
  standard offpage *
  page25_i358
#ISCELL
  mstr_standard tap *
  page25_i359
#ISCELL
  mstr_standard tap *
  page25_i360
#ISCELL
  mstr_standard tap *
  page25_i361
#ISCELL
  mstr_standard tap *
  page25_i362
#ISCELL
  mstr_standard tap *
  page25_i363
#ISCELL
  standard tap *
  page25_i364
#ISCELL
  standard tap *
  page25_i365
#ISCELL
  standard tap *
  page25_i366
#ISCELL
  standard tap *
  page25_i367
#ISCELL
  standard tap *
  page25_i368
#ISCELL
  standard tap *
  page25_i369
#ISCELL
  standard tap *
  page25_i370
#ISCELL
  standard tap *
  page25_i371
#ISCELL
  standard tap *
  page25_i372
#ISCELL
  standard tap *
  page25_i373
#ISCELL
  standard tap *
  page25_i374
#ISCELL
  standard tap *
  page25_i375
#ISCELL
  standard tap *
  page25_i376
#ISCELL
  standard tap *
  page25_i377
#ISCELL
  standard tap *
  page25_i378
#ISCELL
  standard tap *
  page25_i379
#ISCELL
  standard tap *
  page25_i380
#ISCELL
  standard tap *
  page25_i381
#ISCELL
  standard tap *
  page25_i382
#ISCELL
  standard tap *
  page25_i383
#ISCELL
  standard tap *
  page25_i384
#ISCELL
  standard tap *
  page25_i385
#ISCELL
  standard tap *
  page25_i386
#ISCELL
  standard tap *
  page25_i387
#ISCELL
  standard tap *
  page25_i388
#ISCELL
  standard tap *
  page25_i389
#ISCELL
  standard tap *
  page25_i390
#ISCELL
  standard offpage *
  page25_i391
#ISCELL
  standard offpage *
  page25_i392
#ISCELL
  mstr_standard tap *
  page25_i393
#ISCELL
  mstr_standard tap *
  page25_i394
#ISCELL
  mstr_standard tap *
  page25_i395
#ISCELL
  mstr_standard tap *
  page25_i396
#ISCELL
  standard tap *
  page25_i397
#ISCELL
  standard tap *
  page25_i398
#ISCELL
  standard tap *
  page25_i399
#ISCELL
  standard tap *
  page25_i400
#ISCELL
  standard tap *
  page25_i401
#ISCELL
  standard tap *
  page25_i402
#ISCELL
  standard tap *
  page25_i403
#ISCELL
  standard tap *
  page25_i404
#ISCELL
  standard tap *
  page25_i405
#ISCELL
  standard tap *
  page25_i406
#ISCELL
  standard tap *
  page25_i407
#ISCELL
  standard tap *
  page25_i408
#ISCELL
  standard tap *
  page25_i409
#ISCELL
  standard tap *
  page25_i410
#ISCELL
  standard tap *
  page25_i411
#ISCELL
  standard tap *
  page25_i412
#ISCELL
  standard tap *
  page25_i413
#ISCELL
  standard tap *
  page25_i414
#ISCELL
  standard tap *
  page25_i415
#ISCELL
  standard tap *
  page25_i416
#ISCELL
  standard tap *
  page25_i417
#ISCELL
  standard tap *
  page25_i418
#ISCELL
  standard tap *
  page25_i419
#ISCELL
  standard tap *
  page25_i420
#ISCELL
  standard tap *
  page25_i421
#ISCELL
  standard tap *
  page25_i422
#ISCELL
  standard tap *
  page25_i423
#ISCELL
  standard tap *
  page25_i424
#ISCELL
  standard offpage *
  page25_i425
#ISCELL
  standard offpage *
  page25_i426
#ISCELL
  pure_quanta quanta_title_block_c *
  *
#ISCELL
  standard offpage *
  page26_i104
#ISCELL
  standard offpage *
  page26_i105
#ISCELL
  standard offpage *
  page26_i117
#ISCELL
  standard offpage *
  page26_i118
#ISCELL
  standard tap *
  page26_i131
#ISCELL
  standard tap *
  page26_i132
#ISCELL
  standard tap *
  page26_i133
#ISCELL
  standard tap *
  page26_i134
#ISCELL
  standard tap *
  page26_i136
#ISCELL
  standard tap *
  page26_i137
#ISCELL
  standard tap *
  page26_i138
#ISCELL
  standard tap *
  page26_i139
#ISCELL
  standard tap *
  page26_i141
#ISCELL
  standard tap *
  page26_i142
#ISCELL
  standard tap *
  page26_i143
#ISCELL
  standard tap *
  page26_i144
#ISCELL
  standard tap *
  page26_i146
#ISCELL
  standard tap *
  page26_i147
#ISCELL
  standard tap *
  page26_i148
#ISCELL
  standard tap *
  page26_i149
#ISCELL
  standard offpage *
  page26_i150
#ISCELL
  standard offpage *
  page26_i151
#ISCELL
  standard offpage *
  page26_i154
#ISCELL
  standard offpage *
  page26_i155
#CELL
  pure_quanta q_cap_diffbus *
  page26_i156
#CELL
  pure_quanta q_cap_diffbus *
  page26_i157
#ISCELL
  standard offpage *
  page26_i158
#ISCELL
  standard offpage *
  page26_i159
#CELL
  pure_quanta genoa_sp5 *
  page26_i59
#ISCELL
  standard offpage *
  page26_i86
#ISCELL
  standard offpage *
  page26_i87
#ISCELL
  mstr_misc dns *
  *
#ISCELL
  pure_quanta quanta_title_block_c *
  *
#ISCELL
  standard offpage *
  page27_i10
#ISCELL
  pure_quanta_power universal_power *
  page27_i100
#ISCELL
  standard offpage *
  page27_i11
#ISCELL
  standard offpage *
  page27_i12
#ISCELL
  standard offpage *
  page27_i13
#ISCELL
  standard offpage *
  page27_i14
#ISCELL
  standard offpage *
  page27_i169
#CELL
  pure_quanta q_res *
  page27_i170
#ISCELL
  standard offpage *
  page27_i191
#CELL
  pure_quanta genoa_sp5 *
  page27_i227
#ISCELL
  pure_quanta_power universal_power *
  page27_i231
#ISCELL
  standard offpage *
  page27_i245
#ISCELL
  standard offpage *
  page27_i246
#ISCELL
  standard offpage *
  page27_i247
#ISCELL
  standard offpage *
  page27_i248
#ISCELL
  standard offpage *
  page27_i249
#ISCELL
  standard offpage *
  page27_i250
#ISCELL
  standard offpage *
  page27_i251
#ISCELL
  standard offpage *
  page27_i252
#ISCELL
  standard offpage *
  page27_i253
#ISCELL
  standard offpage *
  page27_i254
#ISCELL
  standard offpage *
  page27_i255
#ISCELL
  standard offpage *
  page27_i257
#ISCELL
  standard offpage *
  page27_i263
#ISCELL
  standard offpage *
  page27_i264
#ISCELL
  standard offpage *
  page27_i273
#ISCELL
  standard offpage *
  page27_i274
#ISCELL
  standard offpage *
  page27_i275
#ISCELL
  standard offpage *
  page27_i276
#ISCELL
  standard offpage *
  page27_i277
#ISCELL
  standard offpage *
  page27_i278
#CELL
  pure_quanta q_res *
  page27_i279
#ISCELL
  standard offpage *
  page27_i283
#ISCELL
  standard offpage *
  page27_i284
#ISCELL
  standard offpage *
  page27_i285
#ISCELL
  standard offpage *
  page27_i286
#CELL
  pure_quanta q_res *
  page27_i288
#ISCELL
  pure_quanta_power universal_power *
  page27_i293
#CELL
  pure_quanta q_res *
  page27_i294
#CELL
  pure_quanta q_cap *
  page27_i295
#CELL
  pure_quanta q_res *
  page27_i296
#CELL
  pure_quanta q_cap *
  page27_i297
#ISCELL
  pure_quanta_power gnd *
  page27_i298
#ISCELL
  pure_quanta_power gnd *
  page27_i299
#CELL
  pure_quanta q_res *
  page27_i300
#CELL
  pure_quanta q_res *
  page27_i301
#CELL
  pure_quanta q_cap *
  page27_i302
#CELL
  pure_quanta q_cap *
  page27_i303
#CELL
  pure_quanta q_res *
  page27_i304
#CELL
  pure_quanta q_res *
  page27_i305
#CELL
  pure_quanta q_cap *
  page27_i306
#CELL
  pure_quanta q_cap *
  page27_i307
#ISCELL
  pure_quanta_power gnd *
  page27_i308
#ISCELL
  pure_quanta_power gnd *
  page27_i309
#ISCELL
  pure_quanta_power gnd *
  page27_i310
#ISCELL
  pure_quanta_power gnd *
  page27_i311
#ISCELL
  standard offpage *
  page27_i312
#ISCELL
  standard offpage *
  page27_i313
#ISCELL
  standard offpage *
  page27_i314
#ISCELL
  standard offpage *
  page27_i315
#ISCELL
  standard offpage *
  page27_i316
#ISCELL
  standard offpage *
  page27_i317
#CELL
  pure_quanta q_res *
  page27_i318
#CELL
  pure_quanta q_res *
  page27_i319
#ISCELL
  standard offpage *
  page27_i320
#ISCELL
  standard offpage *
  page27_i321
#CELL
  pure_quanta q_res *
  page27_i322
#CELL
  pure_quanta q_res *
  page27_i323
#ISCELL
  standard offpage *
  page27_i324
#ISCELL
  standard offpage *
  page27_i325
#CELL
  pure_quanta q_res *
  page27_i334
#CELL
  pure_quanta q_res *
  page27_i335
#CELL
  pure_quanta q_res *
  page27_i336
#CELL
  pure_quanta q_res *
  page27_i337
#ISCELL
  standard offpage *
  page27_i338
#ISCELL
  standard offpage *
  page27_i339
#ISCELL
  standard offpage *
  page27_i340
#ISCELL
  standard offpage *
  page27_i341
#ISCELL
  standard offpage *
  page27_i342
#ISCELL
  standard offpage *
  page27_i343
#ISCELL
  standard offpage *
  page27_i344
#ISCELL
  standard offpage *
  page27_i345
#CELL
  pure_quanta q_res *
  page27_i346
#CELL
  pure_quanta q_res *
  page27_i347
#CELL
  pure_quanta q_res *
  page27_i348
#CELL
  pure_quanta q_res *
  page27_i349
#ISCELL
  standard offpage *
  page27_i352
#CELL
  pure_quanta q_res *
  page27_i353
#CELL
  pure_quanta tp *
  page27_i355
#CELL
  pure_quanta tp *
  page27_i356
#CELL
  pure_quanta tp *
  page27_i357
#CELL
  pure_quanta tp *
  page27_i358
#CELL
  pure_quanta tp *
  page27_i359
#CELL
  pure_quanta tp *
  page27_i360
#CELL
  pure_quanta tp *
  page27_i361
#CELL
  pure_quanta tp *
  page27_i362
#ISCELL
  pure_quanta_power universal_gnd *
  page27_i364
#ISCELL
  pure_quanta_power universal_gnd *
  page27_i365
#ISCELL
  pure_quanta_power universal_power *
  page27_i366
#ISCELL
  standard offpage *
  page27_i374
#ISCELL
  standard offpage *
  page27_i375
#ISCELL
  standard offpage *
  page27_i376
#CELL
  pure_quanta q_res *
  page27_i377
#CELL
  pure_quanta q_res *
  page27_i378
#CELL
  pure_quanta q_res *
  page27_i379
#CELL
  pure_quanta q_res *
  page27_i380
#CELL
  pure_quanta q_res *
  page27_i381
#CELL
  pure_quanta q_res *
  page27_i382
#CELL
  pure_quanta q_res *
  page27_i383
#CELL
  pure_quanta q_res *
  page27_i384
#CELL
  pure_quanta q_res *
  page27_i385
#CELL
  pure_quanta q_res *
  page27_i386
#CELL
  pure_quanta q_res *
  page27_i387
#CELL
  pure_quanta q_res *
  page27_i388
#CELL
  pure_quanta q_res *
  page27_i389
#CELL
  pure_quanta q_res *
  page27_i390
#CELL
  pure_quanta q_res *
  page27_i391
#CELL
  pure_quanta q_res *
  page27_i392
#CELL
  pure_quanta q_res *
  page27_i393
#CELL
  pure_quanta q_res *
  page27_i394
#CELL
  pure_quanta q_res *
  page27_i395
#CELL
  pure_quanta q_res *
  page27_i396
#CELL
  pure_quanta q_res *
  page27_i397
#ISCELL
  standard offpage *
  page27_i398
#CELL
  pure_quanta q_res *
  page27_i399
#ISCELL
  standard offpage *
  page27_i400
#CELL
  pure_quanta q_res *
  page27_i401
#CELL
  pure_quanta tp *
  page27_i403
#CELL
  pure_quanta tp *
  page27_i404
#ISCELL
  standard offpage *
  page27_i405
#ISCELL
  standard offpage *
  page27_i406
#ISCELL
  pure_quanta_power universal_power *
  page27_i408
#ISCELL
  pure_quanta_power universal_gnd *
  page27_i410
#ISCELL
  standard offpage *
  page27_i415
#ISCELL
  standard offpage *
  page27_i416
#ISCELL
  standard offpage *
  page27_i417
#ISCELL
  standard offpage *
  page27_i418
#ISCELL
  standard offpage *
  page27_i419
#ISCELL
  standard offpage *
  page27_i420
#ISCELL
  standard offpage *
  page27_i421
#ISCELL
  standard offpage *
  page27_i422
#CELL
  pure_quanta conn10_hbc1051l300d8h *
  page27_i423
#CELL
  pure_quanta sconn8_g802m0083150rd3hr *
  page27_i424
#CELL
  pure_quanta sconn8_g802m0083150rd3hr *
  page27_i425
#CELL
  pure_quanta q_res *
  page27_i427
#CELL
  pure_quanta q_res *
  page27_i428
#CELL
  pure_quanta q_res *
  page27_i429
#ISCELL
  standard offpage *
  page27_i43
#ISCELL
  standard offpage *
  page27_i46
#ISCELL
  standard offpage *
  page27_i47
#ISCELL
  standard offpage *
  page27_i50
#ISCELL
  standard offpage *
  page27_i51
#ISCELL
  standard offpage *
  page27_i53
#ISCELL
  standard offpage *
  page27_i54
#ISCELL
  standard offpage *
  page27_i55
#ISCELL
  standard offpage *
  page27_i56
#ISCELL
  standard offpage *
  page27_i57
#ISCELL
  standard offpage *
  page27_i62
#ISCELL
  standard offpage *
  page27_i63
#ISCELL
  standard offpage *
  page27_i67
#ISCELL
  standard offpage *
  page27_i68
#ISCELL
  standard offpage *
  page27_i69
#ISCELL
  standard offpage *
  page27_i70
#ISCELL
  standard offpage *
  page27_i71
#ISCELL
  standard offpage *
  page27_i72
#ISCELL
  standard offpage *
  page27_i73
#ISCELL
  standard offpage *
  page27_i74
#ISCELL
  standard offpage *
  page27_i75
#ISCELL
  standard offpage *
  page27_i79
#ISCELL
  standard offpage *
  page27_i80
#ISCELL
  standard offpage *
  page27_i81
#ISCELL
  standard offpage *
  page27_i82
#ISCELL
  standard offpage *
  page27_i85
#ISCELL
  standard offpage *
  page27_i86
#ISCELL
  standard offpage *
  page27_i87
#ISCELL
  standard offpage *
  page27_i88
#ISCELL
  standard offpage *
  page27_i92
#ISCELL
  standard offpage *
  page27_i93
#ISCELL
  pure_quanta_power gnd *
  page27_i95
#ISCELL
  pure_quanta_power gnd *
  page27_i96
#ISCELL
  mstr_misc dns *
  *
#ISCELL
  pure_quanta quanta_title_block_c *
  *
#ISCELL
  pure_quanta_power design_note *
  *
#ISCELL
  standard offpage *
  page28_i1
#ISCELL
  standard offpage *
  page28_i10
#CELL
  pure_quanta q_res *
  page28_i100
#ISCELL
  standard offpage *
  page28_i101
#ISCELL
  pure_quanta_power universal_gnd *
  page28_i102
#CELL
  pure_quanta q_xtal_4p_13bi_24gnd *
  page28_i103
#CELL
  pure_quanta q_res *
  page28_i104
#ISCELL
  pure_quanta_power universal_gnd *
  page28_i105
#ISCELL
  pure_quanta_power universal_gnd *
  page28_i106
#ISCELL
  standard offpage *
  page28_i108
#ISCELL
  standard offpage *
  page28_i109
#ISCELL
  standard offpage *
  page28_i11
#ISCELL
  standard offpage *
  page28_i112
#ISCELL
  standard offpage *
  page28_i113
#ISCELL
  standard offpage *
  page28_i114
#ISCELL
  standard offpage *
  page28_i115
#ISCELL
  standard offpage *
  page28_i116
#ISCELL
  standard offpage *
  page28_i117
#ISCELL
  standard offpage *
  page28_i118
#ISCELL
  standard offpage *
  page28_i119
#ISCELL
  standard offpage *
  page28_i12
#ISCELL
  standard offpage *
  page28_i120
#ISCELL
  standard offpage *
  page28_i124
#ISCELL
  standard offpage *
  page28_i125
#ISCELL
  standard offpage *
  page28_i126
#ISCELL
  standard offpage *
  page28_i127
#ISCELL
  standard offpage *
  page28_i128
#ISCELL
  standard offpage *
  page28_i129
#ISCELL
  standard offpage *
  page28_i13
#ISCELL
  standard offpage *
  page28_i130
#ISCELL
  standard offpage *
  page28_i131
#ISCELL
  standard offpage *
  page28_i132
#ISCELL
  standard offpage *
  page28_i133
#ISCELL
  standard offpage *
  page28_i134
#CELL
  pure_quanta q_res *
  page28_i135
#CELL
  pure_quanta q_res *
  page28_i136
#ISCELL
  pure_quanta_power universal_gnd *
  page28_i137
#CELL
  pure_quanta q_crystal *
  page28_i140
#ISCELL
  pure_quanta_power universal_gnd *
  page28_i141
#ISCELL
  standard offpage *
  page28_i143
#ISCELL
  standard offpage *
  page28_i144
#ISCELL
  standard offpage *
  page28_i145
#ISCELL
  standard offpage *
  page28_i146
#ISCELL
  standard offpage *
  page28_i147
#ISCELL
  standard offpage *
  page28_i148
#ISCELL
  standard offpage *
  page28_i150
#CELL
  pure_quanta q_res *
  page28_i151
#CELL
  pure_quanta q_res *
  page28_i152
#CELL
  pure_quanta q_res *
  page28_i153
#CELL
  pure_quanta q_res *
  page28_i154
#CELL
  pure_quanta q_res *
  page28_i155
#CELL
  pure_quanta q_res *
  page28_i156
#CELL
  pure_quanta q_res *
  page28_i157
#CELL
  pure_quanta q_res *
  page28_i158
#ISCELL
  standard offpage *
  page28_i159
#ISCELL
  standard offpage *
  page28_i16
#CELL
  pure_quanta q_res *
  page28_i160
#CELL
  pure_quanta q_res *
  page28_i161
#ISCELL
  standard offpage *
  page28_i162
#ISCELL
  standard offpage *
  page28_i163
#ISCELL
  standard offpage *
  page28_i164
#CELL
  pure_quanta q_res *
  page28_i165
#ISCELL
  standard offpage *
  page28_i166
#CELL
  pure_quanta q_res *
  page28_i167
#CELL
  pure_quanta q_res *
  page28_i168
#ISCELL
  standard offpage *
  page28_i169
#ISCELL
  standard offpage *
  page28_i170
#CELL
  pure_quanta q_res *
  page28_i171
#CELL
  pure_quanta q_res *
  page28_i172
#ISCELL
  standard offpage *
  page28_i173
#ISCELL
  standard offpage *
  page28_i174
#ISCELL
  standard offpage *
  page28_i175
#ISCELL
  standard offpage *
  page28_i176
#ISCELL
  standard offpage *
  page28_i177
#ISCELL
  standard offpage *
  page28_i178
#ISCELL
  standard offpage *
  page28_i179
#ISCELL
  standard offpage *
  page28_i18
#ISCELL
  standard offpage *
  page28_i180
#ISCELL
  standard offpage *
  page28_i181
#ISCELL
  standard offpage *
  page28_i182
#ISCELL
  standard offpage *
  page28_i183
#ISCELL
  standard offpage *
  page28_i184
#ISCELL
  standard offpage *
  page28_i185
#ISCELL
  standard offpage *
  page28_i186
#ISCELL
  standard offpage *
  page28_i187
#CELL
  pure_quanta genoa_sp5 *
  page28_i188
#ISCELL
  standard offpage *
  page28_i189
#ISCELL
  standard offpage *
  page28_i19
#ISCELL
  standard offpage *
  page28_i190
#CELL
  pure_quanta q_res *
  page28_i191
#CELL
  pure_quanta q_res *
  page28_i192
#ISCELL
  pure_quanta_power universal_gnd *
  page28_i193
#CELL
  pure_quanta q_cap *
  page28_i194
#CELL
  pure_quanta q_res *
  page28_i195
#ISCELL
  standard offpage *
  page28_i2
#ISCELL
  standard offpage *
  page28_i20
#CELL
  pure_quanta q_res *
  page28_i206
#CELL
  pure_quanta q_res *
  page28_i207
#CELL
  pure_quanta q_res *
  page28_i208
#CELL
  pure_quanta q_res *
  page28_i209
#ISCELL
  standard offpage *
  page28_i21
#CELL
  pure_quanta q_res *
  page28_i210
#ISCELL
  pure_quanta_power vcc_core *
  page28_i211
#CELL
  pure_quanta q_res *
  page28_i212
#CELL
  pure_quanta q_res *
  page28_i213
#CELL
  pure_quanta q_res *
  page28_i214
#ISCELL
  standard offpage *
  page28_i215
#ISCELL
  standard offpage *
  page28_i216
#ISCELL
  standard offpage *
  page28_i217
#ISCELL
  standard offpage *
  page28_i218
#ISCELL
  standard offpage *
  page28_i219
#CELL
  pure_quanta q_res *
  page28_i22
#ISCELL
  standard offpage *
  page28_i220
#CELL
  pure_quanta q_res *
  page28_i221
#CELL
  pure_quanta q_res *
  page28_i222
#ISCELL
  standard offpage *
  page28_i223
#CELL
  pure_quanta q_res *
  page28_i224
#ISCELL
  pure_quanta_power universal_gnd *
  page28_i225
#ISCELL
  standard offpage *
  page28_i226
#ISCELL
  standard offpage *
  page28_i227
#CELL
  pure_quanta q_res *
  page28_i228
#CELL
  pure_quanta q_res *
  page28_i229
#CELL
  pure_quanta q_res *
  page28_i23
#CELL
  pure_quanta q_cap *
  page28_i230
#CELL
  pure_quanta q_cap *
  page28_i231
#CELL
  pure_quanta q_cap *
  page28_i232
#CELL
  pure_quanta q_cap *
  page28_i233
#CELL
  pure_quanta q_res *
  page28_i24
#CELL
  pure_quanta q_res *
  page28_i25
#ISCELL
  pure_quanta_power vcc_core *
  page28_i26
#ISCELL
  pure_quanta_power universal_gnd *
  page28_i27
#CELL
  pure_quanta conn6_hbc1031l200d8h *
  page28_i28
#CELL
  pure_quanta q_res *
  page28_i29
#ISCELL
  standard offpage *
  page28_i3
#CELL
  pure_quanta q_res *
  page28_i30
#ISCELL
  pure_quanta_power universal_power *
  page28_i31
#ISCELL
  pure_quanta_power universal_gnd *
  page28_i32
#CELL
  pure_quanta q_res *
  page28_i33
#CELL
  pure_quanta q_res *
  page28_i34
#ISCELL
  pure_quanta_power universal_gnd *
  page28_i35
#CELL
  pure_quanta q_res *
  page28_i36
#CELL
  pure_quanta q_res *
  page28_i37
#ISCELL
  pure_quanta_power universal_gnd *
  page28_i38
#ISCELL
  pure_quanta_power universal_gnd *
  page28_i39
#ISCELL
  standard offpage *
  page28_i4
#CELL
  pure_quanta q_res *
  page28_i40
#CELL
  pure_quanta q_res *
  page28_i41
#CELL
  pure_quanta q_res *
  page28_i42
#CELL
  pure_quanta q_res *
  page28_i43
#CELL
  pure_quanta q_res *
  page28_i44
#CELL
  pure_quanta q_res *
  page28_i45
#CELL
  pure_quanta q_res *
  page28_i46
#CELL
  pure_quanta q_res *
  page28_i47
#CELL
  pure_quanta q_res *
  page28_i48
#CELL
  pure_quanta q_res *
  page28_i49
#ISCELL
  standard offpage *
  page28_i5
#CELL
  pure_quanta q_res *
  page28_i53
#CELL
  pure_quanta q_res *
  page28_i55
#CELL
  pure_quanta q_res *
  page28_i56
#ISCELL
  pure_quanta_power universal_power *
  page28_i57
#ISCELL
  pure_quanta_power universal_gnd *
  page28_i58
#CELL
  pure_quanta q_res *
  page28_i59
#ISCELL
  standard offpage *
  page28_i6
#CELL
  pure_quanta q_res *
  page28_i60
#ISCELL
  pure_quanta_power universal_gnd *
  page28_i61
#CELL
  pure_quanta q_res *
  page28_i62
#ISCELL
  pure_quanta_power universal_gnd *
  page28_i63
#CELL
  pure_quanta q_res *
  page28_i64
#CELL
  pure_quanta q_res *
  page28_i65
#CELL
  pure_quanta q_res *
  page28_i66
#ISCELL
  pure_quanta_power universal_gnd *
  page28_i68
#CELL
  pure_quanta q_res *
  page28_i69
#ISCELL
  standard offpage *
  page28_i7
#ISCELL
  standard offpage *
  page28_i70
#ISCELL
  standard offpage *
  page28_i71
#ISCELL
  standard offpage *
  page28_i72
#ISCELL
  standard offpage *
  page28_i73
#ISCELL
  pure_quanta_power universal_power *
  page28_i74
#ISCELL
  standard offpage *
  page28_i75
#ISCELL
  standard offpage *
  page28_i76
#ISCELL
  standard offpage *
  page28_i77
#ISCELL
  standard offpage *
  page28_i78
#ISCELL
  standard offpage *
  page28_i79
#ISCELL
  standard offpage *
  page28_i8
#ISCELL
  standard offpage *
  page28_i80
#ISCELL
  standard offpage *
  page28_i81
#ISCELL
  standard offpage *
  page28_i83
#ISCELL
  standard offpage *
  page28_i85
#ISCELL
  standard offpage *
  page28_i86
#ISCELL
  standard offpage *
  page28_i89
#ISCELL
  standard offpage *
  page28_i9
#ISCELL
  standard offpage *
  page28_i90
#ISCELL
  standard offpage *
  page28_i91
#ISCELL
  standard offpage *
  page28_i92
#CELL
  pure_quanta q_res *
  page28_i93
#CELL
  pure_quanta q_res *
  page28_i94
#CELL
  pure_quanta q_res *
  page28_i95
#CELL
  pure_quanta q_res *
  page28_i96
#CELL
  pure_quanta q_res *
  page28_i97
#CELL
  pure_quanta q_res *
  page28_i98
#ISCELL
  mstr_misc dns *
  *
#ISCELL
  pure_quanta quanta_title_block_c *
  *
#ISCELL
  standard offpage *
  page29_i276
#ISCELL
  pure_quanta_power universal_power *
  page29_i277
#ISCELL
  standard offpage *
  page29_i280
#CELL
  pure_quanta q_res *
  page29_i282
#CELL
  pure_quanta q_res *
  page29_i284
#CELL
  pure_quanta genoa_sp5 *
  page29_i287
#CELL
  pure_quanta q_res *
  page29_i327
#CELL
  pure_quanta q_res *
  page29_i328
#CELL
  pure_quanta q_res *
  page29_i329
#CELL
  pure_quanta q_res *
  page29_i330
#CELL
  pure_quanta q_res *
  page29_i332
#ISCELL
  standard offpage *
  page29_i335
#ISCELL
  standard offpage *
  page29_i336
#ISCELL
  standard offpage *
  page29_i337
#ISCELL
  standard offpage *
  page29_i339
#ISCELL
  standard offpage *
  page29_i340
#ISCELL
  standard offpage *
  page29_i341
#ISCELL
  standard offpage *
  page29_i342
#ISCELL
  standard offpage *
  page29_i343
#ISCELL
  standard offpage *
  page29_i345
#ISCELL
  standard offpage *
  page29_i346
#ISCELL
  standard offpage *
  page29_i347
#ISCELL
  standard offpage *
  page29_i348
#ISCELL
  standard offpage *
  page29_i349
#ISCELL
  standard offpage *
  page29_i350
#ISCELL
  standard offpage *
  page29_i351
#ISCELL
  standard offpage *
  page29_i352
#ISCELL
  standard offpage *
  page29_i353
#ISCELL
  standard offpage *
  page29_i354
#ISCELL
  standard offpage *
  page29_i355
#ISCELL
  standard offpage *
  page29_i356
#ISCELL
  standard offpage *
  page29_i365
#ISCELL
  standard offpage *
  page29_i366
#ISCELL
  standard offpage *
  page29_i372
#CELL
  pure_quanta sn74lvc1g07dbvr *
  page29_i373
#ISCELL
  standard offpage *
  page29_i376
#CELL
  pure_quanta q_res *
  page29_i377
#CELL
  pure_quanta q_cap *
  page29_i379
#ISCELL
  pure_quanta_power universal_gnd *
  page29_i380
#ISCELL
  pure_quanta_power universal_power *
  page29_i382
#CELL
  pure_quanta q_res *
  page29_i383
#ISCELL
  standard offpage *
  page29_i384
#ISCELL
  pure_quanta_power universal_gnd *
  page29_i385
#ISCELL
  pure_quanta_power vcc_core *
  page29_i386
#ISCELL
  standard offpage *
  page29_i394
#ISCELL
  pure_quanta_power universal_power *
  page29_i395
#CELL
  pure_quanta q_res *
  page29_i396
#CELL
  pure_quanta q_res *
  page29_i397
#CELL
  pure_quanta q_res *
  page29_i398
#CELL
  pure_quanta q_res *
  page29_i399
#ISCELL
  standard offpage *
  page29_i400
#ISCELL
  standard offpage *
  page29_i401
#ISCELL
  standard offpage *
  page29_i402
#ISCELL
  standard offpage *
  page29_i403
#ISCELL
  standard offpage *
  page29_i404
#CELL
  pure_quanta q_res *
  page29_i405
#CELL
  pure_quanta q_res *
  page29_i407
#CELL
  pure_quanta q_res *
  page29_i408
#CELL
  pure_quanta q_res *
  page29_i409
#CELL
  pure_quanta q_res *
  page29_i410
#CELL
  pure_quanta q_res *
  page29_i411
#CELL
  pure_quanta q_res *
  page29_i412
#CELL
  pure_quanta q_res *
  page29_i413
#CELL
  pure_quanta q_res *
  page29_i414
#ISCELL
  standard offpage *
  page29_i419
#ISCELL
  standard offpage *
  page29_i420
#ISCELL
  standard offpage *
  page29_i421
#ISCELL
  standard offpage *
  page29_i422
#ISCELL
  standard offpage *
  page29_i423
#ISCELL
  standard offpage *
  page29_i424
#CELL
  pure_quanta q_res *
  page29_i425
#CELL
  pure_quanta q_res *
  page29_i426
#CELL
  pure_quanta q_res *
  page29_i427
#CELL
  pure_quanta q_res *
  page29_i428
#ISCELL
  standard offpage *
  page29_i429
#CELL
  pure_quanta q_res *
  page29_i430
#ISCELL
  pure_quanta quanta_title_block_c *
  *
#CELL
  pure_quanta genoa_sp5 *
  page30_i28
#CELL
  pure_quanta genoa_sp5 *
  page30_i29
#ISCELL
  pure_quanta_power vcc_core *
  page30_i40
#ISCELL
  pure_quanta_power universal_power *
  page30_i41
#CELL
  pure_quanta genoa_sp5 *
  page30_i42
#ISCELL
  pure_quanta_power vcc_core *
  page30_i43
#CELL
  pure_quanta genoa_sp5 *
  page30_i45
#ISCELL
  pure_quanta_power vcc_core *
  page30_i46
#ISCELL
  pure_quanta_power vcc_core *
  page30_i47
#CELL
  pure_quanta genoa_sp5 *
  page30_i50
#ISCELL
  pure_quanta_power vcc_core *
  page30_i51
#ISCELL
  pure_quanta_power vcc_core *
  page30_i52
#ISCELL
  pure_quanta_power universal_power *
  page30_i53
#ISCELL
  pure_quanta_power universal_power *
  page30_i55
#ISCELL
  pure_quanta_power vcc_core *
  page30_i56
#ISCELL
  pure_quanta_power vcc_core *
  page30_i57
#ISCELL
  pure_quanta quanta_title_block_c *
  *
#CELL
  pure_quanta genoa_sp5 *
  page31_i19
#CELL
  pure_quanta genoa_sp5 *
  page31_i20
#CELL
  pure_quanta genoa_sp5 *
  page31_i21
#CELL
  pure_quanta genoa_sp5 *
  page31_i22
#CELL
  pure_quanta genoa_sp5 *
  page31_i23
#CELL
  pure_quanta genoa_sp5 *
  page31_i24
#ISCELL
  pure_quanta_power universal_gnd *
  page31_i39
#ISCELL
  pure_quanta_power universal_gnd *
  page31_i40
#ISCELL
  pure_quanta_power universal_gnd *
  page31_i41
#ISCELL
  pure_quanta_power universal_gnd *
  page31_i43
#ISCELL
  pure_quanta_power universal_gnd *
  page31_i44
#ISCELL
  pure_quanta_power universal_gnd *
  page31_i45
#ISCELL
  pure_quanta_power universal_gnd *
  page31_i46
#ISCELL
  pure_quanta_power universal_gnd *
  page31_i47
#ISCELL
  pure_quanta_power universal_gnd *
  page31_i48
#ISCELL
  pure_quanta_power universal_gnd *
  page31_i49
#ISCELL
  pure_quanta_power universal_gnd *
  page31_i50
#ISCELL
  pure_quanta_power universal_gnd *
  page31_i51
#ISCELL
  pure_quanta quanta_title_block_c *
  *
#CELL
  pure_quanta genoa_sp5 *
  page32_i13
#CELL
  pure_quanta genoa_sp5 *
  page32_i14
#CELL
  pure_quanta genoa_sp5 *
  page32_i15
#CELL
  pure_quanta genoa_sp5 *
  page32_i16
#ISCELL
  pure_quanta_power universal_gnd *
  page32_i17
#ISCELL
  pure_quanta_power universal_gnd *
  page32_i18
#ISCELL
  pure_quanta_power universal_gnd *
  page32_i19
#ISCELL
  pure_quanta_power universal_gnd *
  page32_i20
#ISCELL
  pure_quanta_power universal_gnd *
  page32_i21
#ISCELL
  pure_quanta_power universal_gnd *
  page32_i22
#ISCELL
  pure_quanta_power universal_gnd *
  page32_i23
#ISCELL
  pure_quanta_power universal_gnd *
  page32_i24
#ISCELL
  pure_quanta quanta_title_block_c *
  *
#CELL
  pure_quanta genoa_sp5 *
  page33_i4
#ISCELL
  pure_quanta_power universal_gnd *
  page33_i5
#ISCELL
  pure_quanta_power universal_gnd *
  page33_i6
#ISCELL
  pure_quanta quanta_title_block_c *
  *
#ISCELL
  standard offpage *
  page34_i1
#ISCELL
  standard offpage *
  page34_i104
#ISCELL
  standard offpage *
  page34_i105
#CELL
  pure_quanta q_res *
  page34_i106
#CELL
  pure_quanta q_res *
  page34_i107
#ISCELL
  pure_quanta_power universal_power *
  page34_i108
#ISCELL
  pure_quanta_power universal_gnd *
  page34_i123
#CELL
  pure_quanta q_cap *
  page34_i124
#CELL
  pure_quanta q_res *
  page34_i125
#CELL
  pure_quanta pca9617adp *
  page34_i18
#ISCELL
  standard offpage *
  page34_i2
#ISCELL
  pure_quanta_power universal_power *
  page34_i3
#CELL
  pure_quanta q_res *
  page34_i4
#ISCELL
  pure_quanta_power universal_gnd *
  page34_i40
#ISCELL
  standard offpage *
  page34_i41
#ISCELL
  standard offpage *
  page34_i42
#ISCELL
  pure_quanta_power universal_power *
  page34_i43
#CELL
  pure_quanta q_cap *
  page34_i44
#ISCELL
  pure_quanta_power universal_gnd *
  page34_i45
#ISCELL
  pure_quanta_power universal_power *
  page34_i46
#CELL
  pure_quanta q_cap *
  page34_i47
#ISCELL
  pure_quanta_power universal_gnd *
  page34_i48
#CELL
  pure_quanta q_res *
  page34_i5
#ISCELL
  standard offpage *
  page34_i50
#ISCELL
  standard offpage *
  page34_i51
#ISCELL
  standard offpage *
  page34_i52
#CELL
  pure_quanta q_res *
  page34_i53
#ISCELL
  pure_quanta_power universal_power *
  page34_i54
#CELL
  pure_quanta sn74lvc1g07dbvr *
  page34_i55
#ISCELL
  pure_quanta_power universal_gnd *
  page34_i56
#ISCELL
  pure_quanta_power universal_gnd *
  page34_i58
#CELL
  pure_quanta q_cap *
  page34_i59
#CELL
  pure_quanta q_res *
  page34_i60
#ISCELL
  standard offpage *
  page34_i61
#ISCELL
  pure_quanta_power p1v0 *
  page34_i62
#ISCELL
  pure_quanta quanta_title_block_c *
  *
#ISCELL
  pure_quanta quanta_title_block_c *
  *
#ISCELL
  pure_quanta quanta_title_block_c *
  *
#ISCELL
  pure_quanta_power cad_note *
  *
#CELL
  pure_quanta genoa_sp5 *
  page37_i167
#ISCELL
  mstr_standard offpage *
  page37_i168
#ISCELL
  mstr_standard offpage *
  page37_i169
#ISCELL
  mstr_standard tap *
  page37_i170
#ISCELL
  mstr_standard tap *
  page37_i171
#ISCELL
  mstr_standard tap *
  page37_i172
#ISCELL
  mstr_standard tap *
  page37_i173
#ISCELL
  mstr_standard tap *
  page37_i174
#ISCELL
  mstr_standard tap *
  page37_i175
#ISCELL
  mstr_standard tap *
  page37_i176
#ISCELL
  mstr_standard tap *
  page37_i177
#ISCELL
  mstr_standard tap *
  page37_i178
#ISCELL
  mstr_standard tap *
  page37_i179
#ISCELL
  mstr_standard tap *
  page37_i180
#ISCELL
  mstr_standard tap *
  page37_i181
#ISCELL
  mstr_standard tap *
  page37_i182
#ISCELL
  mstr_standard tap *
  page37_i183
#ISCELL
  mstr_standard tap *
  page37_i184
#ISCELL
  mstr_standard tap *
  page37_i185
#ISCELL
  mstr_standard tap *
  page37_i186
#ISCELL
  mstr_standard tap *
  page37_i187
#ISCELL
  mstr_standard tap *
  page37_i188
#ISCELL
  mstr_standard tap *
  page37_i189
#ISCELL
  mstr_standard tap *
  page37_i190
#ISCELL
  mstr_standard tap *
  page37_i191
#ISCELL
  mstr_standard tap *
  page37_i192
#ISCELL
  mstr_standard tap *
  page37_i193
#ISCELL
  mstr_standard tap *
  page37_i194
#ISCELL
  mstr_standard tap *
  page37_i195
#ISCELL
  mstr_standard tap *
  page37_i196
#ISCELL
  mstr_standard tap *
  page37_i197
#ISCELL
  mstr_standard tap *
  page37_i198
#ISCELL
  mstr_standard tap *
  page37_i199
#ISCELL
  mstr_standard tap *
  page37_i200
#ISCELL
  mstr_standard tap *
  page37_i201
#ISCELL
  mstr_standard tap *
  page37_i202
#ISCELL
  mstr_standard tap *
  page37_i203
#ISCELL
  mstr_standard tap *
  page37_i204
#ISCELL
  mstr_standard tap *
  page37_i205
#ISCELL
  mstr_standard offpage *
  page37_i206
#ISCELL
  mstr_standard tap *
  page37_i207
#ISCELL
  mstr_standard tap *
  page37_i208
#ISCELL
  mstr_standard tap *
  page37_i209
#ISCELL
  mstr_standard tap *
  page37_i210
#ISCELL
  mstr_standard tap *
  page37_i211
#ISCELL
  mstr_standard tap *
  page37_i212
#ISCELL
  mstr_standard tap *
  page37_i213
#ISCELL
  mstr_standard tap *
  page37_i214
#ISCELL
  mstr_standard tap *
  page37_i215
#ISCELL
  mstr_standard tap *
  page37_i216
#ISCELL
  mstr_standard tap *
  page37_i217
#ISCELL
  mstr_standard tap *
  page37_i218
#ISCELL
  mstr_standard tap *
  page37_i219
#ISCELL
  mstr_standard tap *
  page37_i220
#ISCELL
  mstr_standard tap *
  page37_i221
#ISCELL
  mstr_standard tap *
  page37_i222
#ISCELL
  mstr_standard tap *
  page37_i223
#ISCELL
  mstr_standard tap *
  page37_i224
#ISCELL
  mstr_standard tap *
  page37_i225
#ISCELL
  mstr_standard tap *
  page37_i226
#ISCELL
  mstr_standard tap *
  page37_i227
#ISCELL
  mstr_standard tap *
  page37_i228
#ISCELL
  mstr_standard tap *
  page37_i229
#ISCELL
  mstr_standard tap *
  page37_i230
#ISCELL
  mstr_standard tap *
  page37_i231
#ISCELL
  mstr_standard tap *
  page37_i232
#ISCELL
  mstr_standard tap *
  page37_i233
#ISCELL
  mstr_standard tap *
  page37_i234
#ISCELL
  mstr_standard tap *
  page37_i235
#ISCELL
  mstr_standard tap *
  page37_i236
#ISCELL
  mstr_standard tap *
  page37_i237
#ISCELL
  mstr_standard tap *
  page37_i238
#ISCELL
  mstr_standard tap *
  page37_i239
#ISCELL
  mstr_standard tap *
  page37_i240
#ISCELL
  mstr_standard tap *
  page37_i241
#ISCELL
  mstr_standard tap *
  page37_i242
#ISCELL
  mstr_standard offpage *
  page37_i243
#ISCELL
  mstr_standard tap *
  page37_i244
#ISCELL
  mstr_standard tap *
  page37_i245
#ISCELL
  mstr_standard tap *
  page37_i246
#ISCELL
  mstr_standard tap *
  page37_i247
#ISCELL
  mstr_standard tap *
  page37_i248
#ISCELL
  mstr_standard tap *
  page37_i249
#ISCELL
  mstr_standard tap *
  page37_i250
#ISCELL
  mstr_standard tap *
  page37_i251
#ISCELL
  mstr_standard tap *
  page37_i252
#ISCELL
  mstr_standard tap *
  page37_i253
#ISCELL
  mstr_standard tap *
  page37_i254
#ISCELL
  mstr_standard tap *
  page37_i255
#ISCELL
  mstr_standard tap *
  page37_i256
#ISCELL
  mstr_standard tap *
  page37_i257
#ISCELL
  mstr_standard tap *
  page37_i258
#ISCELL
  mstr_standard tap *
  page37_i259
#ISCELL
  mstr_standard tap *
  page37_i260
#ISCELL
  mstr_standard tap *
  page37_i261
#ISCELL
  mstr_standard tap *
  page37_i262
#ISCELL
  mstr_standard tap *
  page37_i263
#ISCELL
  mstr_standard tap *
  page37_i264
#ISCELL
  mstr_standard tap *
  page37_i265
#ISCELL
  mstr_standard tap *
  page37_i266
#ISCELL
  mstr_standard tap *
  page37_i267
#ISCELL
  mstr_standard tap *
  page37_i268
#ISCELL
  mstr_standard tap *
  page37_i269
#ISCELL
  mstr_standard tap *
  page37_i270
#ISCELL
  mstr_standard tap *
  page37_i271
#ISCELL
  mstr_standard tap *
  page37_i272
#ISCELL
  mstr_standard tap *
  page37_i273
#ISCELL
  mstr_standard tap *
  page37_i274
#ISCELL
  mstr_standard tap *
  page37_i275
#ISCELL
  mstr_standard tap *
  page37_i276
#ISCELL
  mstr_standard tap *
  page37_i277
#ISCELL
  mstr_standard tap *
  page37_i278
#ISCELL
  mstr_standard tap *
  page37_i279
#ISCELL
  mstr_standard tap *
  page37_i280
#ISCELL
  mstr_standard tap *
  page37_i281
#ISCELL
  mstr_standard tap *
  page37_i282
#ISCELL
  mstr_standard tap *
  page37_i283
#ISCELL
  mstr_standard tap *
  page37_i284
#ISCELL
  mstr_standard tap *
  page37_i285
#ISCELL
  mstr_standard tap *
  page37_i286
#ISCELL
  mstr_standard tap *
  page37_i287
#ISCELL
  mstr_standard tap *
  page37_i288
#ISCELL
  mstr_standard tap *
  page37_i289
#ISCELL
  mstr_standard tap *
  page37_i290
#ISCELL
  standard offpage *
  page37_i291
#ISCELL
  standard offpage *
  page37_i292
#ISCELL
  standard offpage *
  page37_i293
#ISCELL
  standard offpage *
  page37_i294
#ISCELL
  mstr_standard tap *
  page37_i295
#ISCELL
  mstr_standard tap *
  page37_i296
#ISCELL
  mstr_standard tap *
  page37_i297
#ISCELL
  mstr_standard tap *
  page37_i298
#ISCELL
  mstr_standard tap *
  page37_i299
#ISCELL
  mstr_standard tap *
  page37_i300
#ISCELL
  mstr_standard tap *
  page37_i301
#ISCELL
  mstr_standard tap *
  page37_i302
#ISCELL
  mstr_standard tap *
  page37_i303
#ISCELL
  mstr_standard tap *
  page37_i304
#ISCELL
  mstr_standard tap *
  page37_i305
#ISCELL
  mstr_standard tap *
  page37_i306
#ISCELL
  mstr_standard tap *
  page37_i307
#ISCELL
  mstr_standard tap *
  page37_i308
#ISCELL
  mstr_standard tap *
  page37_i309
#ISCELL
  standard offpage *
  page37_i310
#ISCELL
  standard offpage *
  page37_i311
#ISCELL
  standard offpage *
  page37_i312
#ISCELL
  standard offpage *
  page37_i313
#ISCELL
  standard offpage *
  page37_i314
#ISCELL
  standard offpage *
  page37_i315
#ISCELL
  standard offpage *
  page37_i316
#ISCELL
  mstr_standard offpage *
  page37_i317
#ISCELL
  standard offpage *
  page37_i318
#ISCELL
  standard offpage *
  page37_i319
#ISCELL
  standard offpage *
  page37_i320
#ISCELL
  standard offpage *
  page37_i321
#CELL
  pure_quanta q_res *
  page37_i322
#ISCELL
  standard offpage *
  page37_i323
#ISCELL
  mstr_standard offpage *
  page37_i324
#ISCELL
  pure_quanta quanta_title_block_c *
  *
#ISCELL
  pure_quanta_power cad_note *
  *
#CELL
  pure_quanta genoa_sp5 *
  page38_i159
#ISCELL
  mstr_standard offpage *
  page38_i160
#ISCELL
  mstr_standard offpage *
  page38_i161
#ISCELL
  mstr_standard tap *
  page38_i162
#ISCELL
  mstr_standard tap *
  page38_i163
#ISCELL
  mstr_standard tap *
  page38_i164
#ISCELL
  mstr_standard tap *
  page38_i165
#ISCELL
  mstr_standard tap *
  page38_i166
#ISCELL
  mstr_standard tap *
  page38_i167
#ISCELL
  mstr_standard tap *
  page38_i168
#ISCELL
  mstr_standard tap *
  page38_i169
#ISCELL
  mstr_standard tap *
  page38_i170
#ISCELL
  mstr_standard tap *
  page38_i171
#ISCELL
  mstr_standard tap *
  page38_i172
#ISCELL
  mstr_standard tap *
  page38_i173
#ISCELL
  mstr_standard tap *
  page38_i174
#ISCELL
  mstr_standard tap *
  page38_i175
#ISCELL
  mstr_standard tap *
  page38_i176
#ISCELL
  mstr_standard tap *
  page38_i177
#ISCELL
  mstr_standard tap *
  page38_i178
#ISCELL
  mstr_standard tap *
  page38_i179
#ISCELL
  mstr_standard tap *
  page38_i180
#ISCELL
  mstr_standard tap *
  page38_i181
#ISCELL
  mstr_standard tap *
  page38_i182
#ISCELL
  mstr_standard tap *
  page38_i183
#ISCELL
  mstr_standard tap *
  page38_i184
#ISCELL
  mstr_standard tap *
  page38_i185
#ISCELL
  mstr_standard tap *
  page38_i186
#ISCELL
  mstr_standard tap *
  page38_i187
#ISCELL
  mstr_standard tap *
  page38_i188
#ISCELL
  mstr_standard tap *
  page38_i189
#ISCELL
  mstr_standard tap *
  page38_i190
#ISCELL
  mstr_standard tap *
  page38_i191
#ISCELL
  mstr_standard tap *
  page38_i192
#ISCELL
  mstr_standard tap *
  page38_i193
#ISCELL
  mstr_standard tap *
  page38_i194
#ISCELL
  mstr_standard tap *
  page38_i195
#ISCELL
  mstr_standard tap *
  page38_i196
#ISCELL
  mstr_standard offpage *
  page38_i197
#ISCELL
  mstr_standard tap *
  page38_i198
#ISCELL
  mstr_standard tap *
  page38_i199
#ISCELL
  mstr_standard tap *
  page38_i200
#ISCELL
  mstr_standard tap *
  page38_i201
#ISCELL
  mstr_standard tap *
  page38_i202
#ISCELL
  mstr_standard tap *
  page38_i203
#ISCELL
  mstr_standard tap *
  page38_i204
#ISCELL
  mstr_standard tap *
  page38_i205
#ISCELL
  mstr_standard tap *
  page38_i206
#ISCELL
  mstr_standard tap *
  page38_i207
#ISCELL
  mstr_standard tap *
  page38_i208
#ISCELL
  mstr_standard tap *
  page38_i209
#ISCELL
  mstr_standard tap *
  page38_i210
#ISCELL
  mstr_standard tap *
  page38_i211
#ISCELL
  mstr_standard tap *
  page38_i212
#ISCELL
  mstr_standard tap *
  page38_i213
#ISCELL
  mstr_standard tap *
  page38_i214
#ISCELL
  mstr_standard tap *
  page38_i215
#ISCELL
  mstr_standard tap *
  page38_i216
#ISCELL
  mstr_standard tap *
  page38_i217
#ISCELL
  mstr_standard tap *
  page38_i218
#ISCELL
  mstr_standard tap *
  page38_i219
#ISCELL
  mstr_standard tap *
  page38_i220
#ISCELL
  mstr_standard tap *
  page38_i221
#ISCELL
  mstr_standard tap *
  page38_i222
#ISCELL
  mstr_standard tap *
  page38_i223
#ISCELL
  mstr_standard tap *
  page38_i224
#ISCELL
  mstr_standard tap *
  page38_i225
#ISCELL
  mstr_standard tap *
  page38_i226
#ISCELL
  mstr_standard tap *
  page38_i227
#ISCELL
  mstr_standard tap *
  page38_i228
#ISCELL
  mstr_standard tap *
  page38_i229
#ISCELL
  mstr_standard tap *
  page38_i230
#ISCELL
  mstr_standard tap *
  page38_i231
#ISCELL
  mstr_standard tap *
  page38_i232
#ISCELL
  mstr_standard tap *
  page38_i233
#ISCELL
  mstr_standard tap *
  page38_i234
#ISCELL
  mstr_standard offpage *
  page38_i235
#ISCELL
  mstr_standard tap *
  page38_i236
#ISCELL
  mstr_standard tap *
  page38_i237
#ISCELL
  mstr_standard tap *
  page38_i238
#ISCELL
  mstr_standard tap *
  page38_i239
#ISCELL
  mstr_standard tap *
  page38_i240
#ISCELL
  mstr_standard tap *
  page38_i241
#ISCELL
  mstr_standard tap *
  page38_i242
#ISCELL
  mstr_standard tap *
  page38_i243
#ISCELL
  mstr_standard tap *
  page38_i244
#ISCELL
  mstr_standard tap *
  page38_i245
#ISCELL
  mstr_standard tap *
  page38_i246
#ISCELL
  mstr_standard tap *
  page38_i247
#ISCELL
  mstr_standard tap *
  page38_i248
#ISCELL
  mstr_standard tap *
  page38_i249
#ISCELL
  mstr_standard tap *
  page38_i250
#ISCELL
  mstr_standard tap *
  page38_i251
#ISCELL
  mstr_standard tap *
  page38_i252
#ISCELL
  mstr_standard tap *
  page38_i253
#ISCELL
  mstr_standard tap *
  page38_i254
#ISCELL
  mstr_standard tap *
  page38_i255
#ISCELL
  mstr_standard tap *
  page38_i256
#ISCELL
  mstr_standard tap *
  page38_i257
#ISCELL
  mstr_standard tap *
  page38_i258
#ISCELL
  mstr_standard tap *
  page38_i259
#ISCELL
  mstr_standard tap *
  page38_i260
#ISCELL
  mstr_standard tap *
  page38_i261
#ISCELL
  mstr_standard tap *
  page38_i262
#ISCELL
  mstr_standard tap *
  page38_i263
#ISCELL
  mstr_standard tap *
  page38_i264
#ISCELL
  mstr_standard tap *
  page38_i265
#ISCELL
  mstr_standard tap *
  page38_i266
#ISCELL
  mstr_standard tap *
  page38_i267
#ISCELL
  mstr_standard tap *
  page38_i268
#ISCELL
  mstr_standard tap *
  page38_i269
#ISCELL
  mstr_standard tap *
  page38_i270
#ISCELL
  mstr_standard tap *
  page38_i271
#ISCELL
  mstr_standard tap *
  page38_i272
#ISCELL
  mstr_standard tap *
  page38_i273
#ISCELL
  mstr_standard tap *
  page38_i274
#ISCELL
  mstr_standard tap *
  page38_i275
#ISCELL
  mstr_standard tap *
  page38_i276
#ISCELL
  mstr_standard tap *
  page38_i277
#ISCELL
  mstr_standard tap *
  page38_i278
#ISCELL
  mstr_standard tap *
  page38_i279
#ISCELL
  mstr_standard tap *
  page38_i280
#ISCELL
  mstr_standard tap *
  page38_i281
#ISCELL
  standard offpage *
  page38_i282
#ISCELL
  standard offpage *
  page38_i283
#ISCELL
  standard offpage *
  page38_i284
#ISCELL
  standard offpage *
  page38_i285
#ISCELL
  mstr_standard tap *
  page38_i286
#ISCELL
  mstr_standard tap *
  page38_i287
#ISCELL
  mstr_standard tap *
  page38_i288
#ISCELL
  mstr_standard tap *
  page38_i289
#ISCELL
  mstr_standard tap *
  page38_i290
#ISCELL
  mstr_standard tap *
  page38_i291
#ISCELL
  mstr_standard tap *
  page38_i292
#ISCELL
  mstr_standard tap *
  page38_i293
#ISCELL
  mstr_standard tap *
  page38_i294
#ISCELL
  mstr_standard tap *
  page38_i295
#ISCELL
  mstr_standard tap *
  page38_i296
#ISCELL
  mstr_standard tap *
  page38_i297
#ISCELL
  mstr_standard tap *
  page38_i298
#ISCELL
  mstr_standard tap *
  page38_i299
#ISCELL
  mstr_standard tap *
  page38_i300
#ISCELL
  mstr_standard tap *
  page38_i301
#ISCELL
  standard offpage *
  page38_i302
#ISCELL
  standard offpage *
  page38_i303
#ISCELL
  standard offpage *
  page38_i304
#ISCELL
  standard offpage *
  page38_i305
#ISCELL
  standard offpage *
  page38_i306
#ISCELL
  standard offpage *
  page38_i307
#ISCELL
  standard offpage *
  page38_i308
#ISCELL
  mstr_standard offpage *
  page38_i309
#ISCELL
  standard offpage *
  page38_i310
#ISCELL
  standard offpage *
  page38_i311
#ISCELL
  standard offpage *
  page38_i312
#ISCELL
  standard offpage *
  page38_i313
#CELL
  pure_quanta q_res *
  page38_i314
#ISCELL
  mstr_standard offpage *
  page38_i315
#ISCELL
  standard offpage *
  page38_i316
#ISCELL
  pure_quanta quanta_title_block_c *
  *
#ISCELL
  pure_quanta_power cad_note *
  *
#CELL
  pure_quanta genoa_sp5 *
  page39_i159
#ISCELL
  mstr_standard offpage *
  page39_i160
#ISCELL
  mstr_standard offpage *
  page39_i161
#ISCELL
  mstr_standard tap *
  page39_i162
#ISCELL
  mstr_standard tap *
  page39_i163
#ISCELL
  mstr_standard tap *
  page39_i164
#ISCELL
  mstr_standard tap *
  page39_i165
#ISCELL
  mstr_standard tap *
  page39_i166
#ISCELL
  mstr_standard tap *
  page39_i167
#ISCELL
  mstr_standard tap *
  page39_i168
#ISCELL
  mstr_standard tap *
  page39_i169
#ISCELL
  mstr_standard tap *
  page39_i170
#ISCELL
  mstr_standard tap *
  page39_i171
#ISCELL
  mstr_standard tap *
  page39_i172
#ISCELL
  mstr_standard tap *
  page39_i173
#ISCELL
  mstr_standard tap *
  page39_i174
#ISCELL
  mstr_standard tap *
  page39_i175
#ISCELL
  mstr_standard tap *
  page39_i176
#ISCELL
  mstr_standard tap *
  page39_i177
#ISCELL
  mstr_standard tap *
  page39_i178
#ISCELL
  mstr_standard tap *
  page39_i179
#ISCELL
  mstr_standard tap *
  page39_i180
#ISCELL
  mstr_standard tap *
  page39_i181
#ISCELL
  mstr_standard tap *
  page39_i182
#ISCELL
  mstr_standard tap *
  page39_i183
#ISCELL
  mstr_standard tap *
  page39_i184
#ISCELL
  mstr_standard tap *
  page39_i185
#ISCELL
  mstr_standard tap *
  page39_i186
#ISCELL
  mstr_standard tap *
  page39_i187
#ISCELL
  mstr_standard tap *
  page39_i188
#ISCELL
  mstr_standard tap *
  page39_i189
#ISCELL
  mstr_standard tap *
  page39_i190
#ISCELL
  mstr_standard tap *
  page39_i191
#ISCELL
  mstr_standard tap *
  page39_i192
#ISCELL
  mstr_standard tap *
  page39_i193
#ISCELL
  mstr_standard tap *
  page39_i194
#ISCELL
  mstr_standard tap *
  page39_i195
#ISCELL
  mstr_standard tap *
  page39_i196
#ISCELL
  mstr_standard tap *
  page39_i197
#ISCELL
  mstr_standard offpage *
  page39_i198
#ISCELL
  mstr_standard tap *
  page39_i199
#ISCELL
  mstr_standard tap *
  page39_i200
#ISCELL
  mstr_standard tap *
  page39_i201
#ISCELL
  mstr_standard tap *
  page39_i202
#ISCELL
  mstr_standard tap *
  page39_i203
#ISCELL
  mstr_standard tap *
  page39_i204
#ISCELL
  mstr_standard tap *
  page39_i205
#ISCELL
  mstr_standard tap *
  page39_i206
#ISCELL
  mstr_standard tap *
  page39_i207
#ISCELL
  mstr_standard tap *
  page39_i208
#ISCELL
  mstr_standard tap *
  page39_i209
#ISCELL
  mstr_standard tap *
  page39_i210
#ISCELL
  mstr_standard tap *
  page39_i211
#ISCELL
  mstr_standard tap *
  page39_i212
#ISCELL
  mstr_standard tap *
  page39_i213
#ISCELL
  mstr_standard tap *
  page39_i214
#ISCELL
  mstr_standard tap *
  page39_i215
#ISCELL
  mstr_standard tap *
  page39_i216
#ISCELL
  mstr_standard tap *
  page39_i217
#ISCELL
  mstr_standard tap *
  page39_i218
#ISCELL
  mstr_standard tap *
  page39_i219
#ISCELL
  mstr_standard tap *
  page39_i220
#ISCELL
  mstr_standard tap *
  page39_i221
#ISCELL
  mstr_standard tap *
  page39_i222
#ISCELL
  mstr_standard tap *
  page39_i223
#ISCELL
  mstr_standard tap *
  page39_i224
#ISCELL
  mstr_standard tap *
  page39_i225
#ISCELL
  mstr_standard tap *
  page39_i226
#ISCELL
  mstr_standard tap *
  page39_i227
#ISCELL
  mstr_standard tap *
  page39_i228
#ISCELL
  mstr_standard tap *
  page39_i229
#ISCELL
  mstr_standard tap *
  page39_i230
#ISCELL
  mstr_standard tap *
  page39_i231
#ISCELL
  mstr_standard tap *
  page39_i232
#ISCELL
  mstr_standard tap *
  page39_i233
#ISCELL
  mstr_standard tap *
  page39_i234
#ISCELL
  mstr_standard offpage *
  page39_i235
#ISCELL
  mstr_standard tap *
  page39_i236
#ISCELL
  mstr_standard tap *
  page39_i237
#ISCELL
  mstr_standard tap *
  page39_i238
#ISCELL
  mstr_standard tap *
  page39_i239
#ISCELL
  mstr_standard tap *
  page39_i240
#ISCELL
  mstr_standard tap *
  page39_i241
#ISCELL
  mstr_standard tap *
  page39_i242
#ISCELL
  mstr_standard tap *
  page39_i243
#ISCELL
  mstr_standard tap *
  page39_i244
#ISCELL
  mstr_standard tap *
  page39_i245
#ISCELL
  mstr_standard tap *
  page39_i246
#ISCELL
  mstr_standard tap *
  page39_i247
#ISCELL
  mstr_standard tap *
  page39_i248
#ISCELL
  mstr_standard tap *
  page39_i249
#ISCELL
  mstr_standard tap *
  page39_i250
#ISCELL
  mstr_standard tap *
  page39_i251
#ISCELL
  mstr_standard tap *
  page39_i252
#ISCELL
  mstr_standard tap *
  page39_i253
#ISCELL
  mstr_standard tap *
  page39_i254
#ISCELL
  mstr_standard tap *
  page39_i255
#ISCELL
  mstr_standard tap *
  page39_i256
#ISCELL
  mstr_standard tap *
  page39_i257
#ISCELL
  mstr_standard tap *
  page39_i258
#ISCELL
  mstr_standard tap *
  page39_i259
#ISCELL
  mstr_standard tap *
  page39_i260
#ISCELL
  mstr_standard tap *
  page39_i261
#ISCELL
  mstr_standard tap *
  page39_i262
#ISCELL
  mstr_standard tap *
  page39_i263
#ISCELL
  mstr_standard tap *
  page39_i264
#ISCELL
  mstr_standard tap *
  page39_i265
#ISCELL
  mstr_standard tap *
  page39_i266
#ISCELL
  mstr_standard tap *
  page39_i267
#ISCELL
  mstr_standard tap *
  page39_i268
#ISCELL
  mstr_standard tap *
  page39_i269
#ISCELL
  mstr_standard tap *
  page39_i270
#ISCELL
  mstr_standard tap *
  page39_i271
#ISCELL
  mstr_standard tap *
  page39_i272
#ISCELL
  mstr_standard tap *
  page39_i273
#ISCELL
  mstr_standard tap *
  page39_i274
#ISCELL
  mstr_standard tap *
  page39_i275
#ISCELL
  mstr_standard tap *
  page39_i276
#ISCELL
  mstr_standard tap *
  page39_i277
#ISCELL
  mstr_standard tap *
  page39_i278
#ISCELL
  mstr_standard tap *
  page39_i279
#ISCELL
  mstr_standard tap *
  page39_i280
#ISCELL
  mstr_standard tap *
  page39_i281
#ISCELL
  mstr_standard tap *
  page39_i282
#ISCELL
  standard offpage *
  page39_i283
#ISCELL
  standard offpage *
  page39_i284
#ISCELL
  standard offpage *
  page39_i285
#ISCELL
  standard offpage *
  page39_i286
#ISCELL
  mstr_standard tap *
  page39_i287
#ISCELL
  mstr_standard tap *
  page39_i288
#ISCELL
  mstr_standard tap *
  page39_i289
#ISCELL
  mstr_standard tap *
  page39_i290
#ISCELL
  mstr_standard tap *
  page39_i291
#ISCELL
  mstr_standard tap *
  page39_i292
#ISCELL
  mstr_standard tap *
  page39_i293
#ISCELL
  mstr_standard tap *
  page39_i294
#ISCELL
  mstr_standard tap *
  page39_i295
#ISCELL
  mstr_standard tap *
  page39_i296
#ISCELL
  mstr_standard tap *
  page39_i297
#ISCELL
  mstr_standard tap *
  page39_i298
#ISCELL
  mstr_standard tap *
  page39_i299
#ISCELL
  mstr_standard tap *
  page39_i300
#ISCELL
  mstr_standard tap *
  page39_i301
#ISCELL
  standard offpage *
  page39_i302
#ISCELL
  standard offpage *
  page39_i303
#ISCELL
  standard offpage *
  page39_i304
#ISCELL
  standard offpage *
  page39_i305
#ISCELL
  standard offpage *
  page39_i306
#ISCELL
  standard offpage *
  page39_i307
#ISCELL
  standard offpage *
  page39_i308
#ISCELL
  mstr_standard offpage *
  page39_i309
#ISCELL
  standard offpage *
  page39_i310
#ISCELL
  standard offpage *
  page39_i311
#ISCELL
  standard offpage *
  page39_i312
#CELL
  pure_quanta q_res *
  page39_i313
#ISCELL
  standard offpage *
  page39_i314
#ISCELL
  standard offpage *
  page39_i315
#ISCELL
  mstr_standard offpage *
  page39_i316
#ISCELL
  pure_quanta quanta_title_block_c *
  *
#ISCELL
  pure_quanta_power cad_note *
  *
#CELL
  pure_quanta genoa_sp5 *
  page40_i159
#ISCELL
  mstr_standard offpage *
  page40_i160
#ISCELL
  mstr_standard offpage *
  page40_i161
#ISCELL
  mstr_standard tap *
  page40_i162
#ISCELL
  mstr_standard tap *
  page40_i163
#ISCELL
  mstr_standard tap *
  page40_i164
#ISCELL
  mstr_standard tap *
  page40_i165
#ISCELL
  mstr_standard tap *
  page40_i166
#ISCELL
  mstr_standard tap *
  page40_i167
#ISCELL
  mstr_standard tap *
  page40_i168
#ISCELL
  mstr_standard tap *
  page40_i169
#ISCELL
  mstr_standard tap *
  page40_i170
#ISCELL
  mstr_standard tap *
  page40_i171
#ISCELL
  mstr_standard tap *
  page40_i172
#ISCELL
  mstr_standard tap *
  page40_i173
#ISCELL
  mstr_standard tap *
  page40_i174
#ISCELL
  mstr_standard tap *
  page40_i175
#ISCELL
  mstr_standard tap *
  page40_i176
#ISCELL
  mstr_standard tap *
  page40_i177
#ISCELL
  mstr_standard tap *
  page40_i178
#ISCELL
  mstr_standard tap *
  page40_i179
#ISCELL
  mstr_standard tap *
  page40_i180
#ISCELL
  mstr_standard tap *
  page40_i181
#ISCELL
  mstr_standard tap *
  page40_i182
#ISCELL
  mstr_standard tap *
  page40_i183
#ISCELL
  mstr_standard tap *
  page40_i184
#ISCELL
  mstr_standard tap *
  page40_i185
#ISCELL
  mstr_standard tap *
  page40_i186
#ISCELL
  mstr_standard tap *
  page40_i187
#ISCELL
  mstr_standard tap *
  page40_i188
#ISCELL
  mstr_standard tap *
  page40_i189
#ISCELL
  mstr_standard tap *
  page40_i190
#ISCELL
  mstr_standard tap *
  page40_i191
#ISCELL
  mstr_standard tap *
  page40_i192
#ISCELL
  mstr_standard tap *
  page40_i193
#ISCELL
  mstr_standard tap *
  page40_i194
#ISCELL
  mstr_standard tap *
  page40_i195
#ISCELL
  mstr_standard tap *
  page40_i196
#ISCELL
  mstr_standard offpage *
  page40_i197
#ISCELL
  mstr_standard tap *
  page40_i198
#ISCELL
  mstr_standard tap *
  page40_i199
#ISCELL
  mstr_standard tap *
  page40_i200
#ISCELL
  mstr_standard tap *
  page40_i201
#ISCELL
  mstr_standard tap *
  page40_i202
#ISCELL
  mstr_standard tap *
  page40_i203
#ISCELL
  mstr_standard tap *
  page40_i204
#ISCELL
  mstr_standard tap *
  page40_i205
#ISCELL
  mstr_standard tap *
  page40_i206
#ISCELL
  mstr_standard tap *
  page40_i207
#ISCELL
  mstr_standard tap *
  page40_i208
#ISCELL
  mstr_standard tap *
  page40_i209
#ISCELL
  mstr_standard tap *
  page40_i210
#ISCELL
  mstr_standard tap *
  page40_i211
#ISCELL
  mstr_standard tap *
  page40_i212
#ISCELL
  mstr_standard tap *
  page40_i213
#ISCELL
  mstr_standard tap *
  page40_i214
#ISCELL
  mstr_standard tap *
  page40_i215
#ISCELL
  mstr_standard tap *
  page40_i216
#ISCELL
  mstr_standard tap *
  page40_i217
#ISCELL
  mstr_standard tap *
  page40_i218
#ISCELL
  mstr_standard tap *
  page40_i219
#ISCELL
  mstr_standard tap *
  page40_i220
#ISCELL
  mstr_standard tap *
  page40_i221
#ISCELL
  mstr_standard tap *
  page40_i222
#ISCELL
  mstr_standard tap *
  page40_i223
#ISCELL
  mstr_standard tap *
  page40_i224
#ISCELL
  mstr_standard tap *
  page40_i225
#ISCELL
  mstr_standard tap *
  page40_i226
#ISCELL
  mstr_standard tap *
  page40_i227
#ISCELL
  mstr_standard tap *
  page40_i228
#ISCELL
  mstr_standard tap *
  page40_i229
#ISCELL
  mstr_standard tap *
  page40_i230
#ISCELL
  mstr_standard tap *
  page40_i231
#ISCELL
  mstr_standard tap *
  page40_i232
#ISCELL
  mstr_standard tap *
  page40_i233
#ISCELL
  mstr_standard tap *
  page40_i234
#ISCELL
  mstr_standard offpage *
  page40_i235
#ISCELL
  mstr_standard tap *
  page40_i236
#ISCELL
  mstr_standard tap *
  page40_i237
#ISCELL
  mstr_standard tap *
  page40_i238
#ISCELL
  mstr_standard tap *
  page40_i239
#ISCELL
  mstr_standard tap *
  page40_i240
#ISCELL
  mstr_standard tap *
  page40_i241
#ISCELL
  mstr_standard tap *
  page40_i242
#ISCELL
  mstr_standard tap *
  page40_i243
#ISCELL
  mstr_standard tap *
  page40_i244
#ISCELL
  mstr_standard tap *
  page40_i245
#ISCELL
  mstr_standard tap *
  page40_i246
#ISCELL
  mstr_standard tap *
  page40_i247
#ISCELL
  mstr_standard tap *
  page40_i248
#ISCELL
  mstr_standard tap *
  page40_i249
#ISCELL
  mstr_standard tap *
  page40_i250
#ISCELL
  mstr_standard tap *
  page40_i251
#ISCELL
  mstr_standard tap *
  page40_i252
#ISCELL
  mstr_standard tap *
  page40_i253
#ISCELL
  mstr_standard tap *
  page40_i254
#ISCELL
  mstr_standard tap *
  page40_i255
#ISCELL
  mstr_standard tap *
  page40_i256
#ISCELL
  mstr_standard tap *
  page40_i257
#ISCELL
  mstr_standard tap *
  page40_i258
#ISCELL
  mstr_standard tap *
  page40_i259
#ISCELL
  mstr_standard tap *
  page40_i260
#ISCELL
  mstr_standard tap *
  page40_i261
#ISCELL
  mstr_standard tap *
  page40_i262
#ISCELL
  mstr_standard tap *
  page40_i263
#ISCELL
  mstr_standard tap *
  page40_i264
#ISCELL
  mstr_standard tap *
  page40_i265
#ISCELL
  mstr_standard tap *
  page40_i266
#ISCELL
  mstr_standard tap *
  page40_i267
#ISCELL
  mstr_standard tap *
  page40_i268
#ISCELL
  mstr_standard tap *
  page40_i269
#ISCELL
  mstr_standard tap *
  page40_i270
#ISCELL
  mstr_standard tap *
  page40_i271
#ISCELL
  mstr_standard tap *
  page40_i272
#ISCELL
  mstr_standard tap *
  page40_i273
#ISCELL
  mstr_standard tap *
  page40_i274
#ISCELL
  mstr_standard tap *
  page40_i275
#ISCELL
  mstr_standard tap *
  page40_i276
#ISCELL
  mstr_standard tap *
  page40_i277
#ISCELL
  mstr_standard tap *
  page40_i278
#ISCELL
  mstr_standard tap *
  page40_i279
#ISCELL
  mstr_standard tap *
  page40_i280
#ISCELL
  mstr_standard tap *
  page40_i281
#ISCELL
  standard offpage *
  page40_i282
#ISCELL
  standard offpage *
  page40_i283
#ISCELL
  standard offpage *
  page40_i284
#ISCELL
  standard offpage *
  page40_i285
#ISCELL
  mstr_standard tap *
  page40_i286
#ISCELL
  mstr_standard tap *
  page40_i287
#ISCELL
  mstr_standard tap *
  page40_i288
#ISCELL
  mstr_standard tap *
  page40_i289
#ISCELL
  mstr_standard tap *
  page40_i290
#ISCELL
  mstr_standard tap *
  page40_i291
#ISCELL
  mstr_standard tap *
  page40_i292
#ISCELL
  mstr_standard tap *
  page40_i293
#ISCELL
  mstr_standard tap *
  page40_i294
#ISCELL
  mstr_standard tap *
  page40_i295
#ISCELL
  mstr_standard tap *
  page40_i296
#ISCELL
  mstr_standard tap *
  page40_i297
#ISCELL
  mstr_standard tap *
  page40_i298
#ISCELL
  mstr_standard tap *
  page40_i299
#ISCELL
  mstr_standard tap *
  page40_i300
#ISCELL
  mstr_standard tap *
  page40_i301
#ISCELL
  standard offpage *
  page40_i302
#ISCELL
  standard offpage *
  page40_i303
#ISCELL
  standard offpage *
  page40_i304
#ISCELL
  standard offpage *
  page40_i305
#ISCELL
  standard offpage *
  page40_i306
#ISCELL
  standard offpage *
  page40_i307
#ISCELL
  standard offpage *
  page40_i308
#ISCELL
  mstr_standard offpage *
  page40_i309
#ISCELL
  standard offpage *
  page40_i310
#ISCELL
  standard offpage *
  page40_i311
#ISCELL
  standard offpage *
  page40_i312
#ISCELL
  standard offpage *
  page40_i313
#CELL
  pure_quanta q_res *
  page40_i314
#ISCELL
  mstr_standard offpage *
  page40_i315
#ISCELL
  standard offpage *
  page40_i316
#ISCELL
  pure_quanta quanta_title_block_c *
  *
#ISCELL
  pure_quanta_power cad_note *
  *
#CELL
  pure_quanta genoa_sp5 *
  page41_i159
#ISCELL
  mstr_standard offpage *
  page41_i160
#ISCELL
  mstr_standard offpage *
  page41_i161
#ISCELL
  mstr_standard tap *
  page41_i162
#ISCELL
  mstr_standard tap *
  page41_i163
#ISCELL
  mstr_standard tap *
  page41_i164
#ISCELL
  mstr_standard tap *
  page41_i165
#ISCELL
  mstr_standard tap *
  page41_i166
#ISCELL
  mstr_standard tap *
  page41_i167
#ISCELL
  mstr_standard tap *
  page41_i168
#ISCELL
  mstr_standard tap *
  page41_i169
#ISCELL
  mstr_standard tap *
  page41_i170
#ISCELL
  mstr_standard tap *
  page41_i171
#ISCELL
  mstr_standard tap *
  page41_i172
#ISCELL
  mstr_standard tap *
  page41_i173
#ISCELL
  mstr_standard tap *
  page41_i174
#ISCELL
  mstr_standard tap *
  page41_i175
#ISCELL
  mstr_standard tap *
  page41_i176
#ISCELL
  mstr_standard tap *
  page41_i177
#ISCELL
  mstr_standard tap *
  page41_i178
#ISCELL
  mstr_standard tap *
  page41_i179
#ISCELL
  mstr_standard tap *
  page41_i180
#ISCELL
  mstr_standard tap *
  page41_i181
#ISCELL
  mstr_standard tap *
  page41_i182
#ISCELL
  mstr_standard tap *
  page41_i183
#ISCELL
  mstr_standard tap *
  page41_i184
#ISCELL
  mstr_standard tap *
  page41_i185
#ISCELL
  mstr_standard tap *
  page41_i186
#ISCELL
  mstr_standard tap *
  page41_i187
#ISCELL
  mstr_standard tap *
  page41_i188
#ISCELL
  mstr_standard tap *
  page41_i189
#ISCELL
  mstr_standard tap *
  page41_i190
#ISCELL
  mstr_standard tap *
  page41_i191
#ISCELL
  mstr_standard tap *
  page41_i192
#ISCELL
  mstr_standard tap *
  page41_i193
#ISCELL
  mstr_standard tap *
  page41_i194
#ISCELL
  mstr_standard tap *
  page41_i195
#ISCELL
  mstr_standard offpage *
  page41_i196
#ISCELL
  mstr_standard tap *
  page41_i197
#ISCELL
  mstr_standard tap *
  page41_i198
#ISCELL
  mstr_standard tap *
  page41_i199
#ISCELL
  mstr_standard tap *
  page41_i200
#ISCELL
  mstr_standard tap *
  page41_i201
#ISCELL
  mstr_standard tap *
  page41_i202
#ISCELL
  mstr_standard tap *
  page41_i203
#ISCELL
  mstr_standard tap *
  page41_i204
#ISCELL
  mstr_standard tap *
  page41_i205
#ISCELL
  mstr_standard tap *
  page41_i206
#ISCELL
  mstr_standard tap *
  page41_i207
#ISCELL
  mstr_standard tap *
  page41_i208
#ISCELL
  mstr_standard tap *
  page41_i209
#ISCELL
  mstr_standard tap *
  page41_i210
#ISCELL
  mstr_standard tap *
  page41_i211
#ISCELL
  mstr_standard tap *
  page41_i212
#ISCELL
  mstr_standard tap *
  page41_i213
#ISCELL
  mstr_standard tap *
  page41_i214
#ISCELL
  mstr_standard tap *
  page41_i215
#ISCELL
  mstr_standard tap *
  page41_i216
#ISCELL
  mstr_standard tap *
  page41_i217
#ISCELL
  mstr_standard tap *
  page41_i218
#ISCELL
  mstr_standard tap *
  page41_i219
#ISCELL
  mstr_standard tap *
  page41_i220
#ISCELL
  mstr_standard tap *
  page41_i221
#ISCELL
  mstr_standard tap *
  page41_i222
#ISCELL
  mstr_standard tap *
  page41_i223
#ISCELL
  mstr_standard tap *
  page41_i224
#ISCELL
  mstr_standard tap *
  page41_i225
#ISCELL
  mstr_standard tap *
  page41_i226
#ISCELL
  mstr_standard tap *
  page41_i227
#ISCELL
  mstr_standard tap *
  page41_i228
#ISCELL
  mstr_standard tap *
  page41_i229
#ISCELL
  mstr_standard tap *
  page41_i230
#ISCELL
  mstr_standard tap *
  page41_i231
#ISCELL
  mstr_standard tap *
  page41_i232
#ISCELL
  mstr_standard tap *
  page41_i233
#ISCELL
  mstr_standard offpage *
  page41_i234
#ISCELL
  mstr_standard tap *
  page41_i235
#ISCELL
  mstr_standard tap *
  page41_i236
#ISCELL
  mstr_standard tap *
  page41_i237
#ISCELL
  mstr_standard tap *
  page41_i238
#ISCELL
  mstr_standard tap *
  page41_i239
#ISCELL
  mstr_standard tap *
  page41_i240
#ISCELL
  mstr_standard tap *
  page41_i241
#ISCELL
  mstr_standard tap *
  page41_i242
#ISCELL
  mstr_standard tap *
  page41_i243
#ISCELL
  mstr_standard tap *
  page41_i244
#ISCELL
  mstr_standard tap *
  page41_i245
#ISCELL
  mstr_standard tap *
  page41_i246
#ISCELL
  mstr_standard tap *
  page41_i247
#ISCELL
  mstr_standard tap *
  page41_i248
#ISCELL
  mstr_standard tap *
  page41_i249
#ISCELL
  mstr_standard tap *
  page41_i250
#ISCELL
  mstr_standard tap *
  page41_i251
#ISCELL
  mstr_standard tap *
  page41_i252
#ISCELL
  mstr_standard tap *
  page41_i253
#ISCELL
  mstr_standard tap *
  page41_i254
#ISCELL
  mstr_standard tap *
  page41_i255
#ISCELL
  mstr_standard tap *
  page41_i256
#ISCELL
  mstr_standard tap *
  page41_i257
#ISCELL
  mstr_standard tap *
  page41_i258
#ISCELL
  mstr_standard tap *
  page41_i259
#ISCELL
  mstr_standard tap *
  page41_i260
#ISCELL
  mstr_standard tap *
  page41_i261
#ISCELL
  mstr_standard tap *
  page41_i262
#ISCELL
  mstr_standard tap *
  page41_i263
#ISCELL
  mstr_standard tap *
  page41_i264
#ISCELL
  mstr_standard tap *
  page41_i265
#ISCELL
  mstr_standard tap *
  page41_i266
#ISCELL
  mstr_standard tap *
  page41_i267
#ISCELL
  mstr_standard tap *
  page41_i268
#ISCELL
  mstr_standard tap *
  page41_i269
#ISCELL
  mstr_standard tap *
  page41_i270
#ISCELL
  mstr_standard tap *
  page41_i271
#ISCELL
  mstr_standard tap *
  page41_i272
#ISCELL
  mstr_standard tap *
  page41_i273
#ISCELL
  mstr_standard tap *
  page41_i274
#ISCELL
  mstr_standard tap *
  page41_i275
#ISCELL
  mstr_standard tap *
  page41_i276
#ISCELL
  mstr_standard tap *
  page41_i277
#ISCELL
  mstr_standard tap *
  page41_i278
#ISCELL
  mstr_standard tap *
  page41_i279
#ISCELL
  mstr_standard tap *
  page41_i280
#ISCELL
  standard offpage *
  page41_i281
#ISCELL
  standard offpage *
  page41_i282
#ISCELL
  standard offpage *
  page41_i283
#ISCELL
  standard offpage *
  page41_i284
#ISCELL
  mstr_standard tap *
  page41_i285
#ISCELL
  mstr_standard tap *
  page41_i286
#ISCELL
  mstr_standard tap *
  page41_i287
#ISCELL
  mstr_standard tap *
  page41_i288
#ISCELL
  mstr_standard tap *
  page41_i289
#ISCELL
  mstr_standard tap *
  page41_i290
#ISCELL
  mstr_standard tap *
  page41_i291
#ISCELL
  mstr_standard tap *
  page41_i292
#ISCELL
  mstr_standard tap *
  page41_i293
#ISCELL
  mstr_standard tap *
  page41_i294
#ISCELL
  mstr_standard tap *
  page41_i295
#ISCELL
  mstr_standard tap *
  page41_i296
#ISCELL
  mstr_standard tap *
  page41_i297
#ISCELL
  mstr_standard tap *
  page41_i298
#ISCELL
  mstr_standard tap *
  page41_i299
#ISCELL
  mstr_standard tap *
  page41_i300
#ISCELL
  mstr_standard tap *
  page41_i301
#ISCELL
  standard offpage *
  page41_i302
#ISCELL
  standard offpage *
  page41_i303
#ISCELL
  standard offpage *
  page41_i304
#ISCELL
  standard offpage *
  page41_i305
#ISCELL
  standard offpage *
  page41_i306
#ISCELL
  standard offpage *
  page41_i307
#ISCELL
  standard offpage *
  page41_i308
#ISCELL
  mstr_standard offpage *
  page41_i309
#ISCELL
  standard offpage *
  page41_i310
#ISCELL
  standard offpage *
  page41_i311
#ISCELL
  standard offpage *
  page41_i312
#ISCELL
  standard offpage *
  page41_i313
#CELL
  pure_quanta q_res *
  page41_i314
#ISCELL
  mstr_standard offpage *
  page41_i315
#ISCELL
  standard offpage *
  page41_i316
#ISCELL
  pure_quanta quanta_title_block_c *
  *
#ISCELL
  pure_quanta_power cad_note *
  *
#CELL
  pure_quanta genoa_sp5 *
  page42_i159
#ISCELL
  mstr_standard tap *
  page42_i160
#ISCELL
  mstr_standard offpage *
  page42_i161
#ISCELL
  mstr_standard offpage *
  page42_i162
#ISCELL
  mstr_standard tap *
  page42_i163
#ISCELL
  mstr_standard tap *
  page42_i164
#ISCELL
  mstr_standard tap *
  page42_i165
#ISCELL
  mstr_standard tap *
  page42_i166
#ISCELL
  mstr_standard tap *
  page42_i167
#ISCELL
  mstr_standard tap *
  page42_i168
#ISCELL
  mstr_standard tap *
  page42_i169
#ISCELL
  mstr_standard tap *
  page42_i170
#ISCELL
  mstr_standard tap *
  page42_i171
#ISCELL
  mstr_standard tap *
  page42_i172
#ISCELL
  mstr_standard tap *
  page42_i173
#ISCELL
  mstr_standard tap *
  page42_i174
#ISCELL
  mstr_standard tap *
  page42_i175
#ISCELL
  mstr_standard tap *
  page42_i176
#ISCELL
  mstr_standard tap *
  page42_i177
#ISCELL
  mstr_standard tap *
  page42_i178
#ISCELL
  mstr_standard tap *
  page42_i179
#ISCELL
  mstr_standard tap *
  page42_i180
#ISCELL
  mstr_standard tap *
  page42_i181
#ISCELL
  mstr_standard tap *
  page42_i182
#ISCELL
  mstr_standard tap *
  page42_i183
#ISCELL
  mstr_standard tap *
  page42_i184
#ISCELL
  mstr_standard tap *
  page42_i185
#ISCELL
  mstr_standard tap *
  page42_i186
#ISCELL
  mstr_standard tap *
  page42_i187
#ISCELL
  mstr_standard tap *
  page42_i188
#ISCELL
  mstr_standard tap *
  page42_i189
#ISCELL
  mstr_standard tap *
  page42_i190
#ISCELL
  mstr_standard tap *
  page42_i191
#ISCELL
  mstr_standard tap *
  page42_i192
#ISCELL
  mstr_standard tap *
  page42_i193
#ISCELL
  mstr_standard tap *
  page42_i194
#ISCELL
  mstr_standard tap *
  page42_i195
#ISCELL
  mstr_standard tap *
  page42_i196
#ISCELL
  mstr_standard tap *
  page42_i197
#ISCELL
  mstr_standard tap *
  page42_i198
#ISCELL
  mstr_standard tap *
  page42_i199
#ISCELL
  mstr_standard offpage *
  page42_i200
#ISCELL
  mstr_standard offpage *
  page42_i201
#ISCELL
  mstr_standard tap *
  page42_i202
#ISCELL
  mstr_standard tap *
  page42_i203
#ISCELL
  mstr_standard tap *
  page42_i204
#ISCELL
  mstr_standard tap *
  page42_i205
#ISCELL
  mstr_standard tap *
  page42_i206
#ISCELL
  mstr_standard tap *
  page42_i207
#ISCELL
  mstr_standard tap *
  page42_i208
#ISCELL
  mstr_standard tap *
  page42_i209
#ISCELL
  mstr_standard tap *
  page42_i210
#ISCELL
  mstr_standard tap *
  page42_i211
#ISCELL
  mstr_standard tap *
  page42_i212
#ISCELL
  mstr_standard tap *
  page42_i213
#ISCELL
  mstr_standard tap *
  page42_i214
#ISCELL
  mstr_standard tap *
  page42_i215
#ISCELL
  mstr_standard tap *
  page42_i216
#ISCELL
  mstr_standard tap *
  page42_i217
#ISCELL
  mstr_standard tap *
  page42_i218
#ISCELL
  mstr_standard tap *
  page42_i219
#ISCELL
  mstr_standard tap *
  page42_i220
#ISCELL
  mstr_standard tap *
  page42_i221
#ISCELL
  mstr_standard tap *
  page42_i222
#ISCELL
  mstr_standard tap *
  page42_i223
#ISCELL
  mstr_standard tap *
  page42_i224
#ISCELL
  mstr_standard tap *
  page42_i225
#ISCELL
  mstr_standard tap *
  page42_i226
#ISCELL
  mstr_standard tap *
  page42_i227
#ISCELL
  mstr_standard tap *
  page42_i228
#ISCELL
  mstr_standard tap *
  page42_i229
#ISCELL
  mstr_standard tap *
  page42_i230
#ISCELL
  mstr_standard tap *
  page42_i231
#ISCELL
  mstr_standard tap *
  page42_i232
#ISCELL
  mstr_standard tap *
  page42_i233
#ISCELL
  mstr_standard tap *
  page42_i234
#ISCELL
  mstr_standard tap *
  page42_i235
#ISCELL
  mstr_standard tap *
  page42_i236
#ISCELL
  mstr_standard tap *
  page42_i237
#ISCELL
  mstr_standard tap *
  page42_i238
#ISCELL
  mstr_standard tap *
  page42_i239
#ISCELL
  mstr_standard tap *
  page42_i240
#ISCELL
  mstr_standard tap *
  page42_i241
#ISCELL
  mstr_standard tap *
  page42_i242
#ISCELL
  mstr_standard tap *
  page42_i243
#ISCELL
  mstr_standard tap *
  page42_i244
#ISCELL
  mstr_standard tap *
  page42_i245
#ISCELL
  mstr_standard tap *
  page42_i246
#ISCELL
  mstr_standard tap *
  page42_i247
#ISCELL
  mstr_standard tap *
  page42_i248
#ISCELL
  mstr_standard tap *
  page42_i249
#ISCELL
  mstr_standard tap *
  page42_i250
#ISCELL
  mstr_standard tap *
  page42_i251
#ISCELL
  mstr_standard tap *
  page42_i252
#ISCELL
  mstr_standard tap *
  page42_i253
#ISCELL
  mstr_standard tap *
  page42_i254
#ISCELL
  mstr_standard tap *
  page42_i255
#ISCELL
  mstr_standard tap *
  page42_i256
#ISCELL
  mstr_standard tap *
  page42_i257
#ISCELL
  mstr_standard tap *
  page42_i258
#ISCELL
  mstr_standard tap *
  page42_i259
#ISCELL
  mstr_standard tap *
  page42_i260
#ISCELL
  mstr_standard tap *
  page42_i261
#ISCELL
  mstr_standard tap *
  page42_i262
#ISCELL
  mstr_standard tap *
  page42_i263
#ISCELL
  mstr_standard tap *
  page42_i264
#ISCELL
  mstr_standard tap *
  page42_i265
#ISCELL
  mstr_standard tap *
  page42_i266
#ISCELL
  mstr_standard tap *
  page42_i267
#ISCELL
  mstr_standard tap *
  page42_i268
#ISCELL
  mstr_standard tap *
  page42_i269
#ISCELL
  mstr_standard tap *
  page42_i270
#ISCELL
  mstr_standard tap *
  page42_i271
#ISCELL
  mstr_standard tap *
  page42_i272
#ISCELL
  mstr_standard tap *
  page42_i273
#ISCELL
  mstr_standard tap *
  page42_i274
#ISCELL
  mstr_standard tap *
  page42_i275
#ISCELL
  mstr_standard tap *
  page42_i276
#ISCELL
  mstr_standard tap *
  page42_i277
#ISCELL
  mstr_standard tap *
  page42_i278
#ISCELL
  mstr_standard tap *
  page42_i279
#ISCELL
  mstr_standard tap *
  page42_i280
#ISCELL
  mstr_standard tap *
  page42_i281
#ISCELL
  mstr_standard tap *
  page42_i282
#ISCELL
  mstr_standard tap *
  page42_i283
#ISCELL
  standard offpage *
  page42_i284
#ISCELL
  standard offpage *
  page42_i285
#ISCELL
  standard offpage *
  page42_i286
#ISCELL
  standard offpage *
  page42_i287
#ISCELL
  mstr_standard tap *
  page42_i288
#ISCELL
  mstr_standard tap *
  page42_i289
#ISCELL
  mstr_standard tap *
  page42_i290
#ISCELL
  mstr_standard tap *
  page42_i291
#ISCELL
  mstr_standard tap *
  page42_i292
#ISCELL
  mstr_standard tap *
  page42_i293
#ISCELL
  mstr_standard tap *
  page42_i294
#ISCELL
  mstr_standard tap *
  page42_i295
#ISCELL
  mstr_standard tap *
  page42_i296
#ISCELL
  mstr_standard tap *
  page42_i297
#ISCELL
  mstr_standard tap *
  page42_i298
#ISCELL
  mstr_standard tap *
  page42_i299
#ISCELL
  mstr_standard tap *
  page42_i300
#ISCELL
  mstr_standard tap *
  page42_i301
#ISCELL
  standard offpage *
  page42_i302
#ISCELL
  standard offpage *
  page42_i303
#ISCELL
  standard offpage *
  page42_i304
#ISCELL
  standard offpage *
  page42_i305
#ISCELL
  standard offpage *
  page42_i306
#ISCELL
  standard offpage *
  page42_i307
#ISCELL
  standard offpage *
  page42_i308
#ISCELL
  mstr_standard offpage *
  page42_i309
#ISCELL
  standard offpage *
  page42_i310
#ISCELL
  standard offpage *
  page42_i311
#ISCELL
  standard offpage *
  page42_i312
#ISCELL
  standard offpage *
  page42_i313
#CELL
  pure_quanta q_res *
  page42_i314
#ISCELL
  standard offpage *
  page42_i315
#ISCELL
  mstr_standard offpage *
  page42_i316
#ISCELL
  pure_quanta quanta_title_block_c *
  *
#ISCELL
  pure_quanta_power cad_note *
  *
#CELL
  pure_quanta genoa_sp5 *
  page43_i167
#ISCELL
  mstr_standard offpage *
  page43_i168
#ISCELL
  mstr_standard offpage *
  page43_i169
#ISCELL
  mstr_standard tap *
  page43_i170
#ISCELL
  mstr_standard tap *
  page43_i171
#ISCELL
  mstr_standard tap *
  page43_i172
#ISCELL
  mstr_standard tap *
  page43_i173
#ISCELL
  mstr_standard tap *
  page43_i174
#ISCELL
  mstr_standard tap *
  page43_i175
#ISCELL
  mstr_standard tap *
  page43_i176
#ISCELL
  mstr_standard tap *
  page43_i177
#ISCELL
  mstr_standard tap *
  page43_i178
#ISCELL
  mstr_standard tap *
  page43_i179
#ISCELL
  mstr_standard tap *
  page43_i180
#ISCELL
  mstr_standard tap *
  page43_i181
#ISCELL
  mstr_standard tap *
  page43_i182
#ISCELL
  mstr_standard tap *
  page43_i183
#ISCELL
  mstr_standard tap *
  page43_i184
#ISCELL
  mstr_standard tap *
  page43_i185
#ISCELL
  mstr_standard tap *
  page43_i186
#ISCELL
  mstr_standard tap *
  page43_i187
#ISCELL
  mstr_standard tap *
  page43_i188
#ISCELL
  mstr_standard tap *
  page43_i189
#ISCELL
  mstr_standard tap *
  page43_i190
#ISCELL
  mstr_standard tap *
  page43_i191
#ISCELL
  mstr_standard tap *
  page43_i192
#ISCELL
  mstr_standard tap *
  page43_i193
#ISCELL
  mstr_standard tap *
  page43_i194
#ISCELL
  mstr_standard tap *
  page43_i195
#ISCELL
  mstr_standard tap *
  page43_i196
#ISCELL
  mstr_standard tap *
  page43_i197
#ISCELL
  mstr_standard tap *
  page43_i198
#ISCELL
  mstr_standard tap *
  page43_i199
#ISCELL
  mstr_standard tap *
  page43_i200
#ISCELL
  mstr_standard tap *
  page43_i201
#ISCELL
  mstr_standard tap *
  page43_i202
#ISCELL
  mstr_standard tap *
  page43_i203
#ISCELL
  mstr_standard tap *
  page43_i204
#ISCELL
  mstr_standard tap *
  page43_i205
#ISCELL
  mstr_standard offpage *
  page43_i206
#ISCELL
  mstr_standard tap *
  page43_i207
#ISCELL
  mstr_standard tap *
  page43_i208
#ISCELL
  mstr_standard tap *
  page43_i209
#ISCELL
  mstr_standard tap *
  page43_i210
#ISCELL
  mstr_standard tap *
  page43_i211
#ISCELL
  mstr_standard tap *
  page43_i212
#ISCELL
  mstr_standard tap *
  page43_i213
#ISCELL
  mstr_standard tap *
  page43_i214
#ISCELL
  mstr_standard tap *
  page43_i215
#ISCELL
  mstr_standard tap *
  page43_i216
#ISCELL
  mstr_standard tap *
  page43_i217
#ISCELL
  mstr_standard tap *
  page43_i218
#ISCELL
  mstr_standard tap *
  page43_i219
#ISCELL
  mstr_standard tap *
  page43_i220
#ISCELL
  mstr_standard tap *
  page43_i221
#ISCELL
  mstr_standard tap *
  page43_i222
#ISCELL
  mstr_standard tap *
  page43_i223
#ISCELL
  mstr_standard tap *
  page43_i224
#ISCELL
  mstr_standard tap *
  page43_i225
#ISCELL
  mstr_standard tap *
  page43_i226
#ISCELL
  mstr_standard tap *
  page43_i227
#ISCELL
  mstr_standard tap *
  page43_i228
#ISCELL
  mstr_standard tap *
  page43_i229
#ISCELL
  mstr_standard tap *
  page43_i230
#ISCELL
  mstr_standard tap *
  page43_i231
#ISCELL
  mstr_standard tap *
  page43_i232
#ISCELL
  mstr_standard tap *
  page43_i233
#ISCELL
  mstr_standard tap *
  page43_i234
#ISCELL
  mstr_standard tap *
  page43_i235
#ISCELL
  mstr_standard tap *
  page43_i236
#ISCELL
  mstr_standard tap *
  page43_i237
#ISCELL
  mstr_standard tap *
  page43_i238
#ISCELL
  mstr_standard tap *
  page43_i239
#ISCELL
  mstr_standard tap *
  page43_i240
#ISCELL
  mstr_standard tap *
  page43_i241
#ISCELL
  mstr_standard tap *
  page43_i242
#ISCELL
  mstr_standard offpage *
  page43_i243
#ISCELL
  mstr_standard tap *
  page43_i244
#ISCELL
  mstr_standard tap *
  page43_i245
#ISCELL
  mstr_standard tap *
  page43_i246
#ISCELL
  mstr_standard tap *
  page43_i247
#ISCELL
  mstr_standard tap *
  page43_i248
#ISCELL
  mstr_standard tap *
  page43_i249
#ISCELL
  mstr_standard tap *
  page43_i250
#ISCELL
  mstr_standard tap *
  page43_i251
#ISCELL
  mstr_standard tap *
  page43_i252
#ISCELL
  mstr_standard tap *
  page43_i253
#ISCELL
  mstr_standard tap *
  page43_i254
#ISCELL
  mstr_standard tap *
  page43_i255
#ISCELL
  mstr_standard tap *
  page43_i256
#ISCELL
  mstr_standard tap *
  page43_i257
#ISCELL
  mstr_standard tap *
  page43_i258
#ISCELL
  mstr_standard tap *
  page43_i259
#ISCELL
  mstr_standard tap *
  page43_i260
#ISCELL
  mstr_standard tap *
  page43_i261
#ISCELL
  mstr_standard tap *
  page43_i262
#ISCELL
  mstr_standard tap *
  page43_i263
#ISCELL
  mstr_standard tap *
  page43_i264
#ISCELL
  mstr_standard tap *
  page43_i265
#ISCELL
  mstr_standard tap *
  page43_i266
#ISCELL
  mstr_standard tap *
  page43_i267
#ISCELL
  mstr_standard tap *
  page43_i268
#ISCELL
  mstr_standard tap *
  page43_i269
#ISCELL
  mstr_standard tap *
  page43_i270
#ISCELL
  mstr_standard tap *
  page43_i271
#ISCELL
  mstr_standard tap *
  page43_i272
#ISCELL
  mstr_standard tap *
  page43_i273
#ISCELL
  mstr_standard tap *
  page43_i274
#ISCELL
  mstr_standard tap *
  page43_i275
#ISCELL
  mstr_standard tap *
  page43_i276
#ISCELL
  mstr_standard tap *
  page43_i277
#ISCELL
  mstr_standard tap *
  page43_i278
#ISCELL
  mstr_standard tap *
  page43_i279
#ISCELL
  mstr_standard tap *
  page43_i280
#ISCELL
  mstr_standard tap *
  page43_i281
#ISCELL
  mstr_standard tap *
  page43_i282
#ISCELL
  mstr_standard tap *
  page43_i283
#ISCELL
  mstr_standard tap *
  page43_i284
#ISCELL
  mstr_standard tap *
  page43_i285
#ISCELL
  mstr_standard tap *
  page43_i286
#ISCELL
  mstr_standard tap *
  page43_i287
#ISCELL
  mstr_standard tap *
  page43_i288
#ISCELL
  mstr_standard tap *
  page43_i289
#ISCELL
  mstr_standard tap *
  page43_i290
#ISCELL
  standard offpage *
  page43_i291
#ISCELL
  standard offpage *
  page43_i292
#ISCELL
  standard offpage *
  page43_i293
#ISCELL
  standard offpage *
  page43_i294
#ISCELL
  mstr_standard tap *
  page43_i295
#ISCELL
  mstr_standard tap *
  page43_i296
#ISCELL
  mstr_standard tap *
  page43_i297
#ISCELL
  mstr_standard tap *
  page43_i298
#ISCELL
  mstr_standard tap *
  page43_i299
#ISCELL
  mstr_standard tap *
  page43_i300
#ISCELL
  mstr_standard tap *
  page43_i301
#ISCELL
  mstr_standard tap *
  page43_i302
#ISCELL
  mstr_standard tap *
  page43_i303
#ISCELL
  mstr_standard tap *
  page43_i304
#ISCELL
  mstr_standard tap *
  page43_i305
#ISCELL
  mstr_standard tap *
  page43_i306
#ISCELL
  mstr_standard tap *
  page43_i307
#ISCELL
  mstr_standard tap *
  page43_i308
#ISCELL
  mstr_standard tap *
  page43_i309
#ISCELL
  standard offpage *
  page43_i310
#ISCELL
  standard offpage *
  page43_i311
#ISCELL
  standard offpage *
  page43_i312
#ISCELL
  standard offpage *
  page43_i313
#ISCELL
  standard offpage *
  page43_i314
#ISCELL
  standard offpage *
  page43_i315
#ISCELL
  mstr_standard offpage *
  page43_i316
#ISCELL
  standard offpage *
  page43_i317
#ISCELL
  standard offpage *
  page43_i318
#ISCELL
  standard offpage *
  page43_i319
#ISCELL
  standard offpage *
  page43_i320
#ISCELL
  standard offpage *
  page43_i321
#CELL
  pure_quanta q_res *
  page43_i322
#ISCELL
  standard offpage *
  page43_i323
#ISCELL
  mstr_standard offpage *
  page43_i324
#ISCELL
  pure_quanta quanta_title_block_c *
  *
#ISCELL
  pure_quanta_power cad_note *
  *
#CELL
  pure_quanta genoa_sp5 *
  page44_i159
#ISCELL
  mstr_standard offpage *
  page44_i160
#ISCELL
  mstr_standard tap *
  page44_i161
#ISCELL
  mstr_standard tap *
  page44_i162
#ISCELL
  mstr_standard tap *
  page44_i163
#ISCELL
  mstr_standard tap *
  page44_i164
#ISCELL
  mstr_standard tap *
  page44_i165
#ISCELL
  mstr_standard tap *
  page44_i166
#ISCELL
  mstr_standard tap *
  page44_i167
#ISCELL
  mstr_standard tap *
  page44_i168
#ISCELL
  mstr_standard tap *
  page44_i169
#ISCELL
  mstr_standard tap *
  page44_i170
#ISCELL
  mstr_standard tap *
  page44_i171
#ISCELL
  mstr_standard tap *
  page44_i172
#ISCELL
  mstr_standard tap *
  page44_i173
#ISCELL
  mstr_standard tap *
  page44_i174
#ISCELL
  mstr_standard tap *
  page44_i175
#ISCELL
  mstr_standard tap *
  page44_i176
#ISCELL
  mstr_standard tap *
  page44_i177
#ISCELL
  mstr_standard tap *
  page44_i178
#ISCELL
  mstr_standard tap *
  page44_i179
#ISCELL
  mstr_standard tap *
  page44_i180
#ISCELL
  mstr_standard tap *
  page44_i181
#ISCELL
  mstr_standard tap *
  page44_i182
#ISCELL
  mstr_standard tap *
  page44_i183
#ISCELL
  mstr_standard tap *
  page44_i184
#ISCELL
  mstr_standard tap *
  page44_i185
#ISCELL
  mstr_standard tap *
  page44_i186
#ISCELL
  mstr_standard tap *
  page44_i187
#ISCELL
  mstr_standard tap *
  page44_i188
#ISCELL
  mstr_standard tap *
  page44_i189
#ISCELL
  mstr_standard tap *
  page44_i190
#ISCELL
  mstr_standard tap *
  page44_i191
#ISCELL
  mstr_standard tap *
  page44_i192
#ISCELL
  mstr_standard tap *
  page44_i193
#ISCELL
  mstr_standard offpage *
  page44_i194
#ISCELL
  mstr_standard offpage *
  page44_i195
#ISCELL
  mstr_standard tap *
  page44_i196
#ISCELL
  mstr_standard tap *
  page44_i197
#ISCELL
  mstr_standard tap *
  page44_i198
#ISCELL
  mstr_standard tap *
  page44_i199
#ISCELL
  mstr_standard tap *
  page44_i200
#ISCELL
  mstr_standard tap *
  page44_i201
#ISCELL
  mstr_standard tap *
  page44_i202
#ISCELL
  mstr_standard tap *
  page44_i203
#ISCELL
  mstr_standard tap *
  page44_i204
#ISCELL
  mstr_standard tap *
  page44_i205
#ISCELL
  mstr_standard tap *
  page44_i206
#ISCELL
  mstr_standard tap *
  page44_i207
#ISCELL
  mstr_standard tap *
  page44_i208
#ISCELL
  mstr_standard tap *
  page44_i209
#ISCELL
  mstr_standard tap *
  page44_i210
#ISCELL
  mstr_standard tap *
  page44_i211
#ISCELL
  mstr_standard tap *
  page44_i212
#ISCELL
  mstr_standard tap *
  page44_i213
#ISCELL
  mstr_standard tap *
  page44_i214
#ISCELL
  mstr_standard tap *
  page44_i215
#ISCELL
  mstr_standard tap *
  page44_i216
#ISCELL
  mstr_standard tap *
  page44_i217
#ISCELL
  mstr_standard tap *
  page44_i218
#ISCELL
  mstr_standard tap *
  page44_i219
#ISCELL
  mstr_standard tap *
  page44_i220
#ISCELL
  mstr_standard tap *
  page44_i221
#ISCELL
  mstr_standard tap *
  page44_i222
#ISCELL
  mstr_standard tap *
  page44_i223
#ISCELL
  mstr_standard tap *
  page44_i224
#ISCELL
  mstr_standard tap *
  page44_i225
#ISCELL
  mstr_standard tap *
  page44_i226
#ISCELL
  mstr_standard tap *
  page44_i227
#ISCELL
  mstr_standard tap *
  page44_i228
#ISCELL
  mstr_standard tap *
  page44_i229
#ISCELL
  mstr_standard tap *
  page44_i230
#ISCELL
  mstr_standard tap *
  page44_i231
#ISCELL
  mstr_standard tap *
  page44_i232
#ISCELL
  mstr_standard offpage *
  page44_i233
#ISCELL
  mstr_standard tap *
  page44_i234
#ISCELL
  mstr_standard tap *
  page44_i235
#ISCELL
  mstr_standard tap *
  page44_i236
#ISCELL
  mstr_standard tap *
  page44_i237
#ISCELL
  mstr_standard tap *
  page44_i238
#ISCELL
  mstr_standard tap *
  page44_i239
#ISCELL
  mstr_standard tap *
  page44_i240
#ISCELL
  mstr_standard tap *
  page44_i241
#ISCELL
  mstr_standard tap *
  page44_i242
#ISCELL
  mstr_standard tap *
  page44_i243
#ISCELL
  mstr_standard tap *
  page44_i244
#ISCELL
  mstr_standard tap *
  page44_i245
#ISCELL
  mstr_standard tap *
  page44_i246
#ISCELL
  mstr_standard tap *
  page44_i247
#ISCELL
  mstr_standard tap *
  page44_i248
#ISCELL
  mstr_standard tap *
  page44_i249
#ISCELL
  mstr_standard tap *
  page44_i250
#ISCELL
  mstr_standard tap *
  page44_i251
#ISCELL
  mstr_standard tap *
  page44_i252
#ISCELL
  mstr_standard tap *
  page44_i253
#ISCELL
  mstr_standard tap *
  page44_i254
#ISCELL
  mstr_standard tap *
  page44_i255
#ISCELL
  mstr_standard tap *
  page44_i256
#ISCELL
  mstr_standard tap *
  page44_i257
#ISCELL
  mstr_standard tap *
  page44_i258
#ISCELL
  mstr_standard tap *
  page44_i259
#ISCELL
  mstr_standard tap *
  page44_i260
#ISCELL
  mstr_standard tap *
  page44_i261
#ISCELL
  mstr_standard tap *
  page44_i262
#ISCELL
  mstr_standard tap *
  page44_i263
#ISCELL
  mstr_standard tap *
  page44_i264
#ISCELL
  mstr_standard tap *
  page44_i265
#ISCELL
  mstr_standard tap *
  page44_i266
#ISCELL
  mstr_standard tap *
  page44_i267
#ISCELL
  mstr_standard tap *
  page44_i268
#ISCELL
  mstr_standard tap *
  page44_i269
#ISCELL
  mstr_standard tap *
  page44_i270
#ISCELL
  mstr_standard tap *
  page44_i271
#ISCELL
  mstr_standard tap *
  page44_i272
#ISCELL
  mstr_standard tap *
  page44_i273
#ISCELL
  mstr_standard tap *
  page44_i274
#ISCELL
  mstr_standard tap *
  page44_i275
#ISCELL
  mstr_standard tap *
  page44_i276
#ISCELL
  mstr_standard tap *
  page44_i277
#ISCELL
  mstr_standard tap *
  page44_i278
#ISCELL
  mstr_standard tap *
  page44_i279
#ISCELL
  standard offpage *
  page44_i280
#ISCELL
  standard offpage *
  page44_i281
#ISCELL
  standard offpage *
  page44_i282
#ISCELL
  standard offpage *
  page44_i283
#ISCELL
  mstr_standard tap *
  page44_i284
#ISCELL
  mstr_standard tap *
  page44_i285
#ISCELL
  mstr_standard tap *
  page44_i286
#ISCELL
  mstr_standard tap *
  page44_i287
#ISCELL
  mstr_standard tap *
  page44_i288
#ISCELL
  mstr_standard tap *
  page44_i289
#ISCELL
  mstr_standard tap *
  page44_i290
#ISCELL
  mstr_standard tap *
  page44_i291
#ISCELL
  mstr_standard tap *
  page44_i292
#ISCELL
  mstr_standard tap *
  page44_i293
#ISCELL
  mstr_standard tap *
  page44_i294
#ISCELL
  mstr_standard tap *
  page44_i295
#ISCELL
  mstr_standard tap *
  page44_i296
#ISCELL
  mstr_standard tap *
  page44_i297
#ISCELL
  mstr_standard tap *
  page44_i298
#ISCELL
  mstr_standard tap *
  page44_i299
#ISCELL
  mstr_standard tap *
  page44_i300
#ISCELL
  mstr_standard tap *
  page44_i301
#ISCELL
  standard offpage *
  page44_i302
#ISCELL
  standard offpage *
  page44_i303
#ISCELL
  standard offpage *
  page44_i304
#ISCELL
  standard offpage *
  page44_i305
#ISCELL
  standard offpage *
  page44_i306
#ISCELL
  standard offpage *
  page44_i307
#ISCELL
  standard offpage *
  page44_i308
#ISCELL
  mstr_standard offpage *
  page44_i309
#ISCELL
  standard offpage *
  page44_i310
#ISCELL
  standard offpage *
  page44_i311
#ISCELL
  standard offpage *
  page44_i312
#ISCELL
  standard offpage *
  page44_i313
#CELL
  pure_quanta q_res *
  page44_i314
#ISCELL
  standard offpage *
  page44_i315
#ISCELL
  mstr_standard offpage *
  page44_i316
#ISCELL
  pure_quanta quanta_title_block_c *
  *
#ISCELL
  pure_quanta_power cad_note *
  *
#CELL
  pure_quanta genoa_sp5 *
  page45_i159
#ISCELL
  mstr_standard offpage *
  page45_i160
#ISCELL
  mstr_standard offpage *
  page45_i161
#ISCELL
  mstr_standard tap *
  page45_i162
#ISCELL
  mstr_standard tap *
  page45_i163
#ISCELL
  mstr_standard tap *
  page45_i164
#ISCELL
  mstr_standard tap *
  page45_i165
#ISCELL
  mstr_standard tap *
  page45_i166
#ISCELL
  mstr_standard tap *
  page45_i167
#ISCELL
  mstr_standard tap *
  page45_i168
#ISCELL
  mstr_standard tap *
  page45_i169
#ISCELL
  mstr_standard tap *
  page45_i170
#ISCELL
  mstr_standard tap *
  page45_i171
#ISCELL
  mstr_standard tap *
  page45_i172
#ISCELL
  mstr_standard tap *
  page45_i173
#ISCELL
  mstr_standard tap *
  page45_i174
#ISCELL
  mstr_standard tap *
  page45_i175
#ISCELL
  mstr_standard tap *
  page45_i176
#ISCELL
  mstr_standard tap *
  page45_i177
#ISCELL
  mstr_standard tap *
  page45_i178
#ISCELL
  mstr_standard tap *
  page45_i179
#ISCELL
  mstr_standard tap *
  page45_i180
#ISCELL
  mstr_standard tap *
  page45_i181
#ISCELL
  mstr_standard tap *
  page45_i182
#ISCELL
  mstr_standard tap *
  page45_i183
#ISCELL
  mstr_standard tap *
  page45_i184
#ISCELL
  mstr_standard tap *
  page45_i185
#ISCELL
  mstr_standard tap *
  page45_i186
#ISCELL
  mstr_standard tap *
  page45_i187
#ISCELL
  mstr_standard tap *
  page45_i188
#ISCELL
  mstr_standard tap *
  page45_i189
#ISCELL
  mstr_standard tap *
  page45_i190
#ISCELL
  mstr_standard tap *
  page45_i191
#ISCELL
  mstr_standard tap *
  page45_i192
#ISCELL
  mstr_standard tap *
  page45_i193
#ISCELL
  mstr_standard tap *
  page45_i194
#ISCELL
  mstr_standard tap *
  page45_i195
#ISCELL
  mstr_standard offpage *
  page45_i196
#ISCELL
  mstr_standard tap *
  page45_i197
#ISCELL
  mstr_standard tap *
  page45_i198
#ISCELL
  mstr_standard tap *
  page45_i199
#ISCELL
  mstr_standard tap *
  page45_i200
#ISCELL
  mstr_standard tap *
  page45_i201
#ISCELL
  mstr_standard tap *
  page45_i202
#ISCELL
  mstr_standard tap *
  page45_i203
#ISCELL
  mstr_standard tap *
  page45_i204
#ISCELL
  mstr_standard tap *
  page45_i205
#ISCELL
  mstr_standard tap *
  page45_i206
#ISCELL
  mstr_standard tap *
  page45_i207
#ISCELL
  mstr_standard tap *
  page45_i208
#ISCELL
  mstr_standard tap *
  page45_i209
#ISCELL
  mstr_standard tap *
  page45_i210
#ISCELL
  mstr_standard tap *
  page45_i211
#ISCELL
  mstr_standard tap *
  page45_i212
#ISCELL
  mstr_standard tap *
  page45_i213
#ISCELL
  mstr_standard tap *
  page45_i214
#ISCELL
  mstr_standard tap *
  page45_i215
#ISCELL
  mstr_standard tap *
  page45_i216
#ISCELL
  mstr_standard tap *
  page45_i217
#ISCELL
  mstr_standard tap *
  page45_i218
#ISCELL
  mstr_standard tap *
  page45_i219
#ISCELL
  mstr_standard tap *
  page45_i220
#ISCELL
  mstr_standard tap *
  page45_i221
#ISCELL
  mstr_standard tap *
  page45_i222
#ISCELL
  mstr_standard tap *
  page45_i223
#ISCELL
  mstr_standard tap *
  page45_i224
#ISCELL
  mstr_standard tap *
  page45_i225
#ISCELL
  mstr_standard tap *
  page45_i226
#ISCELL
  mstr_standard tap *
  page45_i227
#ISCELL
  mstr_standard tap *
  page45_i228
#ISCELL
  mstr_standard tap *
  page45_i229
#ISCELL
  mstr_standard tap *
  page45_i230
#ISCELL
  mstr_standard tap *
  page45_i231
#ISCELL
  mstr_standard tap *
  page45_i232
#ISCELL
  mstr_standard tap *
  page45_i233
#ISCELL
  mstr_standard offpage *
  page45_i234
#ISCELL
  mstr_standard tap *
  page45_i235
#ISCELL
  mstr_standard tap *
  page45_i236
#ISCELL
  mstr_standard tap *
  page45_i237
#ISCELL
  mstr_standard tap *
  page45_i238
#ISCELL
  mstr_standard tap *
  page45_i239
#ISCELL
  mstr_standard tap *
  page45_i240
#ISCELL
  mstr_standard tap *
  page45_i241
#ISCELL
  mstr_standard tap *
  page45_i242
#ISCELL
  mstr_standard tap *
  page45_i243
#ISCELL
  mstr_standard tap *
  page45_i244
#ISCELL
  mstr_standard tap *
  page45_i245
#ISCELL
  mstr_standard tap *
  page45_i246
#ISCELL
  mstr_standard tap *
  page45_i247
#ISCELL
  mstr_standard tap *
  page45_i248
#ISCELL
  mstr_standard tap *
  page45_i249
#ISCELL
  mstr_standard tap *
  page45_i250
#ISCELL
  mstr_standard tap *
  page45_i251
#ISCELL
  mstr_standard tap *
  page45_i252
#ISCELL
  mstr_standard tap *
  page45_i253
#ISCELL
  mstr_standard tap *
  page45_i254
#ISCELL
  mstr_standard tap *
  page45_i255
#ISCELL
  mstr_standard tap *
  page45_i256
#ISCELL
  mstr_standard tap *
  page45_i257
#ISCELL
  mstr_standard tap *
  page45_i258
#ISCELL
  mstr_standard tap *
  page45_i259
#ISCELL
  mstr_standard tap *
  page45_i260
#ISCELL
  mstr_standard tap *
  page45_i261
#ISCELL
  mstr_standard tap *
  page45_i262
#ISCELL
  mstr_standard tap *
  page45_i263
#ISCELL
  mstr_standard tap *
  page45_i264
#ISCELL
  mstr_standard tap *
  page45_i265
#ISCELL
  mstr_standard tap *
  page45_i266
#ISCELL
  mstr_standard tap *
  page45_i267
#ISCELL
  mstr_standard tap *
  page45_i268
#ISCELL
  mstr_standard tap *
  page45_i269
#ISCELL
  mstr_standard tap *
  page45_i270
#ISCELL
  mstr_standard tap *
  page45_i271
#ISCELL
  mstr_standard tap *
  page45_i272
#ISCELL
  mstr_standard tap *
  page45_i273
#ISCELL
  mstr_standard tap *
  page45_i274
#ISCELL
  mstr_standard tap *
  page45_i275
#ISCELL
  mstr_standard tap *
  page45_i276
#ISCELL
  mstr_standard tap *
  page45_i277
#ISCELL
  mstr_standard tap *
  page45_i278
#ISCELL
  mstr_standard tap *
  page45_i279
#ISCELL
  mstr_standard tap *
  page45_i280
#ISCELL
  standard offpage *
  page45_i281
#ISCELL
  standard offpage *
  page45_i282
#ISCELL
  standard offpage *
  page45_i283
#ISCELL
  standard offpage *
  page45_i284
#ISCELL
  mstr_standard tap *
  page45_i285
#ISCELL
  mstr_standard tap *
  page45_i286
#ISCELL
  mstr_standard tap *
  page45_i287
#ISCELL
  mstr_standard tap *
  page45_i288
#ISCELL
  mstr_standard tap *
  page45_i289
#ISCELL
  mstr_standard tap *
  page45_i290
#ISCELL
  mstr_standard tap *
  page45_i291
#ISCELL
  mstr_standard tap *
  page45_i292
#ISCELL
  mstr_standard tap *
  page45_i293
#ISCELL
  mstr_standard tap *
  page45_i294
#ISCELL
  mstr_standard tap *
  page45_i295
#ISCELL
  mstr_standard tap *
  page45_i296
#ISCELL
  mstr_standard tap *
  page45_i297
#ISCELL
  mstr_standard tap *
  page45_i298
#ISCELL
  mstr_standard tap *
  page45_i299
#ISCELL
  mstr_standard tap *
  page45_i300
#ISCELL
  mstr_standard tap *
  page45_i301
#ISCELL
  standard offpage *
  page45_i302
#ISCELL
  standard offpage *
  page45_i303
#ISCELL
  standard offpage *
  page45_i304
#ISCELL
  standard offpage *
  page45_i305
#ISCELL
  standard offpage *
  page45_i306
#ISCELL
  standard offpage *
  page45_i307
#ISCELL
  standard offpage *
  page45_i308
#ISCELL
  mstr_standard offpage *
  page45_i309
#ISCELL
  standard offpage *
  page45_i310
#ISCELL
  standard offpage *
  page45_i311
#ISCELL
  standard offpage *
  page45_i312
#ISCELL
  standard offpage *
  page45_i313
#CELL
  pure_quanta q_res *
  page45_i314
#ISCELL
  mstr_standard offpage *
  page45_i315
#ISCELL
  standard offpage *
  page45_i316
#ISCELL
  pure_quanta quanta_title_block_c *
  *
#ISCELL
  pure_quanta_power cad_note *
  *
#CELL
  pure_quanta genoa_sp5 *
  page46_i159
#ISCELL
  mstr_standard offpage *
  page46_i160
#ISCELL
  mstr_standard tap *
  page46_i161
#ISCELL
  mstr_standard tap *
  page46_i162
#ISCELL
  mstr_standard tap *
  page46_i163
#ISCELL
  mstr_standard tap *
  page46_i164
#ISCELL
  mstr_standard tap *
  page46_i165
#ISCELL
  mstr_standard tap *
  page46_i166
#ISCELL
  mstr_standard tap *
  page46_i167
#ISCELL
  mstr_standard tap *
  page46_i168
#ISCELL
  mstr_standard tap *
  page46_i169
#ISCELL
  mstr_standard tap *
  page46_i170
#ISCELL
  mstr_standard tap *
  page46_i171
#ISCELL
  mstr_standard tap *
  page46_i172
#ISCELL
  mstr_standard tap *
  page46_i173
#ISCELL
  mstr_standard tap *
  page46_i174
#ISCELL
  mstr_standard tap *
  page46_i175
#ISCELL
  mstr_standard tap *
  page46_i176
#ISCELL
  mstr_standard tap *
  page46_i177
#ISCELL
  mstr_standard tap *
  page46_i178
#ISCELL
  mstr_standard tap *
  page46_i179
#ISCELL
  mstr_standard tap *
  page46_i180
#ISCELL
  mstr_standard tap *
  page46_i181
#ISCELL
  mstr_standard tap *
  page46_i182
#ISCELL
  mstr_standard tap *
  page46_i183
#ISCELL
  mstr_standard tap *
  page46_i184
#ISCELL
  mstr_standard tap *
  page46_i185
#ISCELL
  mstr_standard tap *
  page46_i186
#ISCELL
  mstr_standard tap *
  page46_i187
#ISCELL
  mstr_standard tap *
  page46_i188
#ISCELL
  mstr_standard tap *
  page46_i189
#ISCELL
  mstr_standard tap *
  page46_i190
#ISCELL
  mstr_standard tap *
  page46_i191
#ISCELL
  mstr_standard tap *
  page46_i192
#ISCELL
  mstr_standard tap *
  page46_i193
#ISCELL
  mstr_standard offpage *
  page46_i194
#ISCELL
  mstr_standard offpage *
  page46_i195
#ISCELL
  mstr_standard tap *
  page46_i196
#ISCELL
  mstr_standard tap *
  page46_i197
#ISCELL
  mstr_standard tap *
  page46_i198
#ISCELL
  mstr_standard tap *
  page46_i199
#ISCELL
  mstr_standard tap *
  page46_i200
#ISCELL
  mstr_standard tap *
  page46_i201
#ISCELL
  mstr_standard tap *
  page46_i202
#ISCELL
  mstr_standard tap *
  page46_i203
#ISCELL
  mstr_standard tap *
  page46_i204
#ISCELL
  mstr_standard tap *
  page46_i205
#ISCELL
  mstr_standard tap *
  page46_i206
#ISCELL
  mstr_standard tap *
  page46_i207
#ISCELL
  mstr_standard tap *
  page46_i208
#ISCELL
  mstr_standard tap *
  page46_i209
#ISCELL
  mstr_standard tap *
  page46_i210
#ISCELL
  mstr_standard tap *
  page46_i211
#ISCELL
  mstr_standard tap *
  page46_i212
#ISCELL
  mstr_standard tap *
  page46_i213
#ISCELL
  mstr_standard tap *
  page46_i214
#ISCELL
  mstr_standard tap *
  page46_i215
#ISCELL
  mstr_standard tap *
  page46_i216
#ISCELL
  mstr_standard tap *
  page46_i217
#ISCELL
  mstr_standard tap *
  page46_i218
#ISCELL
  mstr_standard tap *
  page46_i219
#ISCELL
  mstr_standard tap *
  page46_i220
#ISCELL
  mstr_standard tap *
  page46_i221
#ISCELL
  mstr_standard tap *
  page46_i222
#ISCELL
  mstr_standard tap *
  page46_i223
#ISCELL
  mstr_standard tap *
  page46_i224
#ISCELL
  mstr_standard tap *
  page46_i225
#ISCELL
  mstr_standard tap *
  page46_i226
#ISCELL
  mstr_standard tap *
  page46_i227
#ISCELL
  mstr_standard tap *
  page46_i228
#ISCELL
  mstr_standard tap *
  page46_i229
#ISCELL
  mstr_standard tap *
  page46_i230
#ISCELL
  mstr_standard tap *
  page46_i231
#ISCELL
  mstr_standard tap *
  page46_i232
#ISCELL
  mstr_standard offpage *
  page46_i233
#ISCELL
  mstr_standard tap *
  page46_i234
#ISCELL
  mstr_standard tap *
  page46_i235
#ISCELL
  mstr_standard tap *
  page46_i236
#ISCELL
  mstr_standard tap *
  page46_i237
#ISCELL
  mstr_standard tap *
  page46_i238
#ISCELL
  mstr_standard tap *
  page46_i239
#ISCELL
  mstr_standard tap *
  page46_i240
#ISCELL
  mstr_standard tap *
  page46_i241
#ISCELL
  mstr_standard tap *
  page46_i242
#ISCELL
  mstr_standard tap *
  page46_i243
#ISCELL
  mstr_standard tap *
  page46_i244
#ISCELL
  mstr_standard tap *
  page46_i245
#ISCELL
  mstr_standard tap *
  page46_i246
#ISCELL
  mstr_standard tap *
  page46_i247
#ISCELL
  mstr_standard tap *
  page46_i248
#ISCELL
  mstr_standard tap *
  page46_i249
#ISCELL
  mstr_standard tap *
  page46_i250
#ISCELL
  mstr_standard tap *
  page46_i251
#ISCELL
  mstr_standard tap *
  page46_i252
#ISCELL
  mstr_standard tap *
  page46_i253
#ISCELL
  mstr_standard tap *
  page46_i254
#ISCELL
  mstr_standard tap *
  page46_i255
#ISCELL
  mstr_standard tap *
  page46_i256
#ISCELL
  mstr_standard tap *
  page46_i257
#ISCELL
  mstr_standard tap *
  page46_i258
#ISCELL
  mstr_standard tap *
  page46_i259
#ISCELL
  mstr_standard tap *
  page46_i260
#ISCELL
  mstr_standard tap *
  page46_i261
#ISCELL
  mstr_standard tap *
  page46_i262
#ISCELL
  mstr_standard tap *
  page46_i263
#ISCELL
  mstr_standard tap *
  page46_i264
#ISCELL
  mstr_standard tap *
  page46_i265
#ISCELL
  mstr_standard tap *
  page46_i266
#ISCELL
  mstr_standard tap *
  page46_i267
#ISCELL
  mstr_standard tap *
  page46_i268
#ISCELL
  mstr_standard tap *
  page46_i269
#ISCELL
  mstr_standard tap *
  page46_i270
#ISCELL
  mstr_standard tap *
  page46_i271
#ISCELL
  mstr_standard tap *
  page46_i272
#ISCELL
  mstr_standard tap *
  page46_i273
#ISCELL
  mstr_standard tap *
  page46_i274
#ISCELL
  mstr_standard tap *
  page46_i275
#ISCELL
  mstr_standard tap *
  page46_i276
#ISCELL
  mstr_standard tap *
  page46_i277
#ISCELL
  mstr_standard tap *
  page46_i278
#ISCELL
  mstr_standard tap *
  page46_i279
#ISCELL
  standard offpage *
  page46_i280
#ISCELL
  standard offpage *
  page46_i281
#ISCELL
  standard offpage *
  page46_i282
#ISCELL
  standard offpage *
  page46_i283
#ISCELL
  mstr_standard tap *
  page46_i284
#ISCELL
  mstr_standard tap *
  page46_i285
#ISCELL
  mstr_standard tap *
  page46_i286
#ISCELL
  mstr_standard tap *
  page46_i287
#ISCELL
  mstr_standard tap *
  page46_i288
#ISCELL
  mstr_standard tap *
  page46_i289
#ISCELL
  mstr_standard tap *
  page46_i290
#ISCELL
  mstr_standard tap *
  page46_i291
#ISCELL
  mstr_standard tap *
  page46_i292
#ISCELL
  mstr_standard tap *
  page46_i293
#ISCELL
  mstr_standard tap *
  page46_i294
#ISCELL
  mstr_standard tap *
  page46_i295
#ISCELL
  mstr_standard tap *
  page46_i296
#ISCELL
  mstr_standard tap *
  page46_i297
#ISCELL
  mstr_standard tap *
  page46_i298
#ISCELL
  mstr_standard tap *
  page46_i299
#ISCELL
  mstr_standard tap *
  page46_i300
#ISCELL
  mstr_standard tap *
  page46_i301
#ISCELL
  standard offpage *
  page46_i302
#ISCELL
  standard offpage *
  page46_i303
#ISCELL
  standard offpage *
  page46_i304
#ISCELL
  standard offpage *
  page46_i305
#ISCELL
  standard offpage *
  page46_i306
#ISCELL
  standard offpage *
  page46_i307
#ISCELL
  standard offpage *
  page46_i308
#ISCELL
  standard offpage *
  page46_i309
#ISCELL
  standard offpage *
  page46_i310
#ISCELL
  mstr_standard offpage *
  page46_i311
#ISCELL
  standard offpage *
  page46_i312
#ISCELL
  standard offpage *
  page46_i313
#CELL
  pure_quanta q_res *
  page46_i314
#ISCELL
  standard offpage *
  page46_i315
#ISCELL
  mstr_standard offpage *
  page46_i316
#ISCELL
  pure_quanta quanta_title_block_c *
  *
#ISCELL
  pure_quanta_power cad_note *
  *
#CELL
  pure_quanta genoa_sp5 *
  page47_i159
#ISCELL
  mstr_standard offpage *
  page47_i160
#ISCELL
  mstr_standard tap *
  page47_i161
#ISCELL
  mstr_standard tap *
  page47_i162
#ISCELL
  mstr_standard tap *
  page47_i163
#ISCELL
  mstr_standard tap *
  page47_i164
#ISCELL
  mstr_standard tap *
  page47_i165
#ISCELL
  mstr_standard tap *
  page47_i166
#ISCELL
  mstr_standard tap *
  page47_i167
#ISCELL
  mstr_standard tap *
  page47_i168
#ISCELL
  mstr_standard tap *
  page47_i169
#ISCELL
  mstr_standard tap *
  page47_i170
#ISCELL
  mstr_standard tap *
  page47_i171
#ISCELL
  mstr_standard tap *
  page47_i172
#ISCELL
  mstr_standard tap *
  page47_i173
#ISCELL
  mstr_standard tap *
  page47_i174
#ISCELL
  mstr_standard tap *
  page47_i175
#ISCELL
  mstr_standard tap *
  page47_i176
#ISCELL
  mstr_standard tap *
  page47_i177
#ISCELL
  mstr_standard tap *
  page47_i178
#ISCELL
  mstr_standard tap *
  page47_i179
#ISCELL
  mstr_standard tap *
  page47_i180
#ISCELL
  mstr_standard tap *
  page47_i181
#ISCELL
  mstr_standard tap *
  page47_i182
#ISCELL
  mstr_standard tap *
  page47_i183
#ISCELL
  mstr_standard tap *
  page47_i184
#ISCELL
  mstr_standard tap *
  page47_i185
#ISCELL
  mstr_standard tap *
  page47_i186
#ISCELL
  mstr_standard tap *
  page47_i187
#ISCELL
  mstr_standard tap *
  page47_i188
#ISCELL
  mstr_standard tap *
  page47_i189
#ISCELL
  mstr_standard tap *
  page47_i190
#ISCELL
  mstr_standard tap *
  page47_i191
#ISCELL
  mstr_standard tap *
  page47_i192
#ISCELL
  mstr_standard tap *
  page47_i193
#ISCELL
  mstr_standard offpage *
  page47_i194
#ISCELL
  mstr_standard offpage *
  page47_i195
#ISCELL
  mstr_standard tap *
  page47_i196
#ISCELL
  mstr_standard tap *
  page47_i197
#ISCELL
  mstr_standard tap *
  page47_i198
#ISCELL
  mstr_standard tap *
  page47_i199
#ISCELL
  mstr_standard tap *
  page47_i200
#ISCELL
  mstr_standard tap *
  page47_i201
#ISCELL
  mstr_standard tap *
  page47_i202
#ISCELL
  mstr_standard tap *
  page47_i203
#ISCELL
  mstr_standard tap *
  page47_i204
#ISCELL
  mstr_standard tap *
  page47_i205
#ISCELL
  mstr_standard tap *
  page47_i206
#ISCELL
  mstr_standard tap *
  page47_i207
#ISCELL
  mstr_standard tap *
  page47_i208
#ISCELL
  mstr_standard tap *
  page47_i209
#ISCELL
  mstr_standard tap *
  page47_i210
#ISCELL
  mstr_standard tap *
  page47_i211
#ISCELL
  mstr_standard tap *
  page47_i212
#ISCELL
  mstr_standard tap *
  page47_i213
#ISCELL
  mstr_standard tap *
  page47_i214
#ISCELL
  mstr_standard tap *
  page47_i215
#ISCELL
  mstr_standard tap *
  page47_i216
#ISCELL
  mstr_standard tap *
  page47_i217
#ISCELL
  mstr_standard tap *
  page47_i218
#ISCELL
  mstr_standard tap *
  page47_i219
#ISCELL
  mstr_standard tap *
  page47_i220
#ISCELL
  mstr_standard tap *
  page47_i221
#ISCELL
  mstr_standard tap *
  page47_i222
#ISCELL
  mstr_standard tap *
  page47_i223
#ISCELL
  mstr_standard tap *
  page47_i224
#ISCELL
  mstr_standard tap *
  page47_i225
#ISCELL
  mstr_standard tap *
  page47_i226
#ISCELL
  mstr_standard tap *
  page47_i227
#ISCELL
  mstr_standard tap *
  page47_i228
#ISCELL
  mstr_standard tap *
  page47_i229
#ISCELL
  mstr_standard tap *
  page47_i230
#ISCELL
  mstr_standard tap *
  page47_i231
#ISCELL
  mstr_standard tap *
  page47_i232
#ISCELL
  mstr_standard offpage *
  page47_i233
#ISCELL
  mstr_standard tap *
  page47_i234
#ISCELL
  mstr_standard tap *
  page47_i235
#ISCELL
  mstr_standard tap *
  page47_i236
#ISCELL
  mstr_standard tap *
  page47_i237
#ISCELL
  mstr_standard tap *
  page47_i238
#ISCELL
  mstr_standard tap *
  page47_i239
#ISCELL
  mstr_standard tap *
  page47_i240
#ISCELL
  mstr_standard tap *
  page47_i241
#ISCELL
  mstr_standard tap *
  page47_i242
#ISCELL
  mstr_standard tap *
  page47_i243
#ISCELL
  mstr_standard tap *
  page47_i244
#ISCELL
  mstr_standard tap *
  page47_i245
#ISCELL
  mstr_standard tap *
  page47_i246
#ISCELL
  mstr_standard tap *
  page47_i247
#ISCELL
  mstr_standard tap *
  page47_i248
#ISCELL
  mstr_standard tap *
  page47_i249
#ISCELL
  mstr_standard tap *
  page47_i250
#ISCELL
  mstr_standard tap *
  page47_i251
#ISCELL
  mstr_standard tap *
  page47_i252
#ISCELL
  mstr_standard tap *
  page47_i253
#ISCELL
  mstr_standard tap *
  page47_i254
#ISCELL
  mstr_standard tap *
  page47_i255
#ISCELL
  mstr_standard tap *
  page47_i256
#ISCELL
  mstr_standard tap *
  page47_i257
#ISCELL
  mstr_standard tap *
  page47_i258
#ISCELL
  mstr_standard tap *
  page47_i259
#ISCELL
  mstr_standard tap *
  page47_i260
#ISCELL
  mstr_standard tap *
  page47_i261
#ISCELL
  mstr_standard tap *
  page47_i262
#ISCELL
  mstr_standard tap *
  page47_i263
#ISCELL
  mstr_standard tap *
  page47_i264
#ISCELL
  mstr_standard tap *
  page47_i265
#ISCELL
  mstr_standard tap *
  page47_i266
#ISCELL
  mstr_standard tap *
  page47_i267
#ISCELL
  mstr_standard tap *
  page47_i268
#ISCELL
  mstr_standard tap *
  page47_i269
#ISCELL
  mstr_standard tap *
  page47_i270
#ISCELL
  mstr_standard tap *
  page47_i271
#ISCELL
  mstr_standard tap *
  page47_i272
#ISCELL
  mstr_standard tap *
  page47_i273
#ISCELL
  mstr_standard tap *
  page47_i274
#ISCELL
  mstr_standard tap *
  page47_i275
#ISCELL
  mstr_standard tap *
  page47_i276
#ISCELL
  mstr_standard tap *
  page47_i277
#ISCELL
  mstr_standard tap *
  page47_i278
#ISCELL
  mstr_standard tap *
  page47_i279
#ISCELL
  standard offpage *
  page47_i280
#ISCELL
  standard offpage *
  page47_i281
#ISCELL
  standard offpage *
  page47_i282
#ISCELL
  standard offpage *
  page47_i283
#ISCELL
  mstr_standard tap *
  page47_i284
#ISCELL
  mstr_standard tap *
  page47_i285
#ISCELL
  mstr_standard tap *
  page47_i286
#ISCELL
  mstr_standard tap *
  page47_i287
#ISCELL
  mstr_standard tap *
  page47_i288
#ISCELL
  mstr_standard tap *
  page47_i289
#ISCELL
  mstr_standard tap *
  page47_i290
#ISCELL
  mstr_standard tap *
  page47_i291
#ISCELL
  mstr_standard tap *
  page47_i292
#ISCELL
  mstr_standard tap *
  page47_i293
#ISCELL
  mstr_standard tap *
  page47_i294
#ISCELL
  mstr_standard tap *
  page47_i295
#ISCELL
  mstr_standard tap *
  page47_i296
#ISCELL
  mstr_standard tap *
  page47_i297
#ISCELL
  mstr_standard tap *
  page47_i298
#ISCELL
  mstr_standard tap *
  page47_i299
#ISCELL
  mstr_standard tap *
  page47_i300
#ISCELL
  mstr_standard tap *
  page47_i301
#ISCELL
  standard offpage *
  page47_i302
#ISCELL
  standard offpage *
  page47_i303
#ISCELL
  standard offpage *
  page47_i304
#ISCELL
  standard offpage *
  page47_i305
#ISCELL
  standard offpage *
  page47_i306
#ISCELL
  standard offpage *
  page47_i307
#ISCELL
  standard offpage *
  page47_i308
#ISCELL
  mstr_standard offpage *
  page47_i309
#ISCELL
  standard offpage *
  page47_i310
#ISCELL
  standard offpage *
  page47_i311
#ISCELL
  standard offpage *
  page47_i312
#ISCELL
  standard offpage *
  page47_i313
#CELL
  pure_quanta q_res *
  page47_i314
#ISCELL
  standard offpage *
  page47_i315
#ISCELL
  mstr_standard offpage *
  page47_i316
#ISCELL
  pure_quanta quanta_title_block_c *
  *
#ISCELL
  pure_quanta_power cad_note *
  *
#CELL
  pure_quanta genoa_sp5 *
  page48_i159
#ISCELL
  mstr_standard offpage *
  page48_i160
#ISCELL
  mstr_standard offpage *
  page48_i161
#ISCELL
  mstr_standard tap *
  page48_i162
#ISCELL
  mstr_standard tap *
  page48_i163
#ISCELL
  mstr_standard tap *
  page48_i164
#ISCELL
  mstr_standard tap *
  page48_i165
#ISCELL
  mstr_standard tap *
  page48_i166
#ISCELL
  mstr_standard tap *
  page48_i167
#ISCELL
  mstr_standard tap *
  page48_i168
#ISCELL
  mstr_standard tap *
  page48_i169
#ISCELL
  mstr_standard tap *
  page48_i170
#ISCELL
  mstr_standard tap *
  page48_i171
#ISCELL
  mstr_standard tap *
  page48_i172
#ISCELL
  mstr_standard tap *
  page48_i173
#ISCELL
  mstr_standard tap *
  page48_i174
#ISCELL
  mstr_standard tap *
  page48_i175
#ISCELL
  mstr_standard tap *
  page48_i176
#ISCELL
  mstr_standard tap *
  page48_i177
#ISCELL
  mstr_standard tap *
  page48_i178
#ISCELL
  mstr_standard tap *
  page48_i179
#ISCELL
  mstr_standard tap *
  page48_i180
#ISCELL
  mstr_standard tap *
  page48_i181
#ISCELL
  mstr_standard tap *
  page48_i182
#ISCELL
  mstr_standard tap *
  page48_i183
#ISCELL
  mstr_standard tap *
  page48_i184
#ISCELL
  mstr_standard tap *
  page48_i185
#ISCELL
  mstr_standard tap *
  page48_i186
#ISCELL
  mstr_standard tap *
  page48_i187
#ISCELL
  mstr_standard tap *
  page48_i188
#ISCELL
  mstr_standard tap *
  page48_i189
#ISCELL
  mstr_standard tap *
  page48_i190
#ISCELL
  mstr_standard tap *
  page48_i191
#ISCELL
  mstr_standard tap *
  page48_i192
#ISCELL
  mstr_standard tap *
  page48_i193
#ISCELL
  mstr_standard tap *
  page48_i194
#ISCELL
  mstr_standard offpage *
  page48_i195
#ISCELL
  mstr_standard tap *
  page48_i196
#ISCELL
  mstr_standard tap *
  page48_i197
#ISCELL
  mstr_standard tap *
  page48_i198
#ISCELL
  mstr_standard tap *
  page48_i199
#ISCELL
  mstr_standard tap *
  page48_i200
#ISCELL
  mstr_standard tap *
  page48_i201
#ISCELL
  mstr_standard tap *
  page48_i202
#ISCELL
  mstr_standard tap *
  page48_i203
#ISCELL
  mstr_standard tap *
  page48_i204
#ISCELL
  mstr_standard tap *
  page48_i205
#ISCELL
  mstr_standard tap *
  page48_i206
#ISCELL
  mstr_standard tap *
  page48_i207
#ISCELL
  mstr_standard tap *
  page48_i208
#ISCELL
  mstr_standard tap *
  page48_i209
#ISCELL
  mstr_standard tap *
  page48_i210
#ISCELL
  mstr_standard tap *
  page48_i211
#ISCELL
  mstr_standard tap *
  page48_i212
#ISCELL
  mstr_standard tap *
  page48_i213
#ISCELL
  mstr_standard tap *
  page48_i214
#ISCELL
  mstr_standard tap *
  page48_i215
#ISCELL
  mstr_standard tap *
  page48_i216
#ISCELL
  mstr_standard tap *
  page48_i217
#ISCELL
  mstr_standard tap *
  page48_i218
#ISCELL
  mstr_standard tap *
  page48_i219
#ISCELL
  mstr_standard tap *
  page48_i220
#ISCELL
  mstr_standard tap *
  page48_i221
#ISCELL
  mstr_standard tap *
  page48_i222
#ISCELL
  mstr_standard tap *
  page48_i223
#ISCELL
  mstr_standard tap *
  page48_i224
#ISCELL
  mstr_standard tap *
  page48_i225
#ISCELL
  mstr_standard tap *
  page48_i226
#ISCELL
  mstr_standard tap *
  page48_i227
#ISCELL
  mstr_standard tap *
  page48_i228
#ISCELL
  mstr_standard tap *
  page48_i229
#ISCELL
  mstr_standard tap *
  page48_i230
#ISCELL
  mstr_standard tap *
  page48_i231
#ISCELL
  mstr_standard tap *
  page48_i232
#ISCELL
  mstr_standard offpage *
  page48_i233
#ISCELL
  mstr_standard tap *
  page48_i234
#ISCELL
  mstr_standard tap *
  page48_i235
#ISCELL
  mstr_standard tap *
  page48_i236
#ISCELL
  mstr_standard tap *
  page48_i237
#ISCELL
  mstr_standard tap *
  page48_i238
#ISCELL
  mstr_standard tap *
  page48_i239
#ISCELL
  mstr_standard tap *
  page48_i240
#ISCELL
  mstr_standard tap *
  page48_i241
#ISCELL
  mstr_standard tap *
  page48_i242
#ISCELL
  mstr_standard tap *
  page48_i243
#ISCELL
  mstr_standard tap *
  page48_i244
#ISCELL
  mstr_standard tap *
  page48_i245
#ISCELL
  mstr_standard tap *
  page48_i246
#ISCELL
  mstr_standard tap *
  page48_i247
#ISCELL
  mstr_standard tap *
  page48_i248
#ISCELL
  mstr_standard tap *
  page48_i249
#ISCELL
  mstr_standard tap *
  page48_i250
#ISCELL
  mstr_standard tap *
  page48_i251
#ISCELL
  mstr_standard tap *
  page48_i252
#ISCELL
  mstr_standard tap *
  page48_i253
#ISCELL
  mstr_standard tap *
  page48_i254
#ISCELL
  mstr_standard tap *
  page48_i255
#ISCELL
  mstr_standard tap *
  page48_i256
#ISCELL
  mstr_standard tap *
  page48_i257
#ISCELL
  mstr_standard tap *
  page48_i258
#ISCELL
  mstr_standard tap *
  page48_i259
#ISCELL
  mstr_standard tap *
  page48_i260
#ISCELL
  mstr_standard tap *
  page48_i261
#ISCELL
  mstr_standard tap *
  page48_i262
#ISCELL
  mstr_standard tap *
  page48_i263
#ISCELL
  mstr_standard tap *
  page48_i264
#ISCELL
  mstr_standard tap *
  page48_i265
#ISCELL
  mstr_standard tap *
  page48_i266
#ISCELL
  mstr_standard tap *
  page48_i267
#ISCELL
  mstr_standard tap *
  page48_i268
#ISCELL
  mstr_standard tap *
  page48_i269
#ISCELL
  mstr_standard tap *
  page48_i270
#ISCELL
  mstr_standard tap *
  page48_i271
#ISCELL
  mstr_standard tap *
  page48_i272
#ISCELL
  mstr_standard tap *
  page48_i273
#ISCELL
  mstr_standard tap *
  page48_i274
#ISCELL
  mstr_standard tap *
  page48_i275
#ISCELL
  mstr_standard tap *
  page48_i276
#ISCELL
  mstr_standard tap *
  page48_i277
#ISCELL
  mstr_standard tap *
  page48_i278
#ISCELL
  mstr_standard tap *
  page48_i279
#ISCELL
  standard offpage *
  page48_i280
#ISCELL
  standard offpage *
  page48_i281
#ISCELL
  standard offpage *
  page48_i282
#ISCELL
  standard offpage *
  page48_i283
#ISCELL
  mstr_standard tap *
  page48_i284
#ISCELL
  mstr_standard tap *
  page48_i285
#ISCELL
  mstr_standard tap *
  page48_i286
#ISCELL
  mstr_standard tap *
  page48_i287
#ISCELL
  mstr_standard tap *
  page48_i288
#ISCELL
  mstr_standard tap *
  page48_i289
#ISCELL
  mstr_standard tap *
  page48_i290
#ISCELL
  mstr_standard tap *
  page48_i291
#ISCELL
  mstr_standard tap *
  page48_i292
#ISCELL
  mstr_standard tap *
  page48_i293
#ISCELL
  mstr_standard tap *
  page48_i294
#ISCELL
  mstr_standard tap *
  page48_i295
#ISCELL
  mstr_standard tap *
  page48_i296
#ISCELL
  mstr_standard tap *
  page48_i297
#ISCELL
  mstr_standard tap *
  page48_i298
#ISCELL
  mstr_standard tap *
  page48_i299
#ISCELL
  mstr_standard tap *
  page48_i300
#ISCELL
  mstr_standard tap *
  page48_i301
#ISCELL
  standard offpage *
  page48_i302
#ISCELL
  standard offpage *
  page48_i303
#ISCELL
  standard offpage *
  page48_i304
#ISCELL
  standard offpage *
  page48_i305
#ISCELL
  standard offpage *
  page48_i306
#ISCELL
  standard offpage *
  page48_i307
#ISCELL
  standard offpage *
  page48_i308
#ISCELL
  mstr_standard offpage *
  page48_i309
#ISCELL
  standard offpage *
  page48_i310
#ISCELL
  standard offpage *
  page48_i311
#ISCELL
  standard offpage *
  page48_i312
#CELL
  pure_quanta q_res *
  page48_i313
#ISCELL
  standard offpage *
  page48_i314
#ISCELL
  standard offpage *
  page48_i315
#ISCELL
  mstr_standard offpage *
  page48_i316
#ISCELL
  pure_quanta quanta_title_block_c *
  *
#CELL
  pure_quanta genoa_sp5 *
  page49_i213
#CELL
  pure_quanta genoa_sp5 *
  page49_i214
#ISCELL
  standard offpage *
  page49_i232
#ISCELL
  mstr_standard tap *
  page49_i235
#ISCELL
  mstr_standard tap *
  page49_i236
#ISCELL
  standard tap *
  page49_i240
#ISCELL
  standard tap *
  page49_i241
#ISCELL
  standard tap *
  page49_i244
#ISCELL
  standard tap *
  page49_i245
#ISCELL
  standard tap *
  page49_i246
#ISCELL
  standard tap *
  page49_i250
#ISCELL
  standard tap *
  page49_i251
#ISCELL
  standard tap *
  page49_i254
#ISCELL
  standard tap *
  page49_i255
#ISCELL
  standard tap *
  page49_i256
#ISCELL
  standard tap *
  page49_i260
#ISCELL
  standard tap *
  page49_i261
#ISCELL
  standard tap *
  page49_i264
#ISCELL
  standard tap *
  page49_i265
#ISCELL
  standard offpage *
  page49_i267
#ISCELL
  mstr_standard tap *
  page49_i270
#ISCELL
  standard tap *
  page49_i271
#ISCELL
  mstr_standard tap *
  page49_i272
#ISCELL
  standard tap *
  page49_i276
#ISCELL
  standard tap *
  page49_i277
#ISCELL
  standard tap *
  page49_i280
#ISCELL
  standard tap *
  page49_i281
#ISCELL
  standard tap *
  page49_i282
#ISCELL
  standard tap *
  page49_i286
#ISCELL
  standard tap *
  page49_i287
#ISCELL
  standard tap *
  page49_i290
#ISCELL
  standard tap *
  page49_i291
#ISCELL
  standard tap *
  page49_i292
#ISCELL
  standard tap *
  page49_i296
#ISCELL
  standard tap *
  page49_i297
#ISCELL
  standard tap *
  page49_i298
#ISCELL
  mstr_standard tap *
  page49_i300
#ISCELL
  mstr_standard tap *
  page49_i301
#ISCELL
  mstr_standard tap *
  page49_i303
#ISCELL
  standard tap *
  page49_i304
#ISCELL
  standard tap *
  page49_i308
#ISCELL
  standard tap *
  page49_i309
#ISCELL
  standard tap *
  page49_i310
#ISCELL
  standard tap *
  page49_i313
#ISCELL
  standard tap *
  page49_i314
#ISCELL
  standard tap *
  page49_i318
#ISCELL
  standard tap *
  page49_i319
#ISCELL
  standard tap *
  page49_i320
#ISCELL
  standard tap *
  page49_i323
#ISCELL
  standard tap *
  page49_i324
#ISCELL
  standard tap *
  page49_i328
#ISCELL
  standard tap *
  page49_i329
#ISCELL
  standard offpage *
  page49_i333
#ISCELL
  mstr_standard tap *
  page49_i334
#ISCELL
  mstr_standard tap *
  page49_i335
#ISCELL
  mstr_standard tap *
  page49_i336
#ISCELL
  standard tap *
  page49_i339
#ISCELL
  standard tap *
  page49_i340
#ISCELL
  standard tap *
  page49_i344
#ISCELL
  standard tap *
  page49_i345
#ISCELL
  standard tap *
  page49_i346
#ISCELL
  standard tap *
  page49_i349
#ISCELL
  standard tap *
  page49_i350
#ISCELL
  standard offpage *
  page49_i355
#ISCELL
  standard tap *
  page49_i356
#ISCELL
  standard tap *
  page49_i357
#ISCELL
  standard tap *
  page49_i358
#ISCELL
  standard tap *
  page49_i361
#ISCELL
  standard tap *
  page49_i362
#ISCELL
  standard tap *
  page49_i366
#ISCELL
  standard offpage *
  page49_i436
#ISCELL
  mstr_standard tap *
  page49_i437
#ISCELL
  mstr_standard tap *
  page49_i438
#ISCELL
  standard tap *
  page49_i439
#ISCELL
  standard tap *
  page49_i440
#ISCELL
  standard tap *
  page49_i441
#ISCELL
  standard tap *
  page49_i442
#ISCELL
  standard tap *
  page49_i443
#ISCELL
  standard tap *
  page49_i444
#ISCELL
  standard tap *
  page49_i445
#ISCELL
  standard tap *
  page49_i446
#ISCELL
  standard tap *
  page49_i447
#ISCELL
  standard tap *
  page49_i448
#ISCELL
  standard tap *
  page49_i449
#ISCELL
  standard tap *
  page49_i450
#ISCELL
  standard tap *
  page49_i451
#ISCELL
  standard tap *
  page49_i452
#ISCELL
  mstr_standard tap *
  page49_i453
#ISCELL
  mstr_standard tap *
  page49_i454
#ISCELL
  standard tap *
  page49_i455
#ISCELL
  standard tap *
  page49_i456
#ISCELL
  standard tap *
  page49_i457
#ISCELL
  standard tap *
  page49_i458
#ISCELL
  standard tap *
  page49_i459
#ISCELL
  standard tap *
  page49_i460
#ISCELL
  standard tap *
  page49_i461
#ISCELL
  standard tap *
  page49_i462
#ISCELL
  standard tap *
  page49_i463
#ISCELL
  standard tap *
  page49_i464
#ISCELL
  standard tap *
  page49_i465
#ISCELL
  standard tap *
  page49_i466
#ISCELL
  standard tap *
  page49_i467
#ISCELL
  standard tap *
  page49_i468
#ISCELL
  standard offpage *
  page49_i469
#ISCELL
  mstr_standard tap *
  page49_i470
#ISCELL
  mstr_standard tap *
  page49_i471
#ISCELL
  standard tap *
  page49_i472
#ISCELL
  standard tap *
  page49_i473
#ISCELL
  standard tap *
  page49_i474
#ISCELL
  standard tap *
  page49_i475
#ISCELL
  standard tap *
  page49_i476
#ISCELL
  standard tap *
  page49_i477
#ISCELL
  standard tap *
  page49_i478
#ISCELL
  standard tap *
  page49_i479
#ISCELL
  standard tap *
  page49_i480
#ISCELL
  standard tap *
  page49_i481
#ISCELL
  standard tap *
  page49_i482
#ISCELL
  standard tap *
  page49_i483
#ISCELL
  standard tap *
  page49_i484
#ISCELL
  standard tap *
  page49_i485
#ISCELL
  standard offpage *
  page49_i486
#ISCELL
  standard offpage *
  page49_i487
#ISCELL
  mstr_standard tap *
  page49_i488
#ISCELL
  mstr_standard tap *
  page49_i489
#ISCELL
  standard tap *
  page49_i490
#ISCELL
  standard tap *
  page49_i491
#ISCELL
  standard tap *
  page49_i492
#ISCELL
  standard tap *
  page49_i493
#ISCELL
  standard tap *
  page49_i494
#ISCELL
  standard tap *
  page49_i495
#ISCELL
  standard tap *
  page49_i496
#ISCELL
  standard tap *
  page49_i497
#ISCELL
  standard tap *
  page49_i498
#ISCELL
  standard tap *
  page49_i499
#ISCELL
  standard tap *
  page49_i500
#ISCELL
  standard tap *
  page49_i501
#ISCELL
  standard tap *
  page49_i502
#ISCELL
  standard tap *
  page49_i503
#ISCELL
  pure_quanta quanta_title_block_c *
  *
#CELL
  pure_quanta genoa_sp5 *
  page50_i143
#CELL
  pure_quanta genoa_sp5 *
  page50_i144
#ISCELL
  standard offpage *
  page50_i195
#ISCELL
  mstr_standard tap *
  page50_i198
#ISCELL
  mstr_standard tap *
  page50_i199
#ISCELL
  standard tap *
  page50_i202
#ISCELL
  standard tap *
  page50_i203
#ISCELL
  standard tap *
  page50_i204
#ISCELL
  standard tap *
  page50_i208
#ISCELL
  standard tap *
  page50_i209
#ISCELL
  standard tap *
  page50_i212
#ISCELL
  standard tap *
  page50_i213
#ISCELL
  standard tap *
  page50_i214
#ISCELL
  standard tap *
  page50_i218
#ISCELL
  standard tap *
  page50_i219
#ISCELL
  standard tap *
  page50_i222
#ISCELL
  standard tap *
  page50_i223
#ISCELL
  standard tap *
  page50_i224
#ISCELL
  standard tap *
  page50_i225
#ISCELL
  standard offpage *
  page50_i228
#ISCELL
  mstr_standard tap *
  page50_i241
#ISCELL
  standard tap *
  page50_i242
#ISCELL
  standard tap *
  page50_i243
#ISCELL
  mstr_standard tap *
  page50_i244
#ISCELL
  standard tap *
  page50_i245
#ISCELL
  standard tap *
  page50_i246
#ISCELL
  standard tap *
  page50_i247
#ISCELL
  standard tap *
  page50_i248
#ISCELL
  standard tap *
  page50_i249
#ISCELL
  standard tap *
  page50_i250
#ISCELL
  standard tap *
  page50_i251
#ISCELL
  standard tap *
  page50_i257
#ISCELL
  standard tap *
  page50_i258
#ISCELL
  standard tap *
  page50_i259
#ISCELL
  standard tap *
  page50_i260
#ISCELL
  standard tap *
  page50_i261
#ISCELL
  mstr_standard tap *
  page50_i262
#ISCELL
  mstr_standard tap *
  page50_i263
#ISCELL
  mstr_standard tap *
  page50_i266
#ISCELL
  standard tap *
  page50_i267
#ISCELL
  standard tap *
  page50_i268
#ISCELL
  standard tap *
  page50_i271
#ISCELL
  standard tap *
  page50_i272
#ISCELL
  standard tap *
  page50_i276
#ISCELL
  standard tap *
  page50_i277
#ISCELL
  standard tap *
  page50_i278
#ISCELL
  standard tap *
  page50_i281
#ISCELL
  standard tap *
  page50_i282
#ISCELL
  standard tap *
  page50_i286
#ISCELL
  standard tap *
  page50_i287
#ISCELL
  standard tap *
  page50_i288
#ISCELL
  standard tap *
  page50_i291
#ISCELL
  standard offpage *
  page50_i295
#ISCELL
  standard tap *
  page50_i296
#ISCELL
  standard tap *
  page50_i298
#ISCELL
  standard tap *
  page50_i299
#ISCELL
  standard tap *
  page50_i300
#ISCELL
  standard tap *
  page50_i303
#ISCELL
  standard tap *
  page50_i304
#ISCELL
  standard tap *
  page50_i308
#ISCELL
  standard tap *
  page50_i309
#ISCELL
  standard tap *
  page50_i310
#ISCELL
  standard tap *
  page50_i313
#ISCELL
  standard tap *
  page50_i314
#ISCELL
  standard offpage *
  page50_i318
#ISCELL
  standard tap *
  page50_i320
#ISCELL
  standard tap *
  page50_i321
#ISCELL
  standard tap *
  page50_i322
#ISCELL
  standard tap *
  page50_i325
#ISCELL
  standard tap *
  page50_i327
#ISCELL
  mstr_standard tap *
  page50_i398
#ISCELL
  mstr_standard tap *
  page50_i399
#ISCELL
  standard tap *
  page50_i400
#ISCELL
  standard tap *
  page50_i401
#ISCELL
  standard tap *
  page50_i402
#ISCELL
  standard tap *
  page50_i403
#ISCELL
  standard tap *
  page50_i404
#ISCELL
  standard tap *
  page50_i405
#ISCELL
  standard tap *
  page50_i406
#ISCELL
  standard tap *
  page50_i407
#ISCELL
  standard tap *
  page50_i408
#ISCELL
  standard tap *
  page50_i409
#ISCELL
  standard tap *
  page50_i410
#ISCELL
  standard tap *
  page50_i411
#ISCELL
  standard tap *
  page50_i412
#ISCELL
  standard tap *
  page50_i413
#ISCELL
  standard offpage *
  page50_i414
#ISCELL
  standard offpage *
  page50_i415
#ISCELL
  mstr_standard tap *
  page50_i416
#ISCELL
  mstr_standard tap *
  page50_i417
#ISCELL
  standard tap *
  page50_i418
#ISCELL
  standard tap *
  page50_i419
#ISCELL
  standard tap *
  page50_i420
#ISCELL
  standard tap *
  page50_i421
#ISCELL
  standard tap *
  page50_i422
#ISCELL
  standard tap *
  page50_i423
#ISCELL
  standard tap *
  page50_i424
#ISCELL
  standard tap *
  page50_i425
#ISCELL
  standard tap *
  page50_i426
#ISCELL
  standard tap *
  page50_i427
#ISCELL
  standard tap *
  page50_i428
#ISCELL
  standard tap *
  page50_i429
#ISCELL
  standard tap *
  page50_i430
#ISCELL
  standard tap *
  page50_i431
#ISCELL
  standard offpage *
  page50_i432
#ISCELL
  mstr_standard tap *
  page50_i433
#ISCELL
  mstr_standard tap *
  page50_i434
#ISCELL
  standard tap *
  page50_i435
#ISCELL
  standard tap *
  page50_i436
#ISCELL
  standard tap *
  page50_i437
#ISCELL
  standard tap *
  page50_i438
#ISCELL
  standard tap *
  page50_i439
#ISCELL
  standard tap *
  page50_i440
#ISCELL
  standard tap *
  page50_i441
#ISCELL
  standard tap *
  page50_i442
#ISCELL
  standard tap *
  page50_i443
#ISCELL
  standard tap *
  page50_i444
#ISCELL
  standard tap *
  page50_i445
#ISCELL
  standard tap *
  page50_i446
#ISCELL
  standard tap *
  page50_i447
#ISCELL
  standard tap *
  page50_i448
#ISCELL
  mstr_standard tap *
  page50_i449
#ISCELL
  mstr_standard tap *
  page50_i450
#ISCELL
  standard tap *
  page50_i451
#ISCELL
  standard tap *
  page50_i452
#ISCELL
  standard tap *
  page50_i453
#ISCELL
  standard tap *
  page50_i454
#ISCELL
  standard tap *
  page50_i455
#ISCELL
  standard tap *
  page50_i456
#ISCELL
  standard tap *
  page50_i457
#ISCELL
  standard tap *
  page50_i458
#ISCELL
  standard tap *
  page50_i459
#ISCELL
  standard tap *
  page50_i460
#ISCELL
  standard tap *
  page50_i461
#ISCELL
  standard tap *
  page50_i462
#ISCELL
  standard tap *
  page50_i463
#ISCELL
  standard tap *
  page50_i464
#ISCELL
  standard offpage *
  page50_i465
#ISCELL
  pure_quanta quanta_title_block_c *
  *
#CELL
  pure_quanta genoa_sp5 *
  page51_i147
#CELL
  pure_quanta genoa_sp5 *
  page51_i148
#ISCELL
  standard offpage *
  page51_i183
#ISCELL
  standard offpage *
  page51_i184
#ISCELL
  mstr_standard tap *
  page51_i186
#ISCELL
  mstr_standard tap *
  page51_i187
#ISCELL
  standard tap *
  page51_i188
#ISCELL
  standard tap *
  page51_i189
#ISCELL
  standard tap *
  page51_i190
#ISCELL
  standard tap *
  page51_i191
#ISCELL
  standard tap *
  page51_i192
#ISCELL
  standard tap *
  page51_i193
#ISCELL
  standard tap *
  page51_i194
#ISCELL
  mstr_standard tap *
  page51_i196
#ISCELL
  standard tap *
  page51_i197
#ISCELL
  mstr_standard tap *
  page51_i198
#ISCELL
  standard tap *
  page51_i199
#ISCELL
  standard tap *
  page51_i200
#ISCELL
  standard tap *
  page51_i201
#ISCELL
  standard tap *
  page51_i202
#ISCELL
  standard tap *
  page51_i203
#ISCELL
  standard tap *
  page51_i204
#ISCELL
  standard tap *
  page51_i205
#ISCELL
  standard tap *
  page51_i206
#ISCELL
  standard tap *
  page51_i207
#ISCELL
  standard tap *
  page51_i208
#ISCELL
  standard tap *
  page51_i209
#ISCELL
  standard tap *
  page51_i210
#ISCELL
  standard tap *
  page51_i211
#ISCELL
  standard tap *
  page51_i212
#ISCELL
  standard tap *
  page51_i213
#ISCELL
  standard tap *
  page51_i214
#ISCELL
  standard tap *
  page51_i215
#ISCELL
  standard tap *
  page51_i216
#ISCELL
  standard tap *
  page51_i217
#ISCELL
  standard tap *
  page51_i218
#ISCELL
  mstr_standard tap *
  page51_i219
#ISCELL
  mstr_standard tap *
  page51_i220
#ISCELL
  mstr_standard tap *
  page51_i221
#ISCELL
  standard tap *
  page51_i222
#ISCELL
  standard tap *
  page51_i223
#ISCELL
  standard tap *
  page51_i228
#ISCELL
  standard tap *
  page51_i229
#ISCELL
  standard tap *
  page51_i230
#ISCELL
  standard tap *
  page51_i231
#ISCELL
  standard tap *
  page51_i232
#ISCELL
  standard tap *
  page51_i238
#ISCELL
  standard tap *
  page51_i239
#ISCELL
  standard tap *
  page51_i240
#ISCELL
  standard tap *
  page51_i241
#ISCELL
  standard tap *
  page51_i242
#ISCELL
  standard offpage *
  page51_i249
#ISCELL
  standard tap *
  page51_i253
#ISCELL
  standard tap *
  page51_i255
#ISCELL
  mstr_standard tap *
  page51_i256
#ISCELL
  mstr_standard tap *
  page51_i257
#ISCELL
  mstr_standard tap *
  page51_i258
#ISCELL
  mstr_standard tap *
  page51_i259
#ISCELL
  mstr_standard tap *
  page51_i260
#ISCELL
  standard tap *
  page51_i261
#ISCELL
  standard tap *
  page51_i262
#ISCELL
  standard tap *
  page51_i263
#ISCELL
  standard tap *
  page51_i264
#ISCELL
  standard tap *
  page51_i265
#ISCELL
  standard tap *
  page51_i266
#ISCELL
  standard tap *
  page51_i267
#ISCELL
  standard tap *
  page51_i268
#ISCELL
  standard tap *
  page51_i269
#ISCELL
  standard tap *
  page51_i270
#ISCELL
  standard tap *
  page51_i271
#ISCELL
  standard tap *
  page51_i272
#ISCELL
  standard offpage *
  page51_i273
#ISCELL
  standard offpage *
  page51_i274
#ISCELL
  standard tap *
  page51_i275
#ISCELL
  standard tap *
  page51_i276
#ISCELL
  standard tap *
  page51_i277
#ISCELL
  standard tap *
  page51_i278
#ISCELL
  standard tap *
  page51_i279
#ISCELL
  standard tap *
  page51_i280
#ISCELL
  standard tap *
  page51_i281
#ISCELL
  standard tap *
  page51_i282
#ISCELL
  standard tap *
  page51_i283
#ISCELL
  standard tap *
  page51_i284
#ISCELL
  standard tap *
  page51_i285
#ISCELL
  standard tap *
  page51_i286
#ISCELL
  standard tap *
  page51_i287
#ISCELL
  standard tap *
  page51_i288
#ISCELL
  standard offpage *
  page51_i289
#ISCELL
  mstr_standard tap *
  page51_i291
#ISCELL
  standard tap *
  page51_i295
#ISCELL
  mstr_standard tap *
  page51_i296
#ISCELL
  standard tap *
  page51_i299
#ISCELL
  standard tap *
  page51_i300
#ISCELL
  standard tap *
  page51_i301
#ISCELL
  standard tap *
  page51_i305
#ISCELL
  standard tap *
  page51_i306
#ISCELL
  standard tap *
  page51_i307
#ISCELL
  standard tap *
  page51_i311
#ISCELL
  standard tap *
  page51_i312
#ISCELL
  standard tap *
  page51_i315
#ISCELL
  standard tap *
  page51_i316
#ISCELL
  standard tap *
  page51_i317
#ISCELL
  standard tap *
  page51_i321
#ISCELL
  standard tap *
  page51_i322
#ISCELL
  mstr_standard tap *
  page51_i323
#ISCELL
  mstr_standard tap *
  page51_i324
#ISCELL
  standard tap *
  page51_i325
#ISCELL
  standard tap *
  page51_i326
#ISCELL
  standard tap *
  page51_i327
#ISCELL
  standard tap *
  page51_i328
#ISCELL
  standard tap *
  page51_i329
#ISCELL
  standard tap *
  page51_i330
#ISCELL
  standard tap *
  page51_i331
#ISCELL
  standard tap *
  page51_i332
#ISCELL
  standard tap *
  page51_i333
#ISCELL
  standard tap *
  page51_i334
#ISCELL
  standard tap *
  page51_i335
#ISCELL
  standard tap *
  page51_i336
#ISCELL
  standard tap *
  page51_i337
#ISCELL
  standard tap *
  page51_i338
#ISCELL
  standard offpage *
  page51_i339
#ISCELL
  standard tap *
  page51_i340
#ISCELL
  standard offpage *
  page51_i341
#ISCELL
  mstr_standard tap *
  page51_i342
#ISCELL
  mstr_standard tap *
  page51_i343
#ISCELL
  standard tap *
  page51_i344
#ISCELL
  standard tap *
  page51_i345
#ISCELL
  standard tap *
  page51_i346
#ISCELL
  standard tap *
  page51_i347
#ISCELL
  standard tap *
  page51_i348
#ISCELL
  standard tap *
  page51_i349
#ISCELL
  standard tap *
  page51_i350
#ISCELL
  standard tap *
  page51_i351
#ISCELL
  standard tap *
  page51_i352
#ISCELL
  standard tap *
  page51_i353
#ISCELL
  standard tap *
  page51_i354
#ISCELL
  standard tap *
  page51_i355
#ISCELL
  standard tap *
  page51_i356
#ISCELL
  pure_quanta quanta_title_block_c *
  *
#CELL
  pure_quanta genoa_sp5 *
  page52_i147
#CELL
  pure_quanta genoa_sp5 *
  page52_i148
#ISCELL
  standard offpage *
  page52_i149
#ISCELL
  standard offpage *
  page52_i150
#ISCELL
  mstr_standard tap *
  page52_i151
#ISCELL
  mstr_standard tap *
  page52_i152
#ISCELL
  standard tap *
  page52_i153
#ISCELL
  mstr_standard tap *
  page52_i154
#ISCELL
  mstr_standard tap *
  page52_i155
#ISCELL
  standard tap *
  page52_i156
#ISCELL
  standard tap *
  page52_i157
#ISCELL
  standard tap *
  page52_i158
#ISCELL
  standard tap *
  page52_i159
#ISCELL
  standard tap *
  page52_i160
#ISCELL
  standard tap *
  page52_i161
#ISCELL
  standard tap *
  page52_i162
#ISCELL
  standard tap *
  page52_i163
#ISCELL
  standard tap *
  page52_i164
#ISCELL
  standard tap *
  page52_i165
#ISCELL
  standard tap *
  page52_i166
#ISCELL
  standard tap *
  page52_i167
#ISCELL
  standard tap *
  page52_i168
#ISCELL
  standard tap *
  page52_i169
#ISCELL
  standard tap *
  page52_i170
#ISCELL
  standard tap *
  page52_i171
#ISCELL
  standard tap *
  page52_i172
#ISCELL
  standard tap *
  page52_i173
#ISCELL
  standard tap *
  page52_i174
#ISCELL
  standard tap *
  page52_i175
#ISCELL
  standard tap *
  page52_i176
#ISCELL
  standard tap *
  page52_i177
#ISCELL
  standard tap *
  page52_i178
#ISCELL
  standard tap *
  page52_i179
#ISCELL
  standard tap *
  page52_i180
#ISCELL
  standard tap *
  page52_i181
#ISCELL
  standard tap *
  page52_i182
#ISCELL
  standard offpage *
  page52_i183
#ISCELL
  standard offpage *
  page52_i184
#ISCELL
  mstr_standard tap *
  page52_i185
#ISCELL
  mstr_standard tap *
  page52_i186
#ISCELL
  standard tap *
  page52_i187
#ISCELL
  mstr_standard tap *
  page52_i188
#ISCELL
  mstr_standard tap *
  page52_i189
#ISCELL
  standard tap *
  page52_i190
#ISCELL
  standard tap *
  page52_i191
#ISCELL
  standard tap *
  page52_i192
#ISCELL
  standard tap *
  page52_i193
#ISCELL
  standard tap *
  page52_i194
#ISCELL
  standard tap *
  page52_i195
#ISCELL
  standard tap *
  page52_i196
#ISCELL
  standard tap *
  page52_i197
#ISCELL
  standard tap *
  page52_i198
#ISCELL
  standard tap *
  page52_i199
#ISCELL
  standard tap *
  page52_i200
#ISCELL
  standard tap *
  page52_i201
#ISCELL
  standard tap *
  page52_i202
#ISCELL
  standard tap *
  page52_i203
#ISCELL
  standard tap *
  page52_i204
#ISCELL
  standard tap *
  page52_i205
#ISCELL
  standard tap *
  page52_i206
#ISCELL
  standard tap *
  page52_i207
#ISCELL
  standard tap *
  page52_i208
#ISCELL
  standard tap *
  page52_i209
#ISCELL
  standard tap *
  page52_i210
#ISCELL
  standard tap *
  page52_i211
#ISCELL
  standard tap *
  page52_i212
#ISCELL
  standard tap *
  page52_i213
#ISCELL
  standard tap *
  page52_i214
#ISCELL
  standard tap *
  page52_i215
#ISCELL
  standard tap *
  page52_i216
#ISCELL
  mstr_standard tap *
  page52_i251
#ISCELL
  mstr_standard tap *
  page52_i253
#ISCELL
  mstr_standard tap *
  page52_i254
#ISCELL
  standard tap *
  page52_i255
#ISCELL
  standard tap *
  page52_i256
#ISCELL
  standard tap *
  page52_i257
#ISCELL
  standard tap *
  page52_i263
#ISCELL
  mstr_standard tap *
  page52_i285
#ISCELL
  standard tap *
  page52_i286
#ISCELL
  standard tap *
  page52_i287
#ISCELL
  standard tap *
  page52_i288
#ISCELL
  mstr_standard tap *
  page52_i292
#ISCELL
  mstr_standard tap *
  page52_i293
#ISCELL
  standard tap *
  page52_i294
#ISCELL
  standard tap *
  page52_i299
#ISCELL
  standard tap *
  page52_i302
#ISCELL
  mstr_standard tap *
  page52_i303
#ISCELL
  mstr_standard tap *
  page52_i304
#ISCELL
  standard tap *
  page52_i305
#ISCELL
  standard tap *
  page52_i306
#ISCELL
  standard tap *
  page52_i307
#ISCELL
  standard tap *
  page52_i308
#ISCELL
  standard tap *
  page52_i309
#ISCELL
  mstr_standard tap *
  page52_i310
#ISCELL
  standard tap *
  page52_i311
#ISCELL
  mstr_standard tap *
  page52_i312
#ISCELL
  standard tap *
  page52_i313
#ISCELL
  standard tap *
  page52_i314
#ISCELL
  standard tap *
  page52_i315
#ISCELL
  standard tap *
  page52_i316
#ISCELL
  standard tap *
  page52_i317
#ISCELL
  standard tap *
  page52_i318
#ISCELL
  standard offpage *
  page52_i319
#ISCELL
  standard offpage *
  page52_i320
#ISCELL
  mstr_standard tap *
  page52_i321
#ISCELL
  mstr_standard tap *
  page52_i322
#ISCELL
  mstr_standard tap *
  page52_i323
#ISCELL
  mstr_standard tap *
  page52_i324
#ISCELL
  mstr_standard tap *
  page52_i325
#ISCELL
  standard tap *
  page52_i326
#ISCELL
  standard tap *
  page52_i327
#ISCELL
  standard tap *
  page52_i328
#ISCELL
  standard tap *
  page52_i329
#ISCELL
  standard tap *
  page52_i330
#ISCELL
  standard tap *
  page52_i331
#ISCELL
  standard tap *
  page52_i332
#ISCELL
  standard tap *
  page52_i333
#ISCELL
  standard tap *
  page52_i334
#ISCELL
  standard tap *
  page52_i335
#ISCELL
  standard tap *
  page52_i336
#ISCELL
  standard tap *
  page52_i337
#ISCELL
  standard tap *
  page52_i338
#ISCELL
  standard tap *
  page52_i339
#ISCELL
  standard tap *
  page52_i340
#ISCELL
  standard tap *
  page52_i341
#ISCELL
  standard tap *
  page52_i342
#ISCELL
  standard tap *
  page52_i343
#ISCELL
  standard tap *
  page52_i344
#ISCELL
  standard tap *
  page52_i345
#ISCELL
  standard tap *
  page52_i346
#ISCELL
  standard tap *
  page52_i347
#ISCELL
  standard tap *
  page52_i348
#ISCELL
  standard tap *
  page52_i349
#ISCELL
  standard tap *
  page52_i350
#ISCELL
  standard tap *
  page52_i351
#ISCELL
  standard tap *
  page52_i352
#ISCELL
  standard offpage *
  page52_i353
#ISCELL
  standard offpage *
  page52_i354
#ISCELL
  pure_quanta quanta_title_block_c *
  *
#ISCELL
  standard offpage *
  page53_i109
#ISCELL
  standard offpage *
  page53_i110
#ISCELL
  standard offpage *
  page53_i111
#ISCELL
  standard offpage *
  page53_i112
#ISCELL
  standard offpage *
  page53_i113
#ISCELL
  standard offpage *
  page53_i114
#ISCELL
  standard offpage *
  page53_i115
#ISCELL
  standard offpage *
  page53_i116
#ISCELL
  standard tap *
  page53_i117
#ISCELL
  standard tap *
  page53_i118
#ISCELL
  standard tap *
  page53_i119
#ISCELL
  standard tap *
  page53_i120
#ISCELL
  standard tap *
  page53_i121
#ISCELL
  standard tap *
  page53_i122
#ISCELL
  standard tap *
  page53_i123
#ISCELL
  standard tap *
  page53_i124
#ISCELL
  standard tap *
  page53_i125
#ISCELL
  standard tap *
  page53_i126
#ISCELL
  standard tap *
  page53_i127
#ISCELL
  standard tap *
  page53_i128
#ISCELL
  standard tap *
  page53_i129
#ISCELL
  standard tap *
  page53_i130
#ISCELL
  standard tap *
  page53_i131
#CELL
  pure_quanta q_cap_diffbus *
  page53_i132
#CELL
  pure_quanta q_cap_diffbus *
  page53_i133
#CELL
  pure_quanta q_cap_diffbus *
  page53_i134
#CELL
  pure_quanta q_cap_diffbus *
  page53_i135
#ISCELL
  standard offpage *
  page53_i136
#ISCELL
  standard offpage *
  page53_i137
#ISCELL
  standard tap *
  page53_i138
#ISCELL
  standard offpage *
  page53_i139
#ISCELL
  standard offpage *
  page53_i140
#ISCELL
  standard offpage *
  page53_i141
#ISCELL
  standard offpage *
  page53_i142
#ISCELL
  standard offpage *
  page53_i143
#ISCELL
  standard offpage *
  page53_i144
#CELL
  pure_quanta genoa_sp5 *
  page53_i145
#ISCELL
  mstr_misc dns *
  *
#ISCELL
  pure_quanta quanta_title_block_c *
  *
#ISCELL
  pure_quanta_power universal_power *
  page54_i156
#ISCELL
  standard offpage *
  page54_i162
#ISCELL
  standard offpage *
  page54_i163
#ISCELL
  standard offpage *
  page54_i164
#ISCELL
  standard offpage *
  page54_i165
#ISCELL
  standard offpage *
  page54_i166
#ISCELL
  standard offpage *
  page54_i168
#ISCELL
  standard offpage *
  page54_i176
#ISCELL
  standard offpage *
  page54_i177
#ISCELL
  standard offpage *
  page54_i178
#ISCELL
  standard offpage *
  page54_i179
#CELL
  pure_quanta genoa_sp5 *
  page54_i190
#ISCELL
  standard offpage *
  page54_i192
#ISCELL
  standard offpage *
  page54_i198
#ISCELL
  standard offpage *
  page54_i199
#ISCELL
  standard offpage *
  page54_i200
#ISCELL
  standard offpage *
  page54_i201
#CELL
  pure_quanta q_res *
  page54_i203
#ISCELL
  standard offpage *
  page54_i204
#ISCELL
  standard offpage *
  page54_i205
#ISCELL
  standard offpage *
  page54_i208
#ISCELL
  standard offpage *
  page54_i211
#ISCELL
  standard offpage *
  page54_i216
#ISCELL
  standard offpage *
  page54_i217
#ISCELL
  standard offpage *
  page54_i219
#ISCELL
  standard offpage *
  page54_i220
#ISCELL
  standard offpage *
  page54_i221
#ISCELL
  standard offpage *
  page54_i222
#ISCELL
  standard offpage *
  page54_i224
#ISCELL
  standard offpage *
  page54_i225
#ISCELL
  standard offpage *
  page54_i235
#ISCELL
  standard offpage *
  page54_i236
#CELL
  pure_quanta tp *
  page54_i237
#CELL
  pure_quanta tp *
  page54_i238
#ISCELL
  pure_quanta_power universal_gnd *
  page54_i239
#CELL
  pure_quanta tp *
  page54_i240
#CELL
  pure_quanta tp *
  page54_i241
#CELL
  pure_quanta tp *
  page54_i242
#CELL
  pure_quanta tp *
  page54_i243
#CELL
  pure_quanta tp *
  page54_i244
#CELL
  pure_quanta tp *
  page54_i245
#ISCELL
  standard offpage *
  page54_i246
#ISCELL
  standard offpage *
  page54_i247
#ISCELL
  standard offpage *
  page54_i248
#ISCELL
  standard offpage *
  page54_i249
#ISCELL
  standard offpage *
  page54_i250
#ISCELL
  standard offpage *
  page54_i251
#ISCELL
  standard offpage *
  page54_i252
#ISCELL
  standard offpage *
  page54_i253
#ISCELL
  standard offpage *
  page54_i254
#ISCELL
  standard offpage *
  page54_i255
#ISCELL
  standard offpage *
  page54_i256
#ISCELL
  standard offpage *
  page54_i257
#ISCELL
  standard offpage *
  page54_i258
#ISCELL
  standard offpage *
  page54_i259
#ISCELL
  standard offpage *
  page54_i260
#ISCELL
  standard offpage *
  page54_i261
#ISCELL
  standard offpage *
  page54_i262
#ISCELL
  standard offpage *
  page54_i263
#CELL
  pure_quanta tp *
  page54_i272
#CELL
  pure_quanta tp *
  page54_i273
#ISCELL
  standard offpage *
  page54_i274
#ISCELL
  standard offpage *
  page54_i275
#ISCELL
  pure_quanta_power universal_power *
  page54_i286
#ISCELL
  pure_quanta_power gnd *
  page54_i289
#ISCELL
  pure_quanta_power gnd *
  page54_i291
#CELL
  pure_quanta q_res *
  page54_i308
#CELL
  pure_quanta q_res *
  page54_i309
#CELL
  pure_quanta q_cap *
  page54_i310
#CELL
  pure_quanta q_cap *
  page54_i311
#ISCELL
  pure_quanta_power gnd *
  page54_i312
#ISCELL
  pure_quanta_power gnd *
  page54_i313
#CELL
  pure_quanta q_res *
  page54_i314
#CELL
  pure_quanta q_cap *
  page54_i315
#CELL
  pure_quanta q_res *
  page54_i316
#CELL
  pure_quanta q_res *
  page54_i317
#CELL
  pure_quanta q_cap *
  page54_i318
#CELL
  pure_quanta q_cap *
  page54_i319
#ISCELL
  pure_quanta_power gnd *
  page54_i320
#ISCELL
  pure_quanta_power gnd *
  page54_i321
#ISCELL
  pure_quanta_power gnd *
  page54_i322
#ISCELL
  pure_quanta_power universal_power *
  page54_i323
#CELL
  pure_quanta q_res *
  page54_i324
#CELL
  pure_quanta q_cap *
  page54_i325
#ISCELL
  standard offpage *
  page54_i326
#ISCELL
  standard offpage *
  page54_i327
#ISCELL
  standard offpage *
  page54_i328
#ISCELL
  standard offpage *
  page54_i329
#ISCELL
  standard offpage *
  page54_i330
#ISCELL
  standard offpage *
  page54_i331
#ISCELL
  pure_quanta_power gnd *
  page54_i332
#CELL
  pure_quanta q_res *
  page54_i333
#CELL
  pure_quanta q_res *
  page54_i334
#ISCELL
  standard offpage *
  page54_i335
#ISCELL
  standard offpage *
  page54_i336
#CELL
  pure_quanta q_res *
  page54_i337
#CELL
  pure_quanta q_res *
  page54_i338
#ISCELL
  standard offpage *
  page54_i339
#ISCELL
  standard offpage *
  page54_i340
#ISCELL
  standard offpage *
  page54_i357
#ISCELL
  standard offpage *
  page54_i358
#ISCELL
  standard offpage *
  page54_i359
#ISCELL
  standard offpage *
  page54_i360
#CELL
  pure_quanta q_res *
  page54_i361
#CELL
  pure_quanta q_res *
  page54_i362
#CELL
  pure_quanta q_res *
  page54_i363
#CELL
  pure_quanta q_res *
  page54_i364
#ISCELL
  pure_quanta_power universal_gnd *
  page54_i365
#ISCELL
  standard offpage *
  page54_i366
#ISCELL
  standard offpage *
  page54_i367
#ISCELL
  standard offpage *
  page54_i368
#ISCELL
  standard offpage *
  page54_i369
#ISCELL
  pure_quanta_power universal_gnd *
  page54_i370
#CELL
  pure_quanta q_res *
  page54_i371
#CELL
  pure_quanta q_res *
  page54_i372
#CELL
  pure_quanta q_res *
  page54_i373
#CELL
  pure_quanta q_res *
  page54_i374
#ISCELL
  standard offpage *
  page54_i375
#ISCELL
  standard offpage *
  page54_i376
#ISCELL
  standard offpage *
  page54_i377
#ISCELL
  standard offpage *
  page54_i378
#ISCELL
  standard offpage *
  page54_i379
#ISCELL
  standard offpage *
  page54_i380
#ISCELL
  standard offpage *
  page54_i381
#ISCELL
  standard offpage *
  page54_i382
#ISCELL
  standard offpage *
  page54_i384
#ISCELL
  standard offpage *
  page54_i385
#ISCELL
  standard offpage *
  page54_i386
#CELL
  pure_quanta q_res *
  page54_i387
#CELL
  pure_quanta q_res *
  page54_i388
#ISCELL
  pure_quanta_power universal_power *
  page54_i389
#CELL
  pure_quanta q_res *
  page54_i390
#CELL
  pure_quanta q_res *
  page54_i391
#CELL
  pure_quanta q_res *
  page54_i396
#ISCELL
  standard offpage *
  page54_i397
#CELL
  pure_quanta q_res *
  page54_i398
#CELL
  pure_quanta q_res *
  page54_i400
#CELL
  pure_quanta q_res *
  page54_i401
#CELL
  pure_quanta q_res *
  page54_i402
#CELL
  pure_quanta q_res *
  page54_i403
#CELL
  pure_quanta q_res *
  page54_i404
#CELL
  pure_quanta q_res *
  page54_i405
#CELL
  pure_quanta q_res *
  page54_i406
#CELL
  pure_quanta q_res *
  page54_i407
#CELL
  pure_quanta q_res *
  page54_i408
#CELL
  pure_quanta q_res *
  page54_i409
#CELL
  pure_quanta q_res *
  page54_i410
#CELL
  pure_quanta q_res *
  page54_i411
#CELL
  pure_quanta q_res *
  page54_i412
#CELL
  pure_quanta q_res *
  page54_i413
#ISCELL
  standard offpage *
  page54_i414
#CELL
  pure_quanta q_res *
  page54_i415
#ISCELL
  standard offpage *
  page54_i416
#CELL
  pure_quanta q_res *
  page54_i417
#CELL
  pure_quanta sconn8_g802m0083150rd3hr *
  page54_i418
#CELL
  pure_quanta sconn8_g802m0083150rd3hr *
  page54_i419
#CELL
  pure_quanta q_res *
  page54_i421
#ISCELL
  mstr_misc dns *
  *
#ISCELL
  pure_quanta quanta_title_block_c *
  *
#CELL
  pure_quanta q_res *
  page55_i10
#ISCELL
  pure_quanta_power universal_gnd *
  page55_i11
#CELL
  pure_quanta q_xtal_4p_13bi_24gnd *
  page55_i12
#ISCELL
  pure_quanta_power universal_gnd *
  page55_i13
#ISCELL
  pure_quanta_power universal_gnd *
  page55_i14
#CELL
  pure_quanta q_cap *
  page55_i15
#ISCELL
  standard offpage *
  page55_i16
#ISCELL
  standard offpage *
  page55_i17
#ISCELL
  standard offpage *
  page55_i18
#CELL
  pure_quanta genoa_sp5 *
  page55_i182
#ISCELL
  standard offpage *
  page55_i183
#ISCELL
  standard offpage *
  page55_i185
#ISCELL
  standard offpage *
  page55_i186
#ISCELL
  standard offpage *
  page55_i187
#ISCELL
  standard offpage *
  page55_i188
#ISCELL
  standard offpage *
  page55_i189
#ISCELL
  standard offpage *
  page55_i19
#ISCELL
  standard offpage *
  page55_i190
#ISCELL
  standard offpage *
  page55_i191
#ISCELL
  standard offpage *
  page55_i192
#ISCELL
  standard offpage *
  page55_i193
#ISCELL
  pure_quanta_power universal_gnd *
  page55_i2
#ISCELL
  standard offpage *
  page55_i212
#ISCELL
  standard offpage *
  page55_i215
#ISCELL
  standard offpage *
  page55_i216
#ISCELL
  standard offpage *
  page55_i217
#ISCELL
  standard offpage *
  page55_i218
#ISCELL
  standard offpage *
  page55_i219
#ISCELL
  standard offpage *
  page55_i220
#ISCELL
  standard offpage *
  page55_i221
#ISCELL
  standard offpage *
  page55_i230
#CELL
  pure_quanta q_res *
  page55_i236
#CELL
  pure_quanta q_res *
  page55_i24
#ISCELL
  standard offpage *
  page55_i241
#ISCELL
  standard offpage *
  page55_i251
#ISCELL
  standard offpage *
  page55_i252
#ISCELL
  standard offpage *
  page55_i253
#ISCELL
  standard offpage *
  page55_i254
#ISCELL
  standard offpage *
  page55_i255
#ISCELL
  standard offpage *
  page55_i256
#CELL
  pure_quanta q_res *
  page55_i26
#ISCELL
  standard offpage *
  page55_i27
#ISCELL
  standard offpage *
  page55_i277
#ISCELL
  standard offpage *
  page55_i278
#ISCELL
  pure_quanta_power universal_power *
  page55_i291
#CELL
  pure_quanta q_res *
  page55_i292
#CELL
  pure_quanta q_res *
  page55_i296
#CELL
  pure_quanta q_res *
  page55_i297
#CELL
  pure_quanta q_res *
  page55_i298
#ISCELL
  standard offpage *
  page55_i299
#CELL
  pure_quanta q_cap *
  page55_i3
#ISCELL
  standard offpage *
  page55_i300
#ISCELL
  standard offpage *
  page55_i301
#CELL
  pure_quanta q_res *
  page55_i302
#CELL
  pure_quanta q_res *
  page55_i303
#ISCELL
  standard offpage *
  page55_i304
#ISCELL
  standard offpage *
  page55_i305
#CELL
  pure_quanta q_res *
  page55_i306
#CELL
  pure_quanta q_res *
  page55_i307
#CELL
  pure_quanta q_res *
  page55_i308
#CELL
  pure_quanta q_res *
  page55_i309
#ISCELL
  standard offpage *
  page55_i310
#ISCELL
  standard offpage *
  page55_i311
#CELL
  pure_quanta q_res *
  page55_i312
#CELL
  pure_quanta q_res *
  page55_i313
#ISCELL
  standard offpage *
  page55_i314
#ISCELL
  standard offpage *
  page55_i315
#CELL
  pure_quanta q_res *
  page55_i316
#CELL
  pure_quanta q_res *
  page55_i317
#ISCELL
  standard offpage *
  page55_i318
#ISCELL
  standard offpage *
  page55_i319
#CELL
  pure_quanta q_res *
  page55_i320
#CELL
  pure_quanta q_res *
  page55_i321
#ISCELL
  standard offpage *
  page55_i322
#ISCELL
  standard offpage *
  page55_i323
#ISCELL
  standard offpage *
  page55_i324
#ISCELL
  standard offpage *
  page55_i325
#CELL
  pure_quanta q_res *
  page55_i326
#CELL
  pure_quanta q_res *
  page55_i327
#ISCELL
  pure_quanta_power universal_gnd *
  page55_i328
#ISCELL
  pure_quanta_power universal_gnd *
  page55_i329
#CELL
  pure_quanta q_res *
  page55_i330
#CELL
  pure_quanta q_res *
  page55_i331
#ISCELL
  pure_quanta_power universal_gnd *
  page55_i332
#ISCELL
  pure_quanta_power universal_gnd *
  page55_i333
#CELL
  pure_quanta q_res *
  page55_i334
#CELL
  pure_quanta q_res *
  page55_i335
#CELL
  pure_quanta q_res *
  page55_i336
#CELL
  pure_quanta q_res *
  page55_i337
#CELL
  pure_quanta q_res *
  page55_i338
#CELL
  pure_quanta q_res *
  page55_i339
#ISCELL
  pure_quanta_power universal_gnd *
  page55_i340
#CELL
  pure_quanta q_res *
  page55_i341
#CELL
  pure_quanta q_res *
  page55_i342
#ISCELL
  pure_quanta_power universal_power *
  page55_i343
#ISCELL
  standard offpage *
  page55_i344
#ISCELL
  standard offpage *
  page55_i345
#ISCELL
  standard offpage *
  page55_i346
#ISCELL
  standard offpage *
  page55_i347
#ISCELL
  standard offpage *
  page55_i348
#ISCELL
  standard offpage *
  page55_i349
#ISCELL
  standard offpage *
  page55_i350
#ISCELL
  standard offpage *
  page55_i351
#CELL
  pure_quanta q_res *
  page55_i352
#CELL
  pure_quanta q_res *
  page55_i353
#CELL
  pure_quanta q_res *
  page55_i355
#CELL
  pure_quanta q_res *
  page55_i356
#CELL
  pure_quanta q_res *
  page55_i357
#CELL
  pure_quanta q_res *
  page55_i359
#CELL
  pure_quanta q_res *
  page55_i360
#ISCELL
  pure_quanta_power universal_power *
  page55_i361
#CELL
  pure_quanta q_res *
  page55_i362
#CELL
  pure_quanta q_res *
  page55_i363
#CELL
  pure_quanta q_res *
  page55_i364
#CELL
  pure_quanta q_res *
  page55_i365
#CELL
  pure_quanta q_res *
  page55_i366
#CELL
  pure_quanta q_res *
  page55_i367
#CELL
  pure_quanta q_res *
  page55_i368
#ISCELL
  pure_quanta_power vcc_core *
  page55_i369
#ISCELL
  standard offpage *
  page55_i370
#ISCELL
  standard offpage *
  page55_i371
#ISCELL
  standard offpage *
  page55_i373
#ISCELL
  standard offpage *
  page55_i374
#ISCELL
  standard offpage *
  page55_i375
#ISCELL
  standard offpage *
  page55_i376
#ISCELL
  standard offpage *
  page55_i377
#ISCELL
  standard offpage *
  page55_i378
#ISCELL
  standard offpage *
  page55_i379
#ISCELL
  standard offpage *
  page55_i380
#ISCELL
  standard offpage *
  page55_i381
#ISCELL
  standard offpage *
  page55_i382
#ISCELL
  standard offpage *
  page55_i383
#ISCELL
  standard offpage *
  page55_i384
#ISCELL
  standard offpage *
  page55_i385
#CELL
  pure_quanta q_res *
  page55_i386
#ISCELL
  pure_quanta_power universal_gnd *
  page55_i387
#CELL
  pure_quanta q_cap *
  page55_i388
#CELL
  pure_quanta q_res *
  page55_i389
#CELL
  pure_quanta q_res *
  page55_i390
#ISCELL
  standard offpage *
  page55_i391
#CELL
  pure_quanta q_res *
  page55_i392
#ISCELL
  pure_quanta_power universal_gnd *
  page55_i393
#CELL
  pure_quanta q_res *
  page55_i394
#ISCELL
  standard offpage *
  page55_i395
#ISCELL
  standard offpage *
  page55_i396
#CELL
  pure_quanta q_res *
  page55_i397
#ISCELL
  standard offpage *
  page55_i398
#ISCELL
  pure_quanta_power universal_gnd *
  page55_i4
#CELL
  pure_quanta q_cap *
  page55_i5
#CELL
  pure_quanta q_crystal *
  page55_i7
#ISCELL
  pure_quanta_power universal_gnd *
  page55_i8
#CELL
  pure_quanta q_cap *
  page55_i9
#ISCELL
  pure_quanta quanta_title_block_c *
  *
#ISCELL
  standard offpage *
  page56_i10
#CELL
  pure_quanta q_res *
  page56_i11
#ISCELL
  standard offpage *
  page56_i12
#CELL
  pure_quanta genoa_sp5 *
  page56_i8
#ISCELL
  mstr_misc dns *
  *
#ISCELL
  pure_quanta quanta_title_block_c *
  *
#ISCELL
  pure_quanta_power vcc_core *
  page57_i27
#ISCELL
  pure_quanta_power vcc_core *
  page57_i28
#CELL
  pure_quanta genoa_sp5 *
  page57_i29
#ISCELL
  pure_quanta_power vcc_core *
  page57_i30
#ISCELL
  pure_quanta_power vcc_core *
  page57_i31
#CELL
  pure_quanta genoa_sp5 *
  page57_i32
#ISCELL
  pure_quanta_power vcc_core *
  page57_i36
#ISCELL
  pure_quanta_power universal_power *
  page57_i37
#ISCELL
  pure_quanta_power universal_power *
  page57_i38
#ISCELL
  pure_quanta_power vcc_core *
  page57_i41
#ISCELL
  pure_quanta_power universal_power *
  page57_i42
#ISCELL
  pure_quanta_power universal_power *
  page57_i44
#CELL
  pure_quanta genoa_sp5 *
  page57_i45
#CELL
  pure_quanta genoa_sp5 *
  page57_i46
#ISCELL
  pure_quanta_power vcc_core *
  page57_i47
#ISCELL
  pure_quanta_power vcc_core *
  page57_i48
#CELL
  pure_quanta genoa_sp5 *
  page57_i49
#CELL
  pure_quanta q_res *
  page57_i51
#CELL
  pure_quanta q_res *
  page57_i52
#ISCELL
  pure_quanta quanta_title_block_c *
  *
#CELL
  pure_quanta genoa_sp5 *
  page58_i1
#CELL
  pure_quanta genoa_sp5 *
  page58_i12
#CELL
  pure_quanta genoa_sp5 *
  page58_i15
#ISCELL
  pure_quanta_power universal_gnd *
  page58_i18
#ISCELL
  pure_quanta_power universal_gnd *
  page58_i19
#ISCELL
  pure_quanta_power universal_gnd *
  page58_i20
#ISCELL
  pure_quanta_power universal_gnd *
  page58_i21
#ISCELL
  pure_quanta_power universal_gnd *
  page58_i22
#ISCELL
  pure_quanta_power universal_gnd *
  page58_i23
#ISCELL
  pure_quanta_power universal_gnd *
  page58_i24
#ISCELL
  pure_quanta_power universal_gnd *
  page58_i25
#ISCELL
  pure_quanta_power universal_gnd *
  page58_i26
#ISCELL
  pure_quanta_power universal_gnd *
  page58_i27
#ISCELL
  pure_quanta_power universal_gnd *
  page58_i28
#ISCELL
  pure_quanta_power universal_gnd *
  page58_i29
#CELL
  pure_quanta genoa_sp5 *
  page58_i3
#CELL
  pure_quanta genoa_sp5 *
  page58_i6
#CELL
  pure_quanta genoa_sp5 *
  page58_i9
#ISCELL
  pure_quanta quanta_title_block_c *
  *
#CELL
  pure_quanta genoa_sp5 *
  page59_i1
#ISCELL
  pure_quanta_power universal_gnd *
  page59_i10
#ISCELL
  pure_quanta_power universal_gnd *
  page59_i11
#ISCELL
  pure_quanta_power universal_gnd *
  page59_i12
#CELL
  pure_quanta genoa_sp5 *
  page59_i2
#CELL
  pure_quanta genoa_sp5 *
  page59_i3
#CELL
  pure_quanta genoa_sp5 *
  page59_i4
#ISCELL
  pure_quanta_power universal_gnd *
  page59_i5
#ISCELL
  pure_quanta_power universal_gnd *
  page59_i6
#ISCELL
  pure_quanta_power universal_gnd *
  page59_i7
#ISCELL
  pure_quanta_power universal_gnd *
  page59_i8
#ISCELL
  pure_quanta_power universal_gnd *
  page59_i9
#ISCELL
  pure_quanta quanta_title_block_c *
  *
#ISCELL
  pure_quanta_power universal_gnd *
  page60_i1
#ISCELL
  pure_quanta_power universal_gnd *
  page60_i2
#CELL
  pure_quanta genoa_sp5 *
  page60_i3
#ISCELL
  pure_quanta quanta_title_block_c *
  *
#ISCELL
  pure_quanta quanta_title_block_c *
  *
#ISCELL
  pure_quanta quanta_title_block_c *
  *
#ISCELL
  standard offpage *
  page351_i1
#ISCELL
  standard tap *
  page351_i10
#ISCELL
  standard tap *
  page351_i100
#ISCELL
  standard tap *
  page351_i101
#ISCELL
  standard tap *
  page351_i102
#ISCELL
  standard tap *
  page351_i103
#ISCELL
  standard tap *
  page351_i104
#ISCELL
  standard offpage *
  page351_i105
#ISCELL
  standard offpage *
  page351_i106
#ISCELL
  standard offpage *
  page351_i107
#ISCELL
  standard offpage *
  page351_i108
#ISCELL
  standard tap *
  page351_i109
#ISCELL
  standard tap *
  page351_i11
#ISCELL
  standard tap *
  page351_i110
#ISCELL
  standard tap *
  page351_i111
#ISCELL
  standard tap *
  page351_i112
#ISCELL
  standard tap *
  page351_i113
#ISCELL
  standard tap *
  page351_i114
#ISCELL
  standard tap *
  page351_i115
#ISCELL
  standard tap *
  page351_i116
#ISCELL
  standard tap *
  page351_i117
#ISCELL
  standard tap *
  page351_i118
#ISCELL
  standard tap *
  page351_i119
#ISCELL
  standard tap *
  page351_i12
#ISCELL
  standard tap *
  page351_i120
#CELL
  pure_quanta q_cap_diffbus *
  page351_i121
#CELL
  pure_quanta q_cap_diffbus *
  page351_i122
#CELL
  pure_quanta q_cap_diffbus *
  page351_i123
#CELL
  pure_quanta q_cap_diffbus *
  page351_i124
#CELL
  pure_quanta q_cap_diffbus *
  page351_i125
#CELL
  pure_quanta q_cap_diffbus *
  page351_i126
#CELL
  pure_quanta q_cap_diffbus *
  page351_i127
#CELL
  pure_quanta q_cap_diffbus *
  page351_i128
#ISCELL
  standard tap *
  page351_i129
#ISCELL
  standard tap *
  page351_i13
#ISCELL
  standard tap *
  page351_i130
#ISCELL
  standard tap *
  page351_i131
#ISCELL
  standard tap *
  page351_i132
#CELL
  pure_quanta q_cap_diffbus *
  page351_i133
#CELL
  pure_quanta q_cap_diffbus *
  page351_i134
#CELL
  pure_quanta q_cap_diffbus *
  page351_i135
#CELL
  pure_quanta q_cap_diffbus *
  page351_i136
#CELL
  pure_quanta q_cap_diffbus *
  page351_i137
#ISCELL
  standard tap *
  page351_i138
#ISCELL
  standard tap *
  page351_i139
#ISCELL
  standard tap *
  page351_i14
#ISCELL
  standard tap *
  page351_i140
#ISCELL
  standard tap *
  page351_i141
#ISCELL
  standard tap *
  page351_i142
#ISCELL
  standard tap *
  page351_i143
#ISCELL
  standard tap *
  page351_i144
#ISCELL
  standard tap *
  page351_i145
#ISCELL
  standard tap *
  page351_i146
#ISCELL
  standard tap *
  page351_i147
#ISCELL
  standard tap *
  page351_i148
#ISCELL
  standard tap *
  page351_i149
#ISCELL
  standard tap *
  page351_i15
#ISCELL
  standard tap *
  page351_i150
#CELL
  pure_quanta q_cap_diffbus *
  page351_i151
#CELL
  pure_quanta q_cap_diffbus *
  page351_i152
#CELL
  pure_quanta q_cap_diffbus *
  page351_i153
#CELL
  pure_quanta q_cap_diffbus *
  page351_i154
#CELL
  pure_quanta q_cap_diffbus *
  page351_i155
#CELL
  pure_quanta q_cap_diffbus *
  page351_i156
#CELL
  pure_quanta q_cap_diffbus *
  page351_i157
#CELL
  pure_quanta q_cap_diffbus *
  page351_i158
#CELL
  pure_quanta q_cap_diffbus *
  page351_i159
#ISCELL
  standard tap *
  page351_i16
#CELL
  pure_quanta q_cap_diffbus *
  page351_i160
#ISCELL
  standard tap *
  page351_i161
#ISCELL
  standard tap *
  page351_i162
#ISCELL
  standard tap *
  page351_i163
#CELL
  pure_quanta q_cap_diffbus *
  page351_i164
#CELL
  pure_quanta q_cap_diffbus *
  page351_i165
#CELL
  pure_quanta q_cap_diffbus *
  page351_i166
#CELL
  pure_quanta q_cap_diffbus *
  page351_i167
#CELL
  pure_quanta q_cap_diffbus *
  page351_i168
#CELL
  pure_quanta q_cap_diffbus *
  page351_i169
#ISCELL
  standard tap *
  page351_i17
#ISCELL
  standard tap *
  page351_i170
#ISCELL
  standard tap *
  page351_i171
#ISCELL
  standard tap *
  page351_i172
#ISCELL
  standard tap *
  page351_i173
#ISCELL
  standard tap *
  page351_i174
#ISCELL
  standard tap *
  page351_i175
#ISCELL
  standard tap *
  page351_i176
#ISCELL
  standard tap *
  page351_i177
#ISCELL
  standard tap *
  page351_i178
#ISCELL
  standard tap *
  page351_i179
#ISCELL
  standard tap *
  page351_i18
#ISCELL
  standard tap *
  page351_i180
#ISCELL
  standard tap *
  page351_i181
#ISCELL
  standard tap *
  page351_i182
#ISCELL
  standard tap *
  page351_i183
#ISCELL
  standard tap *
  page351_i184
#ISCELL
  standard offpage *
  page351_i185
#ISCELL
  standard offpage *
  page351_i186
#ISCELL
  standard tap *
  page351_i187
#ISCELL
  standard tap *
  page351_i188
#ISCELL
  standard tap *
  page351_i189
#ISCELL
  standard tap *
  page351_i19
#ISCELL
  standard tap *
  page351_i190
#ISCELL
  standard tap *
  page351_i191
#ISCELL
  standard tap *
  page351_i192
#ISCELL
  standard tap *
  page351_i193
#ISCELL
  standard tap *
  page351_i194
#ISCELL
  standard tap *
  page351_i195
#ISCELL
  standard tap *
  page351_i196
#ISCELL
  standard tap *
  page351_i197
#ISCELL
  standard tap *
  page351_i198
#ISCELL
  standard tap *
  page351_i199
#ISCELL
  standard offpage *
  page351_i2
#ISCELL
  standard tap *
  page351_i20
#ISCELL
  standard tap *
  page351_i200
#ISCELL
  standard tap *
  page351_i201
#ISCELL
  standard tap *
  page351_i202
#ISCELL
  standard offpage *
  page351_i203
#ISCELL
  standard offpage *
  page351_i204
#ISCELL
  standard tap *
  page351_i205
#CELL
  pure_quanta q_cap_diffbus *
  page351_i206
#CELL
  pure_quanta q_cap_diffbus *
  page351_i207
#CELL
  pure_quanta q_cap_diffbus *
  page351_i208
#CELL
  pure_quanta q_cap_diffbus *
  page351_i21
#CELL
  pure_quanta q_cap_diffbus *
  page351_i22
#CELL
  pure_quanta q_cap_diffbus *
  page351_i23
#CELL
  pure_quanta q_cap_diffbus *
  page351_i24
#CELL
  pure_quanta q_cap_diffbus *
  page351_i25
#CELL
  pure_quanta q_cap_diffbus *
  page351_i26
#CELL
  pure_quanta q_cap_diffbus *
  page351_i27
#CELL
  pure_quanta q_cap_diffbus *
  page351_i28
#CELL
  pure_quanta q_cap_diffbus *
  page351_i29
#ISCELL
  standard offpage *
  page351_i3
#CELL
  pure_quanta q_cap_diffbus *
  page351_i30
#CELL
  pure_quanta q_cap_diffbus *
  page351_i31
#CELL
  pure_quanta q_cap_diffbus *
  page351_i32
#CELL
  pure_quanta q_cap_diffbus *
  page351_i33
#CELL
  pure_quanta q_cap_diffbus *
  page351_i34
#CELL
  pure_quanta q_cap_diffbus *
  page351_i35
#CELL
  pure_quanta q_cap_diffbus *
  page351_i36
#ISCELL
  standard tap *
  page351_i37
#ISCELL
  standard tap *
  page351_i38
#ISCELL
  standard tap *
  page351_i39
#ISCELL
  standard offpage *
  page351_i4
#ISCELL
  standard tap *
  page351_i40
#ISCELL
  standard tap *
  page351_i41
#ISCELL
  standard tap *
  page351_i42
#ISCELL
  standard tap *
  page351_i43
#ISCELL
  standard tap *
  page351_i44
#ISCELL
  standard tap *
  page351_i45
#ISCELL
  standard tap *
  page351_i46
#ISCELL
  standard tap *
  page351_i47
#ISCELL
  standard tap *
  page351_i48
#ISCELL
  standard tap *
  page351_i49
#ISCELL
  standard tap *
  page351_i5
#ISCELL
  standard tap *
  page351_i50
#ISCELL
  standard tap *
  page351_i51
#ISCELL
  standard tap *
  page351_i52
#CELL
  pure_quanta q_cap_diffbus *
  page351_i53
#CELL
  pure_quanta q_cap_diffbus *
  page351_i54
#CELL
  pure_quanta q_cap_diffbus *
  page351_i55
#CELL
  pure_quanta q_cap_diffbus *
  page351_i56
#CELL
  pure_quanta q_cap_diffbus *
  page351_i57
#CELL
  pure_quanta q_cap_diffbus *
  page351_i58
#CELL
  pure_quanta q_cap_diffbus *
  page351_i59
#ISCELL
  standard tap *
  page351_i6
#CELL
  pure_quanta q_cap_diffbus *
  page351_i60
#CELL
  pure_quanta q_cap_diffbus *
  page351_i61
#CELL
  pure_quanta q_cap_diffbus *
  page351_i62
#CELL
  pure_quanta q_cap_diffbus *
  page351_i63
#CELL
  pure_quanta q_cap_diffbus *
  page351_i64
#CELL
  pure_quanta q_cap_diffbus *
  page351_i65
#CELL
  pure_quanta q_cap_diffbus *
  page351_i66
#CELL
  pure_quanta q_cap_diffbus *
  page351_i67
#CELL
  pure_quanta q_cap_diffbus *
  page351_i68
#ISCELL
  standard tap *
  page351_i69
#ISCELL
  standard tap *
  page351_i7
#ISCELL
  standard tap *
  page351_i70
#ISCELL
  standard tap *
  page351_i71
#ISCELL
  standard tap *
  page351_i72
#ISCELL
  standard tap *
  page351_i73
#ISCELL
  standard tap *
  page351_i74
#ISCELL
  standard tap *
  page351_i75
#ISCELL
  standard tap *
  page351_i76
#ISCELL
  standard tap *
  page351_i77
#ISCELL
  standard tap *
  page351_i78
#ISCELL
  standard tap *
  page351_i79
#ISCELL
  standard tap *
  page351_i8
#ISCELL
  standard tap *
  page351_i80
#ISCELL
  standard tap *
  page351_i81
#ISCELL
  standard tap *
  page351_i82
#ISCELL
  standard tap *
  page351_i83
#ISCELL
  standard tap *
  page351_i84
#ISCELL
  standard tap *
  page351_i85
#ISCELL
  standard tap *
  page351_i86
#ISCELL
  standard tap *
  page351_i87
#ISCELL
  standard tap *
  page351_i88
#ISCELL
  standard tap *
  page351_i89
#ISCELL
  standard tap *
  page351_i9
#ISCELL
  standard tap *
  page351_i90
#ISCELL
  standard tap *
  page351_i91
#ISCELL
  standard tap *
  page351_i92
#ISCELL
  standard offpage *
  page351_i93
#ISCELL
  standard offpage *
  page351_i94
#ISCELL
  standard offpage *
  page351_i95
#ISCELL
  standard offpage *
  page351_i96
#ISCELL
  standard tap *
  page351_i97
#ISCELL
  standard tap *
  page351_i98
#ISCELL
  standard tap *
  page351_i99
#ISCELL
  pure_quanta quanta_title_block_c *
  *
#ISCELL
  standard offpage *
  page352_i1
#ISCELL
  standard tap *
  page352_i10
#ISCELL
  standard tap *
  page352_i100
#ISCELL
  standard tap *
  page352_i101
#ISCELL
  standard tap *
  page352_i102
#ISCELL
  standard tap *
  page352_i103
#ISCELL
  standard tap *
  page352_i104
#ISCELL
  standard offpage *
  page352_i105
#ISCELL
  standard offpage *
  page352_i106
#ISCELL
  standard offpage *
  page352_i107
#ISCELL
  standard offpage *
  page352_i108
#ISCELL
  standard tap *
  page352_i109
#ISCELL
  standard tap *
  page352_i11
#ISCELL
  standard tap *
  page352_i110
#ISCELL
  standard tap *
  page352_i111
#ISCELL
  standard tap *
  page352_i112
#ISCELL
  standard tap *
  page352_i113
#ISCELL
  standard tap *
  page352_i114
#ISCELL
  standard tap *
  page352_i115
#ISCELL
  standard tap *
  page352_i116
#ISCELL
  standard tap *
  page352_i117
#ISCELL
  standard tap *
  page352_i118
#ISCELL
  standard tap *
  page352_i119
#ISCELL
  standard tap *
  page352_i12
#CELL
  pure_quanta q_cap_diffbus *
  page352_i120
#CELL
  pure_quanta q_cap_diffbus *
  page352_i121
#CELL
  pure_quanta q_cap_diffbus *
  page352_i122
#CELL
  pure_quanta q_cap_diffbus *
  page352_i123
#CELL
  pure_quanta q_cap_diffbus *
  page352_i124
#CELL
  pure_quanta q_cap_diffbus *
  page352_i125
#CELL
  pure_quanta q_cap_diffbus *
  page352_i126
#CELL
  pure_quanta q_cap_diffbus *
  page352_i127
#CELL
  pure_quanta q_cap_diffbus *
  page352_i128
#ISCELL
  standard tap *
  page352_i129
#ISCELL
  standard tap *
  page352_i13
#ISCELL
  standard tap *
  page352_i130
#ISCELL
  standard tap *
  page352_i131
#CELL
  pure_quanta q_cap_diffbus *
  page352_i132
#CELL
  pure_quanta q_cap_diffbus *
  page352_i133
#CELL
  pure_quanta q_cap_diffbus *
  page352_i134
#CELL
  pure_quanta q_cap_diffbus *
  page352_i135
#CELL
  pure_quanta q_cap_diffbus *
  page352_i136
#CELL
  pure_quanta q_cap_diffbus *
  page352_i137
#ISCELL
  standard tap *
  page352_i138
#ISCELL
  standard tap *
  page352_i139
#ISCELL
  standard tap *
  page352_i14
#ISCELL
  standard tap *
  page352_i140
#ISCELL
  standard tap *
  page352_i141
#ISCELL
  standard tap *
  page352_i142
#ISCELL
  standard tap *
  page352_i143
#ISCELL
  standard tap *
  page352_i144
#ISCELL
  standard tap *
  page352_i145
#ISCELL
  standard tap *
  page352_i146
#ISCELL
  standard tap *
  page352_i147
#ISCELL
  standard tap *
  page352_i148
#ISCELL
  standard tap *
  page352_i149
#ISCELL
  standard tap *
  page352_i15
#ISCELL
  standard tap *
  page352_i150
#CELL
  pure_quanta q_cap_diffbus *
  page352_i151
#CELL
  pure_quanta q_cap_diffbus *
  page352_i152
#CELL
  pure_quanta q_cap_diffbus *
  page352_i153
#CELL
  pure_quanta q_cap_diffbus *
  page352_i154
#CELL
  pure_quanta q_cap_diffbus *
  page352_i155
#CELL
  pure_quanta q_cap_diffbus *
  page352_i156
#CELL
  pure_quanta q_cap_diffbus *
  page352_i157
#CELL
  pure_quanta q_cap_diffbus *
  page352_i158
#CELL
  pure_quanta q_cap_diffbus *
  page352_i159
#ISCELL
  standard tap *
  page352_i16
#CELL
  pure_quanta q_cap_diffbus *
  page352_i160
#ISCELL
  standard tap *
  page352_i161
#ISCELL
  standard tap *
  page352_i162
#ISCELL
  standard tap *
  page352_i163
#CELL
  pure_quanta q_cap_diffbus *
  page352_i164
#CELL
  pure_quanta q_cap_diffbus *
  page352_i165
#CELL
  pure_quanta q_cap_diffbus *
  page352_i166
#CELL
  pure_quanta q_cap_diffbus *
  page352_i167
#CELL
  pure_quanta q_cap_diffbus *
  page352_i168
#CELL
  pure_quanta q_cap_diffbus *
  page352_i169
#ISCELL
  standard tap *
  page352_i17
#ISCELL
  standard tap *
  page352_i170
#ISCELL
  standard tap *
  page352_i171
#ISCELL
  standard tap *
  page352_i172
#ISCELL
  standard tap *
  page352_i173
#ISCELL
  standard tap *
  page352_i174
#ISCELL
  standard tap *
  page352_i175
#ISCELL
  standard tap *
  page352_i176
#ISCELL
  standard tap *
  page352_i177
#ISCELL
  standard tap *
  page352_i178
#ISCELL
  standard tap *
  page352_i179
#ISCELL
  standard tap *
  page352_i18
#ISCELL
  standard tap *
  page352_i180
#ISCELL
  standard tap *
  page352_i181
#ISCELL
  standard tap *
  page352_i182
#ISCELL
  standard tap *
  page352_i183
#ISCELL
  standard tap *
  page352_i184
#ISCELL
  standard tap *
  page352_i185
#ISCELL
  standard offpage *
  page352_i186
#ISCELL
  standard offpage *
  page352_i187
#ISCELL
  standard tap *
  page352_i188
#ISCELL
  standard tap *
  page352_i189
#ISCELL
  standard tap *
  page352_i19
#ISCELL
  standard tap *
  page352_i190
#ISCELL
  standard tap *
  page352_i191
#ISCELL
  standard tap *
  page352_i192
#ISCELL
  standard tap *
  page352_i193
#ISCELL
  standard tap *
  page352_i194
#ISCELL
  standard tap *
  page352_i195
#ISCELL
  standard tap *
  page352_i196
#ISCELL
  standard tap *
  page352_i197
#ISCELL
  standard tap *
  page352_i198
#ISCELL
  standard tap *
  page352_i199
#ISCELL
  standard offpage *
  page352_i2
#ISCELL
  standard tap *
  page352_i20
#ISCELL
  standard tap *
  page352_i200
#ISCELL
  standard tap *
  page352_i201
#ISCELL
  standard tap *
  page352_i202
#ISCELL
  standard tap *
  page352_i203
#ISCELL
  standard offpage *
  page352_i204
#ISCELL
  standard offpage *
  page352_i205
#CELL
  pure_quanta q_cap_diffbus *
  page352_i206
#ISCELL
  standard tap *
  page352_i207
#ISCELL
  standard tap *
  page352_i208
#CELL
  pure_quanta q_cap_diffbus *
  page352_i21
#CELL
  pure_quanta q_cap_diffbus *
  page352_i22
#CELL
  pure_quanta q_cap_diffbus *
  page352_i23
#CELL
  pure_quanta q_cap_diffbus *
  page352_i24
#CELL
  pure_quanta q_cap_diffbus *
  page352_i25
#CELL
  pure_quanta q_cap_diffbus *
  page352_i26
#CELL
  pure_quanta q_cap_diffbus *
  page352_i27
#CELL
  pure_quanta q_cap_diffbus *
  page352_i28
#CELL
  pure_quanta q_cap_diffbus *
  page352_i29
#ISCELL
  standard offpage *
  page352_i3
#CELL
  pure_quanta q_cap_diffbus *
  page352_i30
#ISCELL
  standard tap *
  page352_i31
#ISCELL
  standard tap *
  page352_i32
#ISCELL
  standard tap *
  page352_i33
#ISCELL
  standard tap *
  page352_i34
#ISCELL
  standard tap *
  page352_i35
#CELL
  pure_quanta q_cap_diffbus *
  page352_i36
#CELL
  pure_quanta q_cap_diffbus *
  page352_i37
#CELL
  pure_quanta q_cap_diffbus *
  page352_i38
#CELL
  pure_quanta q_cap_diffbus *
  page352_i39
#ISCELL
  standard offpage *
  page352_i4
#CELL
  pure_quanta q_cap_diffbus *
  page352_i40
#CELL
  pure_quanta q_cap_diffbus *
  page352_i41
#ISCELL
  standard tap *
  page352_i42
#ISCELL
  standard tap *
  page352_i43
#ISCELL
  standard tap *
  page352_i44
#ISCELL
  standard tap *
  page352_i45
#ISCELL
  standard tap *
  page352_i46
#ISCELL
  standard tap *
  page352_i47
#ISCELL
  standard tap *
  page352_i48
#ISCELL
  standard tap *
  page352_i49
#ISCELL
  standard tap *
  page352_i5
#ISCELL
  standard tap *
  page352_i50
#ISCELL
  standard tap *
  page352_i51
#ISCELL
  standard tap *
  page352_i52
#ISCELL
  standard tap *
  page352_i53
#ISCELL
  standard tap *
  page352_i54
#ISCELL
  standard tap *
  page352_i55
#ISCELL
  standard tap *
  page352_i56
#ISCELL
  standard tap *
  page352_i57
#ISCELL
  standard tap *
  page352_i58
#ISCELL
  standard tap *
  page352_i59
#ISCELL
  standard tap *
  page352_i6
#ISCELL
  standard tap *
  page352_i60
#CELL
  pure_quanta q_cap_diffbus *
  page352_i61
#CELL
  pure_quanta q_cap_diffbus *
  page352_i62
#CELL
  pure_quanta q_cap_diffbus *
  page352_i63
#CELL
  pure_quanta q_cap_diffbus *
  page352_i64
#CELL
  pure_quanta q_cap_diffbus *
  page352_i65
#CELL
  pure_quanta q_cap_diffbus *
  page352_i66
#CELL
  pure_quanta q_cap_diffbus *
  page352_i67
#CELL
  pure_quanta q_cap_diffbus *
  page352_i68
#CELL
  pure_quanta q_cap_diffbus *
  page352_i69
#ISCELL
  standard tap *
  page352_i7
#CELL
  pure_quanta q_cap_diffbus *
  page352_i70
#ISCELL
  standard tap *
  page352_i71
#ISCELL
  standard tap *
  page352_i72
#ISCELL
  standard tap *
  page352_i73
#ISCELL
  standard tap *
  page352_i74
#ISCELL
  standard tap *
  page352_i75
#CELL
  pure_quanta q_cap_diffbus *
  page352_i76
#CELL
  pure_quanta q_cap_diffbus *
  page352_i77
#CELL
  pure_quanta q_cap_diffbus *
  page352_i78
#CELL
  pure_quanta q_cap_diffbus *
  page352_i79
#ISCELL
  standard tap *
  page352_i8
#CELL
  pure_quanta q_cap_diffbus *
  page352_i80
#CELL
  pure_quanta q_cap_diffbus *
  page352_i81
#ISCELL
  standard tap *
  page352_i82
#ISCELL
  standard tap *
  page352_i83
#ISCELL
  standard tap *
  page352_i84
#ISCELL
  standard tap *
  page352_i85
#ISCELL
  standard tap *
  page352_i86
#ISCELL
  standard tap *
  page352_i87
#ISCELL
  standard tap *
  page352_i88
#ISCELL
  standard tap *
  page352_i89
#ISCELL
  standard tap *
  page352_i9
#ISCELL
  standard tap *
  page352_i90
#ISCELL
  standard tap *
  page352_i91
#ISCELL
  standard tap *
  page352_i92
#ISCELL
  standard offpage *
  page352_i93
#ISCELL
  standard offpage *
  page352_i94
#ISCELL
  standard offpage *
  page352_i95
#ISCELL
  standard offpage *
  page352_i96
#ISCELL
  standard tap *
  page352_i97
#ISCELL
  standard tap *
  page352_i98
#ISCELL
  standard tap *
  page352_i99
#ISCELL
  pure_quanta quanta_title_block_c *
  *
#ISCELL
  standard offpage *
  page353_i209
#ISCELL
  standard offpage *
  page353_i210
#ISCELL
  standard offpage *
  page353_i211
#ISCELL
  standard offpage *
  page353_i212
#ISCELL
  standard tap *
  page353_i213
#ISCELL
  standard tap *
  page353_i214
#ISCELL
  standard tap *
  page353_i215
#ISCELL
  standard tap *
  page353_i216
#ISCELL
  standard tap *
  page353_i217
#ISCELL
  standard tap *
  page353_i218
#ISCELL
  standard tap *
  page353_i219
#ISCELL
  standard tap *
  page353_i220
#ISCELL
  standard tap *
  page353_i221
#ISCELL
  standard tap *
  page353_i222
#ISCELL
  standard tap *
  page353_i223
#ISCELL
  standard tap *
  page353_i224
#ISCELL
  standard tap *
  page353_i225
#ISCELL
  standard tap *
  page353_i226
#ISCELL
  standard tap *
  page353_i227
#ISCELL
  standard tap *
  page353_i228
#CELL
  pure_quanta q_cap_diffbus *
  page353_i229
#CELL
  pure_quanta q_cap_diffbus *
  page353_i230
#CELL
  pure_quanta q_cap_diffbus *
  page353_i231
#CELL
  pure_quanta q_cap_diffbus *
  page353_i232
#CELL
  pure_quanta q_cap_diffbus *
  page353_i233
#CELL
  pure_quanta q_cap_diffbus *
  page353_i234
#CELL
  pure_quanta q_cap_diffbus *
  page353_i235
#CELL
  pure_quanta q_cap_diffbus *
  page353_i236
#CELL
  pure_quanta q_cap_diffbus *
  page353_i237
#CELL
  pure_quanta q_cap_diffbus *
  page353_i238
#CELL
  pure_quanta q_cap_diffbus *
  page353_i239
#CELL
  pure_quanta q_cap_diffbus *
  page353_i240
#CELL
  pure_quanta q_cap_diffbus *
  page353_i241
#CELL
  pure_quanta q_cap_diffbus *
  page353_i242
#ISCELL
  standard tap *
  page353_i243
#ISCELL
  standard tap *
  page353_i244
#ISCELL
  standard tap *
  page353_i245
#ISCELL
  standard tap *
  page353_i246
#ISCELL
  standard tap *
  page353_i247
#ISCELL
  standard tap *
  page353_i248
#ISCELL
  standard tap *
  page353_i249
#ISCELL
  standard tap *
  page353_i250
#ISCELL
  standard tap *
  page353_i251
#ISCELL
  standard tap *
  page353_i252
#ISCELL
  standard tap *
  page353_i253
#ISCELL
  standard tap *
  page353_i254
#ISCELL
  standard tap *
  page353_i255
#ISCELL
  standard tap *
  page353_i256
#ISCELL
  standard tap *
  page353_i257
#ISCELL
  standard tap *
  page353_i258
#CELL
  pure_quanta q_cap_diffbus *
  page353_i259
#CELL
  pure_quanta q_cap_diffbus *
  page353_i260
#CELL
  pure_quanta q_cap_diffbus *
  page353_i261
#CELL
  pure_quanta q_cap_diffbus *
  page353_i262
#CELL
  pure_quanta q_cap_diffbus *
  page353_i263
#CELL
  pure_quanta q_cap_diffbus *
  page353_i264
#CELL
  pure_quanta q_cap_diffbus *
  page353_i265
#CELL
  pure_quanta q_cap_diffbus *
  page353_i266
#CELL
  pure_quanta q_cap_diffbus *
  page353_i267
#CELL
  pure_quanta q_cap_diffbus *
  page353_i268
#CELL
  pure_quanta q_cap_diffbus *
  page353_i269
#CELL
  pure_quanta q_cap_diffbus *
  page353_i270
#CELL
  pure_quanta q_cap_diffbus *
  page353_i271
#CELL
  pure_quanta q_cap_diffbus *
  page353_i272
#CELL
  pure_quanta q_cap_diffbus *
  page353_i273
#CELL
  pure_quanta q_cap_diffbus *
  page353_i274
#ISCELL
  standard tap *
  page353_i275
#ISCELL
  standard tap *
  page353_i276
#ISCELL
  standard tap *
  page353_i277
#ISCELL
  standard tap *
  page353_i278
#ISCELL
  standard tap *
  page353_i279
#ISCELL
  standard tap *
  page353_i280
#ISCELL
  standard tap *
  page353_i281
#ISCELL
  standard tap *
  page353_i282
#ISCELL
  standard tap *
  page353_i283
#ISCELL
  standard tap *
  page353_i284
#ISCELL
  standard tap *
  page353_i285
#ISCELL
  standard tap *
  page353_i286
#ISCELL
  standard tap *
  page353_i287
#ISCELL
  standard tap *
  page353_i288
#ISCELL
  standard tap *
  page353_i289
#ISCELL
  standard tap *
  page353_i290
#ISCELL
  standard offpage *
  page353_i291
#ISCELL
  standard offpage *
  page353_i292
#ISCELL
  standard tap *
  page353_i293
#ISCELL
  standard tap *
  page353_i294
#ISCELL
  standard tap *
  page353_i295
#ISCELL
  standard tap *
  page353_i296
#ISCELL
  standard tap *
  page353_i297
#ISCELL
  standard tap *
  page353_i298
#ISCELL
  standard tap *
  page353_i299
#ISCELL
  standard tap *
  page353_i300
#ISCELL
  standard tap *
  page353_i301
#ISCELL
  standard tap *
  page353_i302
#ISCELL
  standard tap *
  page353_i303
#ISCELL
  standard tap *
  page353_i304
#ISCELL
  standard tap *
  page353_i305
#ISCELL
  standard tap *
  page353_i306
#ISCELL
  standard tap *
  page353_i307
#ISCELL
  standard tap *
  page353_i308
#ISCELL
  standard offpage *
  page353_i309
#ISCELL
  standard offpage *
  page353_i310
#CELL
  pure_quanta q_cap_diffbus *
  page353_i311
#CELL
  pure_quanta q_cap_diffbus *
  page353_i312
#ISCELL
  standard offpage *
  page353_i313
#ISCELL
  standard offpage *
  page353_i314
#ISCELL
  standard offpage *
  page353_i315
#ISCELL
  standard offpage *
  page353_i316
#ISCELL
  standard tap *
  page353_i317
#ISCELL
  standard tap *
  page353_i318
#ISCELL
  standard tap *
  page353_i319
#ISCELL
  standard tap *
  page353_i320
#ISCELL
  standard tap *
  page353_i321
#ISCELL
  standard tap *
  page353_i322
#ISCELL
  standard tap *
  page353_i323
#ISCELL
  standard tap *
  page353_i324
#ISCELL
  standard tap *
  page353_i325
#ISCELL
  standard tap *
  page353_i326
#ISCELL
  standard tap *
  page353_i327
#ISCELL
  standard tap *
  page353_i328
#ISCELL
  standard tap *
  page353_i329
#ISCELL
  standard tap *
  page353_i330
#ISCELL
  standard tap *
  page353_i331
#ISCELL
  standard tap *
  page353_i332
#CELL
  pure_quanta q_cap_diffbus *
  page353_i333
#CELL
  pure_quanta q_cap_diffbus *
  page353_i334
#CELL
  pure_quanta q_cap_diffbus *
  page353_i335
#CELL
  pure_quanta q_cap_diffbus *
  page353_i336
#CELL
  pure_quanta q_cap_diffbus *
  page353_i337
#CELL
  pure_quanta q_cap_diffbus *
  page353_i338
#CELL
  pure_quanta q_cap_diffbus *
  page353_i339
#CELL
  pure_quanta q_cap_diffbus *
  page353_i340
#CELL
  pure_quanta q_cap_diffbus *
  page353_i341
#CELL
  pure_quanta q_cap_diffbus *
  page353_i342
#CELL
  pure_quanta q_cap_diffbus *
  page353_i343
#CELL
  pure_quanta q_cap_diffbus *
  page353_i344
#CELL
  pure_quanta q_cap_diffbus *
  page353_i345
#CELL
  pure_quanta q_cap_diffbus *
  page353_i346
#ISCELL
  standard tap *
  page353_i347
#ISCELL
  standard tap *
  page353_i348
#ISCELL
  standard tap *
  page353_i349
#ISCELL
  standard tap *
  page353_i350
#ISCELL
  standard tap *
  page353_i351
#ISCELL
  standard tap *
  page353_i352
#ISCELL
  standard tap *
  page353_i353
#ISCELL
  standard tap *
  page353_i354
#ISCELL
  standard tap *
  page353_i355
#ISCELL
  standard tap *
  page353_i356
#ISCELL
  standard tap *
  page353_i357
#ISCELL
  standard tap *
  page353_i358
#ISCELL
  standard tap *
  page353_i359
#ISCELL
  standard tap *
  page353_i360
#ISCELL
  standard tap *
  page353_i361
#ISCELL
  standard tap *
  page353_i362
#CELL
  pure_quanta q_cap_diffbus *
  page353_i363
#CELL
  pure_quanta q_cap_diffbus *
  page353_i364
#CELL
  pure_quanta q_cap_diffbus *
  page353_i365
#CELL
  pure_quanta q_cap_diffbus *
  page353_i366
#CELL
  pure_quanta q_cap_diffbus *
  page353_i367
#CELL
  pure_quanta q_cap_diffbus *
  page353_i368
#CELL
  pure_quanta q_cap_diffbus *
  page353_i369
#CELL
  pure_quanta q_cap_diffbus *
  page353_i370
#CELL
  pure_quanta q_cap_diffbus *
  page353_i371
#CELL
  pure_quanta q_cap_diffbus *
  page353_i372
#CELL
  pure_quanta q_cap_diffbus *
  page353_i373
#CELL
  pure_quanta q_cap_diffbus *
  page353_i374
#CELL
  pure_quanta q_cap_diffbus *
  page353_i375
#CELL
  pure_quanta q_cap_diffbus *
  page353_i376
#CELL
  pure_quanta q_cap_diffbus *
  page353_i377
#CELL
  pure_quanta q_cap_diffbus *
  page353_i378
#ISCELL
  standard tap *
  page353_i379
#ISCELL
  standard tap *
  page353_i380
#ISCELL
  standard tap *
  page353_i381
#ISCELL
  standard tap *
  page353_i382
#ISCELL
  standard tap *
  page353_i383
#ISCELL
  standard tap *
  page353_i384
#ISCELL
  standard tap *
  page353_i385
#ISCELL
  standard tap *
  page353_i386
#ISCELL
  standard tap *
  page353_i387
#ISCELL
  standard tap *
  page353_i388
#ISCELL
  standard tap *
  page353_i389
#ISCELL
  standard tap *
  page353_i390
#ISCELL
  standard tap *
  page353_i391
#ISCELL
  standard tap *
  page353_i392
#ISCELL
  standard tap *
  page353_i393
#ISCELL
  standard offpage *
  page353_i394
#ISCELL
  standard offpage *
  page353_i395
#ISCELL
  standard tap *
  page353_i396
#ISCELL
  standard tap *
  page353_i397
#ISCELL
  standard tap *
  page353_i398
#ISCELL
  standard tap *
  page353_i399
#ISCELL
  standard tap *
  page353_i400
#ISCELL
  standard tap *
  page353_i401
#ISCELL
  standard tap *
  page353_i402
#ISCELL
  standard tap *
  page353_i403
#ISCELL
  standard tap *
  page353_i404
#ISCELL
  standard tap *
  page353_i405
#ISCELL
  standard tap *
  page353_i406
#ISCELL
  standard tap *
  page353_i407
#ISCELL
  standard tap *
  page353_i408
#ISCELL
  standard tap *
  page353_i409
#ISCELL
  standard tap *
  page353_i410
#ISCELL
  standard tap *
  page353_i411
#ISCELL
  standard offpage *
  page353_i412
#ISCELL
  standard offpage *
  page353_i413
#ISCELL
  standard tap *
  page353_i414
#CELL
  pure_quanta q_cap_diffbus *
  page353_i415
#CELL
  pure_quanta q_cap_diffbus *
  page353_i416
#ISCELL
  pure_quanta quanta_title_block_c *
  *
#ISCELL
  standard offpage *
  page354_i107
#ISCELL
  standard offpage *
  page354_i108
#ISCELL
  standard tap *
  page354_i109
#ISCELL
  standard tap *
  page354_i110
#ISCELL
  standard tap *
  page354_i111
#ISCELL
  standard tap *
  page354_i112
#ISCELL
  standard tap *
  page354_i113
#ISCELL
  standard tap *
  page354_i114
#ISCELL
  standard tap *
  page354_i115
#ISCELL
  standard tap *
  page354_i116
#ISCELL
  standard tap *
  page354_i117
#ISCELL
  standard tap *
  page354_i118
#ISCELL
  standard tap *
  page354_i119
#ISCELL
  standard tap *
  page354_i120
#ISCELL
  standard tap *
  page354_i121
#CELL
  pure_quanta q_cap_diffbus *
  page354_i122
#CELL
  pure_quanta q_cap_diffbus *
  page354_i123
#CELL
  pure_quanta q_cap_diffbus *
  page354_i124
#CELL
  pure_quanta q_cap_diffbus *
  page354_i125
#CELL
  pure_quanta q_cap_diffbus *
  page354_i126
#CELL
  pure_quanta q_cap_diffbus *
  page354_i127
#CELL
  pure_quanta q_cap_diffbus *
  page354_i128
#CELL
  pure_quanta q_cap_diffbus *
  page354_i129
#CELL
  pure_quanta q_cap_diffbus *
  page354_i130
#CELL
  pure_quanta q_cap_diffbus *
  page354_i131
#ISCELL
  standard tap *
  page354_i132
#ISCELL
  standard tap *
  page354_i133
#ISCELL
  standard tap *
  page354_i134
#CELL
  pure_quanta q_cap_diffbus *
  page354_i135
#CELL
  pure_quanta q_cap_diffbus *
  page354_i136
#CELL
  pure_quanta q_cap_diffbus *
  page354_i137
#CELL
  pure_quanta q_cap_diffbus *
  page354_i138
#CELL
  pure_quanta q_cap_diffbus *
  page354_i139
#CELL
  pure_quanta q_cap_diffbus *
  page354_i140
#ISCELL
  standard tap *
  page354_i141
#ISCELL
  standard tap *
  page354_i142
#ISCELL
  standard tap *
  page354_i143
#ISCELL
  standard tap *
  page354_i144
#ISCELL
  standard tap *
  page354_i145
#ISCELL
  standard tap *
  page354_i146
#ISCELL
  standard tap *
  page354_i147
#ISCELL
  standard tap *
  page354_i148
#ISCELL
  standard tap *
  page354_i149
#ISCELL
  standard tap *
  page354_i150
#ISCELL
  standard tap *
  page354_i151
#ISCELL
  standard tap *
  page354_i152
#ISCELL
  standard tap *
  page354_i153
#CELL
  pure_quanta q_cap_diffbus *
  page354_i154
#CELL
  pure_quanta q_cap_diffbus *
  page354_i155
#CELL
  pure_quanta q_cap_diffbus *
  page354_i156
#CELL
  pure_quanta q_cap_diffbus *
  page354_i157
#CELL
  pure_quanta q_cap_diffbus *
  page354_i158
#CELL
  pure_quanta q_cap_diffbus *
  page354_i159
#CELL
  pure_quanta q_cap_diffbus *
  page354_i160
#CELL
  pure_quanta q_cap_diffbus *
  page354_i161
#CELL
  pure_quanta q_cap_diffbus *
  page354_i162
#CELL
  pure_quanta q_cap_diffbus *
  page354_i163
#ISCELL
  standard tap *
  page354_i164
#ISCELL
  standard tap *
  page354_i165
#ISCELL
  standard tap *
  page354_i166
#CELL
  pure_quanta q_cap_diffbus *
  page354_i167
#CELL
  pure_quanta q_cap_diffbus *
  page354_i168
#CELL
  pure_quanta q_cap_diffbus *
  page354_i169
#CELL
  pure_quanta q_cap_diffbus *
  page354_i170
#CELL
  pure_quanta q_cap_diffbus *
  page354_i171
#CELL
  pure_quanta q_cap_diffbus *
  page354_i172
#ISCELL
  standard tap *
  page354_i173
#ISCELL
  standard tap *
  page354_i174
#ISCELL
  standard tap *
  page354_i175
#ISCELL
  standard tap *
  page354_i176
#ISCELL
  standard tap *
  page354_i177
#ISCELL
  standard tap *
  page354_i178
#ISCELL
  standard tap *
  page354_i179
#ISCELL
  standard tap *
  page354_i180
#ISCELL
  standard tap *
  page354_i181
#ISCELL
  standard tap *
  page354_i182
#ISCELL
  standard tap *
  page354_i183
#ISCELL
  standard tap *
  page354_i184
#ISCELL
  standard tap *
  page354_i185
#ISCELL
  standard tap *
  page354_i186
#ISCELL
  standard tap *
  page354_i187
#ISCELL
  standard tap *
  page354_i188
#ISCELL
  standard offpage *
  page354_i189
#ISCELL
  standard offpage *
  page354_i190
#ISCELL
  standard tap *
  page354_i191
#ISCELL
  standard tap *
  page354_i192
#ISCELL
  standard tap *
  page354_i193
#ISCELL
  standard tap *
  page354_i194
#ISCELL
  standard tap *
  page354_i195
#ISCELL
  standard tap *
  page354_i196
#ISCELL
  standard tap *
  page354_i197
#ISCELL
  standard tap *
  page354_i198
#ISCELL
  standard tap *
  page354_i199
#ISCELL
  standard tap *
  page354_i200
#ISCELL
  standard tap *
  page354_i201
#ISCELL
  standard tap *
  page354_i202
#ISCELL
  standard tap *
  page354_i203
#ISCELL
  standard tap *
  page354_i204
#ISCELL
  standard tap *
  page354_i205
#ISCELL
  standard tap *
  page354_i206
#ISCELL
  standard offpage *
  page354_i207
#ISCELL
  standard offpage *
  page354_i208
#ISCELL
  standard offpage *
  page354_i209
#ISCELL
  standard offpage *
  page354_i210
#ISCELL
  standard offpage *
  page354_i211
#ISCELL
  standard offpage *
  page354_i212
#ISCELL
  standard tap *
  page354_i213
#ISCELL
  standard tap *
  page354_i214
#ISCELL
  standard tap *
  page354_i215
#ISCELL
  standard tap *
  page354_i216
#ISCELL
  standard tap *
  page354_i217
#ISCELL
  standard tap *
  page354_i218
#ISCELL
  standard tap *
  page354_i219
#ISCELL
  standard tap *
  page354_i220
#ISCELL
  standard tap *
  page354_i221
#ISCELL
  standard tap *
  page354_i222
#ISCELL
  standard tap *
  page354_i223
#ISCELL
  standard tap *
  page354_i224
#ISCELL
  standard tap *
  page354_i225
#ISCELL
  standard tap *
  page354_i226
#ISCELL
  standard tap *
  page354_i227
#ISCELL
  standard tap *
  page354_i228
#CELL
  pure_quanta q_cap_diffbus *
  page354_i229
#CELL
  pure_quanta q_cap_diffbus *
  page354_i230
#CELL
  pure_quanta q_cap_diffbus *
  page354_i231
#CELL
  pure_quanta q_cap_diffbus *
  page354_i232
#CELL
  pure_quanta q_cap_diffbus *
  page354_i233
#CELL
  pure_quanta q_cap_diffbus *
  page354_i234
#CELL
  pure_quanta q_cap_diffbus *
  page354_i235
#CELL
  pure_quanta q_cap_diffbus *
  page354_i236
#CELL
  pure_quanta q_cap_diffbus *
  page354_i237
#ISCELL
  standard tap *
  page354_i238
#ISCELL
  standard tap *
  page354_i239
#ISCELL
  standard tap *
  page354_i240
#ISCELL
  standard tap *
  page354_i241
#ISCELL
  standard tap *
  page354_i242
#ISCELL
  standard tap *
  page354_i243
#ISCELL
  standard tap *
  page354_i244
#ISCELL
  standard tap *
  page354_i245
#CELL
  pure_quanta q_cap_diffbus *
  page354_i246
#CELL
  pure_quanta q_cap_diffbus *
  page354_i247
#CELL
  pure_quanta q_cap_diffbus *
  page354_i248
#CELL
  pure_quanta q_cap_diffbus *
  page354_i249
#CELL
  pure_quanta q_cap_diffbus *
  page354_i250
#CELL
  pure_quanta q_cap_diffbus *
  page354_i251
#ISCELL
  standard tap *
  page354_i252
#ISCELL
  standard tap *
  page354_i253
#ISCELL
  standard tap *
  page354_i254
#ISCELL
  standard tap *
  page354_i255
#ISCELL
  standard tap *
  page354_i256
#ISCELL
  standard tap *
  page354_i257
#ISCELL
  standard tap *
  page354_i258
#ISCELL
  standard tap *
  page354_i259
#ISCELL
  standard tap *
  page354_i260
#ISCELL
  standard tap *
  page354_i261
#ISCELL
  standard tap *
  page354_i262
#ISCELL
  standard tap *
  page354_i263
#ISCELL
  standard tap *
  page354_i264
#ISCELL
  standard tap *
  page354_i265
#ISCELL
  standard tap *
  page354_i266
#ISCELL
  standard tap *
  page354_i267
#ISCELL
  standard tap *
  page354_i268
#ISCELL
  standard tap *
  page354_i269
#ISCELL
  standard tap *
  page354_i270
#ISCELL
  standard tap *
  page354_i271
#ISCELL
  standard tap *
  page354_i272
#ISCELL
  standard tap *
  page354_i273
#CELL
  pure_quanta q_cap_diffbus *
  page354_i274
#CELL
  pure_quanta q_cap_diffbus *
  page354_i275
#CELL
  pure_quanta q_cap_diffbus *
  page354_i276
#CELL
  pure_quanta q_cap_diffbus *
  page354_i277
#CELL
  pure_quanta q_cap_diffbus *
  page354_i278
#CELL
  pure_quanta q_cap_diffbus *
  page354_i279
#CELL
  pure_quanta q_cap_diffbus *
  page354_i280
#CELL
  pure_quanta q_cap_diffbus *
  page354_i281
#CELL
  pure_quanta q_cap_diffbus *
  page354_i282
#CELL
  pure_quanta q_cap_diffbus *
  page354_i283
#ISCELL
  standard tap *
  page354_i284
#ISCELL
  standard tap *
  page354_i285
#ISCELL
  standard tap *
  page354_i286
#ISCELL
  standard tap *
  page354_i287
#ISCELL
  standard tap *
  page354_i288
#ISCELL
  standard tap *
  page354_i289
#ISCELL
  standard tap *
  page354_i290
#ISCELL
  standard tap *
  page354_i291
#ISCELL
  standard tap *
  page354_i292
#ISCELL
  standard tap *
  page354_i293
#CELL
  pure_quanta q_cap_diffbus *
  page354_i294
#CELL
  pure_quanta q_cap_diffbus *
  page354_i295
#CELL
  pure_quanta q_cap_diffbus *
  page354_i296
#CELL
  pure_quanta q_cap_diffbus *
  page354_i297
#CELL
  pure_quanta q_cap_diffbus *
  page354_i298
#CELL
  pure_quanta q_cap_diffbus *
  page354_i299
#ISCELL
  standard tap *
  page354_i300
#ISCELL
  standard tap *
  page354_i301
#ISCELL
  standard tap *
  page354_i302
#ISCELL
  standard tap *
  page354_i303
#ISCELL
  standard tap *
  page354_i304
#ISCELL
  standard tap *
  page354_i305
#ISCELL
  standard offpage *
  page354_i306
#ISCELL
  standard offpage *
  page354_i307
#ISCELL
  standard offpage *
  page354_i308
#ISCELL
  standard offpage *
  page354_i309
#ISCELL
  standard tap *
  page354_i310
#ISCELL
  standard tap *
  page354_i311
#CELL
  pure_quanta q_cap_diffbus *
  page354_i312
#ISCELL
  standard offpage *
  page354_i95
#ISCELL
  standard offpage *
  page354_i96
#ISCELL
  pure_quanta quanta_title_block_c *
  *
#ISCELL
  standard tap *
  page355_i1
#CELL
  pure_quanta q_cap_diffbus *
  page355_i10
#ISCELL
  standard tap *
  page355_i100
#ISCELL
  standard tap *
  page355_i101
#ISCELL
  standard tap *
  page355_i102
#ISCELL
  standard tap *
  page355_i103
#ISCELL
  standard tap *
  page355_i104
#ISCELL
  standard tap *
  page355_i105
#ISCELL
  standard tap *
  page355_i106
#CELL
  pure_quanta q_cap_diffbus *
  page355_i107
#ISCELL
  standard offpage *
  page355_i108
#ISCELL
  standard offpage *
  page355_i109
#CELL
  pure_quanta q_cap_diffbus *
  page355_i11
#ISCELL
  standard tap *
  page355_i110
#ISCELL
  standard tap *
  page355_i111
#ISCELL
  standard tap *
  page355_i112
#ISCELL
  standard tap *
  page355_i113
#ISCELL
  standard tap *
  page355_i114
#ISCELL
  standard tap *
  page355_i115
#CELL
  pure_quanta q_cap_diffbus *
  page355_i116
#CELL
  pure_quanta q_cap_diffbus *
  page355_i117
#CELL
  pure_quanta q_cap_diffbus *
  page355_i118
#CELL
  pure_quanta q_cap_diffbus *
  page355_i119
#CELL
  pure_quanta q_cap_diffbus *
  page355_i12
#CELL
  pure_quanta q_cap_diffbus *
  page355_i120
#ISCELL
  standard tap *
  page355_i121
#ISCELL
  standard tap *
  page355_i122
#ISCELL
  standard tap *
  page355_i123
#ISCELL
  standard tap *
  page355_i124
#ISCELL
  standard tap *
  page355_i125
#ISCELL
  standard tap *
  page355_i126
#ISCELL
  standard tap *
  page355_i127
#ISCELL
  standard tap *
  page355_i128
#ISCELL
  standard tap *
  page355_i129
#ISCELL
  standard tap *
  page355_i13
#ISCELL
  standard tap *
  page355_i130
#ISCELL
  standard tap *
  page355_i131
#ISCELL
  standard tap *
  page355_i132
#CELL
  pure_quanta q_cap_diffbus *
  page355_i133
#CELL
  pure_quanta q_cap_diffbus *
  page355_i134
#CELL
  pure_quanta q_cap_diffbus *
  page355_i135
#CELL
  pure_quanta q_cap_diffbus *
  page355_i136
#CELL
  pure_quanta q_cap_diffbus *
  page355_i137
#CELL
  pure_quanta q_cap_diffbus *
  page355_i138
#ISCELL
  standard tap *
  page355_i139
#ISCELL
  standard tap *
  page355_i14
#ISCELL
  standard tap *
  page355_i140
#ISCELL
  standard tap *
  page355_i141
#ISCELL
  standard tap *
  page355_i142
#ISCELL
  standard tap *
  page355_i143
#ISCELL
  standard tap *
  page355_i144
#ISCELL
  standard offpage *
  page355_i145
#ISCELL
  standard offpage *
  page355_i146
#ISCELL
  standard offpage *
  page355_i147
#ISCELL
  standard offpage *
  page355_i148
#ISCELL
  standard offpage *
  page355_i149
#ISCELL
  standard tap *
  page355_i15
#ISCELL
  standard offpage *
  page355_i150
#ISCELL
  standard offpage *
  page355_i151
#ISCELL
  standard offpage *
  page355_i152
#ISCELL
  standard tap *
  page355_i153
#ISCELL
  standard tap *
  page355_i154
#ISCELL
  standard tap *
  page355_i155
#ISCELL
  standard tap *
  page355_i156
#ISCELL
  standard tap *
  page355_i157
#ISCELL
  standard tap *
  page355_i158
#ISCELL
  standard tap *
  page355_i159
#ISCELL
  standard tap *
  page355_i16
#ISCELL
  standard tap *
  page355_i160
#CELL
  pure_quanta q_cap_diffbus *
  page355_i161
#CELL
  pure_quanta q_cap_diffbus *
  page355_i162
#ISCELL
  standard tap *
  page355_i163
#ISCELL
  standard tap *
  page355_i164
#CELL
  pure_quanta q_cap_diffbus *
  page355_i165
#CELL
  pure_quanta q_cap_diffbus *
  page355_i166
#CELL
  pure_quanta q_cap_diffbus *
  page355_i167
#CELL
  pure_quanta q_cap_diffbus *
  page355_i168
#CELL
  pure_quanta q_cap_diffbus *
  page355_i169
#ISCELL
  standard tap *
  page355_i17
#CELL
  pure_quanta q_cap_diffbus *
  page355_i170
#ISCELL
  standard tap *
  page355_i171
#ISCELL
  standard tap *
  page355_i172
#ISCELL
  standard tap *
  page355_i173
#ISCELL
  standard tap *
  page355_i174
#ISCELL
  standard tap *
  page355_i175
#ISCELL
  standard tap *
  page355_i176
#ISCELL
  standard tap *
  page355_i177
#ISCELL
  standard tap *
  page355_i178
#ISCELL
  standard tap *
  page355_i179
#ISCELL
  standard tap *
  page355_i18
#ISCELL
  standard tap *
  page355_i180
#ISCELL
  standard tap *
  page355_i181
#ISCELL
  standard tap *
  page355_i182
#ISCELL
  standard tap *
  page355_i183
#ISCELL
  standard tap *
  page355_i184
#ISCELL
  standard tap *
  page355_i185
#ISCELL
  standard tap *
  page355_i186
#ISCELL
  standard tap *
  page355_i187
#ISCELL
  standard tap *
  page355_i188
#ISCELL
  standard tap *
  page355_i189
#ISCELL
  standard offpage *
  page355_i19
#ISCELL
  standard tap *
  page355_i190
#ISCELL
  standard tap *
  page355_i191
#ISCELL
  standard tap *
  page355_i192
#ISCELL
  standard tap *
  page355_i193
#ISCELL
  standard tap *
  page355_i194
#ISCELL
  standard tap *
  page355_i195
#ISCELL
  standard tap *
  page355_i196
#CELL
  pure_quanta q_cap_diffbus *
  page355_i197
#CELL
  pure_quanta q_cap_diffbus *
  page355_i198
#CELL
  pure_quanta q_cap_diffbus *
  page355_i199
#ISCELL
  standard tap *
  page355_i2
#ISCELL
  standard offpage *
  page355_i20
#CELL
  pure_quanta q_cap_diffbus *
  page355_i200
#CELL
  pure_quanta q_cap_diffbus *
  page355_i201
#CELL
  pure_quanta q_cap_diffbus *
  page355_i202
#CELL
  pure_quanta q_cap_diffbus *
  page355_i203
#CELL
  pure_quanta q_cap_diffbus *
  page355_i204
#CELL
  pure_quanta q_cap_diffbus *
  page355_i205
#CELL
  pure_quanta q_cap_diffbus *
  page355_i206
#ISCELL
  standard tap *
  page355_i207
#ISCELL
  standard tap *
  page355_i208
#ISCELL
  standard tap *
  page355_i209
#ISCELL
  standard tap *
  page355_i21
#ISCELL
  standard tap *
  page355_i210
#ISCELL
  standard tap *
  page355_i211
#ISCELL
  standard tap *
  page355_i212
#ISCELL
  standard tap *
  page355_i213
#ISCELL
  standard tap *
  page355_i214
#ISCELL
  standard tap *
  page355_i215
#CELL
  pure_quanta q_cap_diffbus *
  page355_i216
#CELL
  pure_quanta q_cap_diffbus *
  page355_i217
#CELL
  pure_quanta q_cap_diffbus *
  page355_i218
#CELL
  pure_quanta q_cap_diffbus *
  page355_i219
#ISCELL
  standard tap *
  page355_i22
#CELL
  pure_quanta q_cap_diffbus *
  page355_i220
#CELL
  pure_quanta q_cap_diffbus *
  page355_i221
#CELL
  pure_quanta q_cap_diffbus *
  page355_i222
#CELL
  pure_quanta q_cap_diffbus *
  page355_i223
#CELL
  pure_quanta q_cap_diffbus *
  page355_i224
#CELL
  pure_quanta q_cap_diffbus *
  page355_i225
#ISCELL
  standard tap *
  page355_i226
#ISCELL
  standard tap *
  page355_i227
#ISCELL
  standard tap *
  page355_i228
#ISCELL
  standard tap *
  page355_i229
#ISCELL
  standard tap *
  page355_i23
#ISCELL
  standard tap *
  page355_i230
#ISCELL
  standard tap *
  page355_i231
#ISCELL
  standard tap *
  page355_i232
#ISCELL
  standard tap *
  page355_i233
#ISCELL
  standard tap *
  page355_i234
#ISCELL
  standard tap *
  page355_i235
#CELL
  pure_quanta q_cap_diffbus *
  page355_i236
#ISCELL
  standard offpage *
  page355_i237
#ISCELL
  standard offpage *
  page355_i238
#ISCELL
  standard offpage *
  page355_i239
#ISCELL
  standard tap *
  page355_i24
#ISCELL
  standard offpage *
  page355_i240
#ISCELL
  standard tap *
  page355_i241
#ISCELL
  standard tap *
  page355_i242
#ISCELL
  standard tap *
  page355_i243
#ISCELL
  standard tap *
  page355_i244
#ISCELL
  standard tap *
  page355_i245
#ISCELL
  standard tap *
  page355_i246
#CELL
  pure_quanta q_cap_diffbus *
  page355_i247
#CELL
  pure_quanta q_cap_diffbus *
  page355_i248
#CELL
  pure_quanta q_cap_diffbus *
  page355_i249
#ISCELL
  standard tap *
  page355_i25
#CELL
  pure_quanta q_cap_diffbus *
  page355_i250
#CELL
  pure_quanta q_cap_diffbus *
  page355_i251
#ISCELL
  standard tap *
  page355_i252
#ISCELL
  standard tap *
  page355_i253
#ISCELL
  standard tap *
  page355_i254
#ISCELL
  standard tap *
  page355_i255
#ISCELL
  standard tap *
  page355_i256
#ISCELL
  standard tap *
  page355_i257
#ISCELL
  standard offpage *
  page355_i258
#ISCELL
  standard offpage *
  page355_i259
#ISCELL
  standard tap *
  page355_i26
#ISCELL
  standard offpage *
  page355_i260
#ISCELL
  standard offpage *
  page355_i261
#ISCELL
  standard offpage *
  page355_i262
#ISCELL
  standard offpage *
  page355_i263
#ISCELL
  standard tap *
  page355_i264
#ISCELL
  standard tap *
  page355_i27
#ISCELL
  standard tap *
  page355_i28
#ISCELL
  standard offpage *
  page355_i29
#ISCELL
  standard tap *
  page355_i3
#ISCELL
  standard offpage *
  page355_i30
#ISCELL
  standard tap *
  page355_i31
#ISCELL
  standard tap *
  page355_i32
#ISCELL
  standard tap *
  page355_i33
#ISCELL
  standard tap *
  page355_i34
#ISCELL
  standard tap *
  page355_i35
#ISCELL
  standard tap *
  page355_i36
#ISCELL
  standard tap *
  page355_i37
#ISCELL
  standard tap *
  page355_i38
#ISCELL
  standard tap *
  page355_i39
#ISCELL
  standard tap *
  page355_i4
#ISCELL
  standard tap *
  page355_i40
#ISCELL
  standard tap *
  page355_i41
#ISCELL
  standard tap *
  page355_i42
#ISCELL
  standard tap *
  page355_i43
#ISCELL
  standard tap *
  page355_i44
#ISCELL
  standard tap *
  page355_i45
#ISCELL
  standard tap *
  page355_i46
#ISCELL
  standard tap *
  page355_i47
#ISCELL
  standard tap *
  page355_i48
#ISCELL
  standard tap *
  page355_i49
#ISCELL
  standard tap *
  page355_i5
#ISCELL
  standard tap *
  page355_i50
#CELL
  pure_quanta q_cap_diffbus *
  page355_i51
#CELL
  pure_quanta q_cap_diffbus *
  page355_i52
#CELL
  pure_quanta q_cap_diffbus *
  page355_i53
#CELL
  pure_quanta q_cap_diffbus *
  page355_i54
#CELL
  pure_quanta q_cap_diffbus *
  page355_i55
#CELL
  pure_quanta q_cap_diffbus *
  page355_i56
#CELL
  pure_quanta q_cap_diffbus *
  page355_i57
#CELL
  pure_quanta q_cap_diffbus *
  page355_i58
#ISCELL
  standard tap *
  page355_i59
#ISCELL
  standard tap *
  page355_i6
#ISCELL
  standard tap *
  page355_i60
#ISCELL
  standard tap *
  page355_i61
#ISCELL
  standard tap *
  page355_i62
#ISCELL
  standard tap *
  page355_i63
#ISCELL
  standard tap *
  page355_i64
#ISCELL
  standard tap *
  page355_i65
#ISCELL
  standard tap *
  page355_i66
#CELL
  pure_quanta q_cap_diffbus *
  page355_i67
#CELL
  pure_quanta q_cap_diffbus *
  page355_i68
#CELL
  pure_quanta q_cap_diffbus *
  page355_i69
#CELL
  pure_quanta q_cap_diffbus *
  page355_i7
#CELL
  pure_quanta q_cap_diffbus *
  page355_i70
#CELL
  pure_quanta q_cap_diffbus *
  page355_i71
#CELL
  pure_quanta q_cap_diffbus *
  page355_i72
#CELL
  pure_quanta q_cap_diffbus *
  page355_i73
#CELL
  pure_quanta q_cap_diffbus *
  page355_i74
#CELL
  pure_quanta q_cap_diffbus *
  page355_i75
#CELL
  pure_quanta q_cap_diffbus *
  page355_i76
#CELL
  pure_quanta q_cap_diffbus *
  page355_i77
#CELL
  pure_quanta q_cap_diffbus *
  page355_i78
#CELL
  pure_quanta q_cap_diffbus *
  page355_i79
#CELL
  pure_quanta q_cap_diffbus *
  page355_i8
#CELL
  pure_quanta q_cap_diffbus *
  page355_i80
#CELL
  pure_quanta q_cap_diffbus *
  page355_i81
#CELL
  pure_quanta q_cap_diffbus *
  page355_i82
#CELL
  pure_quanta q_cap_diffbus *
  page355_i83
#CELL
  pure_quanta q_cap_diffbus *
  page355_i84
#CELL
  pure_quanta q_cap_diffbus *
  page355_i85
#CELL
  pure_quanta q_cap_diffbus *
  page355_i86
#ISCELL
  standard tap *
  page355_i87
#ISCELL
  standard tap *
  page355_i88
#ISCELL
  standard tap *
  page355_i89
#CELL
  pure_quanta q_cap_diffbus *
  page355_i9
#ISCELL
  standard tap *
  page355_i90
#ISCELL
  standard tap *
  page355_i91
#ISCELL
  standard tap *
  page355_i92
#ISCELL
  standard tap *
  page355_i93
#ISCELL
  standard tap *
  page355_i94
#ISCELL
  standard tap *
  page355_i95
#ISCELL
  standard tap *
  page355_i96
#ISCELL
  standard tap *
  page355_i97
#ISCELL
  standard tap *
  page355_i98
#ISCELL
  standard tap *
  page355_i99
#ISCELL
  pure_quanta quanta_title_block_c *
  *
#CELL
  pure_quanta q_cap *
  page67_i100
#CELL
  pure_quanta q_cap *
  page67_i101
#CELL
  pure_quanta q_cap *
  page67_i102
#CELL
  pure_quanta q_cap *
  page67_i103
#CELL
  pure_quanta q_cap *
  page67_i104
#ISCELL
  pure_quanta_power universal_gnd *
  page67_i105
#CELL
  pure_quanta q_cap *
  page67_i106
#ISCELL
  pure_quanta_power universal_gnd *
  page67_i107
#CELL
  pure_quanta q_cap *
  page67_i108
#CELL
  pure_quanta q_cap *
  page67_i109
#CELL
  pure_quanta q_cap *
  page67_i110
#ISCELL
  pure_quanta_power universal_power *
  page67_i111
#CELL
  pure_quanta q_cap *
  page67_i112
#CELL
  pure_quanta q_cap *
  page67_i113
#ISCELL
  pure_quanta_power universal_power *
  page67_i114
#CELL
  pure_quanta q_cap *
  page67_i115
#CELL
  pure_quanta q_cap *
  page67_i116
#CELL
  pure_quanta q_cap *
  page67_i117
#CELL
  pure_quanta q_cap *
  page67_i118
#ISCELL
  pure_quanta_power universal_gnd *
  page67_i119
#CELL
  pure_quanta q_cap *
  page67_i120
#CELL
  pure_quanta q_cap *
  page67_i121
#CELL
  pure_quanta q_cap *
  page67_i122
#CELL
  pure_quanta q_cap *
  page67_i123
#CELL
  pure_quanta q_cap *
  page67_i124
#CELL
  pure_quanta q_cap *
  page67_i125
#ISCELL
  pure_quanta_power universal_gnd *
  page67_i126
#CELL
  pure_quanta q_cap *
  page67_i127
#CELL
  pure_quanta q_cap *
  page67_i128
#CELL
  pure_quanta q_cap *
  page67_i129
#ISCELL
  pure_quanta_power universal_gnd *
  page67_i130
#CELL
  pure_quanta q_cap *
  page67_i131
#ISCELL
  pure_quanta_power universal_power *
  page67_i132
#CELL
  pure_quanta q_cap *
  page67_i133
#CELL
  pure_quanta q_cap *
  page67_i134
#CELL
  pure_quanta q_cap *
  page67_i135
#CELL
  pure_quanta q_cap *
  page67_i136
#CELL
  pure_quanta q_cap *
  page67_i137
#CELL
  pure_quanta q_cap *
  page67_i138
#CELL
  pure_quanta q_cap *
  page67_i139
#ISCELL
  pure_quanta_power universal_power *
  page67_i140
#CELL
  pure_quanta q_cap *
  page67_i141
#ISCELL
  pure_quanta_power universal_gnd *
  page67_i142
#CELL
  pure_quanta q_cap *
  page67_i143
#ISCELL
  pure_quanta_power universal_gnd *
  page67_i82
#CELL
  pure_quanta q_cap *
  page67_i83
#ISCELL
  pure_quanta_power universal_power *
  page67_i84
#CELL
  pure_quanta q_cap *
  page67_i85
#CELL
  pure_quanta q_cap *
  page67_i86
#CELL
  pure_quanta q_cap *
  page67_i87
#ISCELL
  pure_quanta_power universal_power *
  page67_i88
#CELL
  pure_quanta q_cap *
  page67_i89
#CELL
  pure_quanta q_cap *
  page67_i90
#ISCELL
  pure_quanta_power universal_power *
  page67_i91
#CELL
  pure_quanta q_cap *
  page67_i92
#CELL
  pure_quanta q_cap *
  page67_i93
#CELL
  pure_quanta q_cap *
  page67_i94
#CELL
  pure_quanta q_cap *
  page67_i95
#CELL
  pure_quanta q_cap *
  page67_i96
#CELL
  pure_quanta q_cap *
  page67_i97
#CELL
  pure_quanta q_cap *
  page67_i98
#CELL
  pure_quanta q_cap *
  page67_i99
#ISCELL
  pure_quanta quanta_title_block_c *
  *
#CELL
  pure_quanta q_cap *
  page68_i1
#CELL
  pure_quanta q_cap *
  page68_i10
#CELL
  pure_quanta q_cap *
  page68_i100
#CELL
  pure_quanta q_cap *
  page68_i101
#CELL
  pure_quanta q_cap *
  page68_i102
#CELL
  pure_quanta q_cap *
  page68_i103
#CELL
  pure_quanta q_cap *
  page68_i104
#CELL
  pure_quanta q_cap *
  page68_i105
#CELL
  pure_quanta q_cap *
  page68_i106
#ISCELL
  pure_quanta_power universal_gnd *
  page68_i107
#CELL
  pure_quanta q_cap *
  page68_i108
#CELL
  pure_quanta q_cap *
  page68_i109
#ISCELL
  pure_quanta_power universal_power *
  page68_i11
#CELL
  pure_quanta q_cap *
  page68_i110
#CELL
  pure_quanta q_cap *
  page68_i12
#ISCELL
  pure_quanta_power universal_power *
  page68_i13
#CELL
  pure_quanta q_cap *
  page68_i14
#CELL
  pure_quanta q_cap *
  page68_i15
#CELL
  pure_quanta q_cap *
  page68_i16
#CELL
  pure_quanta q_cap *
  page68_i17
#ISCELL
  pure_quanta_power universal_gnd *
  page68_i18
#CELL
  pure_quanta q_cap *
  page68_i19
#CELL
  pure_quanta q_cap *
  page68_i2
#CELL
  pure_quanta q_cap *
  page68_i20
#CELL
  pure_quanta q_cap *
  page68_i21
#CELL
  pure_quanta q_cap *
  page68_i22
#CELL
  pure_quanta q_cap *
  page68_i23
#CELL
  pure_quanta q_cap *
  page68_i24
#CELL
  pure_quanta q_cap *
  page68_i25
#CELL
  pure_quanta q_cap *
  page68_i26
#CELL
  pure_quanta q_cap *
  page68_i27
#CELL
  pure_quanta q_cap *
  page68_i28
#CELL
  pure_quanta q_cap *
  page68_i29
#ISCELL
  pure_quanta_power universal_power *
  page68_i3
#CELL
  pure_quanta q_cap *
  page68_i30
#CELL
  pure_quanta q_cap *
  page68_i31
#CELL
  pure_quanta q_cap *
  page68_i32
#CELL
  pure_quanta q_cap *
  page68_i33
#CELL
  pure_quanta q_cap *
  page68_i34
#ISCELL
  pure_quanta_power universal_gnd *
  page68_i35
#CELL
  pure_quanta q_cap *
  page68_i36
#ISCELL
  pure_quanta_power universal_power *
  page68_i37
#CELL
  pure_quanta q_cap *
  page68_i38
#ISCELL
  pure_quanta_power universal_gnd *
  page68_i39
#CELL
  pure_quanta q_cap *
  page68_i4
#CELL
  pure_quanta q_cap *
  page68_i40
#ISCELL
  pure_quanta_power universal_gnd *
  page68_i41
#ISCELL
  pure_quanta_power universal_power *
  page68_i42
#CELL
  pure_quanta q_cap *
  page68_i43
#ISCELL
  pure_quanta_power universal_power *
  page68_i44
#CELL
  pure_quanta q_cap *
  page68_i45
#CELL
  pure_quanta q_cap *
  page68_i46
#CELL
  pure_quanta q_cap *
  page68_i47
#CELL
  pure_quanta q_cap *
  page68_i48
#CELL
  pure_quanta q_cap *
  page68_i49
#CELL
  pure_quanta q_cap *
  page68_i5
#CELL
  pure_quanta q_cap *
  page68_i50
#CELL
  pure_quanta q_cap *
  page68_i51
#CELL
  pure_quanta q_cap *
  page68_i52
#CELL
  pure_quanta q_cap *
  page68_i53
#CELL
  pure_quanta q_cap *
  page68_i54
#CELL
  pure_quanta q_cap *
  page68_i55
#CELL
  pure_quanta q_cap *
  page68_i56
#CELL
  pure_quanta q_cap *
  page68_i57
#CELL
  pure_quanta q_cap *
  page68_i58
#ISCELL
  pure_quanta_power universal_gnd *
  page68_i59
#ISCELL
  pure_quanta_power universal_power *
  page68_i6
#CELL
  pure_quanta q_cap *
  page68_i60
#ISCELL
  pure_quanta_power universal_power *
  page68_i61
#CELL
  pure_quanta q_cap *
  page68_i62
#CELL
  pure_quanta q_cap *
  page68_i63
#ISCELL
  pure_quanta_power universal_power *
  page68_i64
#CELL
  pure_quanta q_cap *
  page68_i65
#CELL
  pure_quanta q_cap *
  page68_i66
#CELL
  pure_quanta q_cap *
  page68_i67
#ISCELL
  pure_quanta_power universal_gnd *
  page68_i68
#CELL
  pure_quanta q_cap *
  page68_i69
#CELL
  pure_quanta q_cap *
  page68_i7
#CELL
  pure_quanta q_cap *
  page68_i70
#CELL
  pure_quanta q_cap *
  page68_i71
#CELL
  pure_quanta q_cap *
  page68_i72
#CELL
  pure_quanta q_cap *
  page68_i73
#CELL
  pure_quanta q_cap *
  page68_i74
#CELL
  pure_quanta q_cap *
  page68_i75
#CELL
  pure_quanta q_cap *
  page68_i76
#CELL
  pure_quanta q_cap *
  page68_i77
#CELL
  pure_quanta q_cap *
  page68_i78
#CELL
  pure_quanta q_cap *
  page68_i79
#ISCELL
  pure_quanta_power universal_power *
  page68_i8
#CELL
  pure_quanta q_cap *
  page68_i80
#CELL
  pure_quanta q_cap *
  page68_i81
#CELL
  pure_quanta q_cap *
  page68_i82
#CELL
  pure_quanta q_cap *
  page68_i83
#CELL
  pure_quanta q_cap *
  page68_i84
#ISCELL
  pure_quanta_power universal_gnd *
  page68_i85
#CELL
  pure_quanta q_cap *
  page68_i86
#CELL
  pure_quanta q_cap *
  page68_i87
#ISCELL
  pure_quanta_power universal_gnd *
  page68_i88
#CELL
  pure_quanta q_cap *
  page68_i89
#CELL
  pure_quanta q_cap *
  page68_i9
#ISCELL
  pure_quanta_power universal_gnd *
  page68_i90
#CELL
  pure_quanta q_cap *
  page68_i91
#CELL
  pure_quanta q_cap *
  page68_i92
#CELL
  pure_quanta q_cap *
  page68_i93
#CELL
  pure_quanta q_cap *
  page68_i94
#CELL
  pure_quanta q_cap *
  page68_i95
#CELL
  pure_quanta q_cap *
  page68_i96
#CELL
  pure_quanta q_cap *
  page68_i97
#CELL
  pure_quanta q_cap *
  page68_i98
#CELL
  pure_quanta q_cap *
  page68_i99
#ISCELL
  pure_quanta quanta_title_block_c *
  *
#CELL
  pure_quanta q_cap *
  page69_i1
#CELL
  pure_quanta q_cap *
  page69_i10
#ISCELL
  pure_quanta_power universal_gnd *
  page69_i100
#CELL
  pure_quanta q_cap *
  page69_i101
#CELL
  pure_quanta q_cap *
  page69_i102
#ISCELL
  pure_quanta_power universal_power *
  page69_i103
#CELL
  pure_quanta q_cap *
  page69_i104
#ISCELL
  pure_quanta_power universal_gnd *
  page69_i105
#CELL
  pure_quanta q_cap *
  page69_i106
#ISCELL
  pure_quanta_power universal_power *
  page69_i107
#CELL
  pure_quanta q_cap *
  page69_i108
#ISCELL
  pure_quanta_power universal_power *
  page69_i109
#CELL
  pure_quanta q_cap *
  page69_i11
#ISCELL
  pure_quanta_power universal_gnd *
  page69_i110
#CELL
  pure_quanta q_cap *
  page69_i111
#CELL
  pure_quanta q_cap *
  page69_i112
#CELL
  pure_quanta q_cap *
  page69_i113
#CELL
  pure_quanta q_cap *
  page69_i114
#CELL
  pure_quanta q_cap *
  page69_i115
#CELL
  pure_quanta q_cap *
  page69_i116
#CELL
  pure_quanta q_cap *
  page69_i117
#CELL
  pure_quanta q_cap *
  page69_i118
#CELL
  pure_quanta q_cap *
  page69_i119
#ISCELL
  pure_quanta_power universal_power *
  page69_i12
#CELL
  pure_quanta q_cap *
  page69_i120
#CELL
  pure_quanta q_cap *
  page69_i121
#CELL
  pure_quanta q_cap *
  page69_i122
#CELL
  pure_quanta q_cap *
  page69_i123
#CELL
  pure_quanta q_cap *
  page69_i124
#CELL
  pure_quanta q_cap *
  page69_i125
#CELL
  pure_quanta q_cap *
  page69_i126
#CELL
  pure_quanta q_cap *
  page69_i127
#ISCELL
  pure_quanta_power universal_gnd *
  page69_i128
#CELL
  pure_quanta q_cap *
  page69_i129
#CELL
  pure_quanta q_cap *
  page69_i13
#CELL
  pure_quanta q_cap *
  page69_i130
#CELL
  pure_quanta q_cap *
  page69_i131
#CELL
  pure_quanta q_cap *
  page69_i132
#CELL
  pure_quanta q_cap *
  page69_i133
#CELL
  pure_quanta q_cap *
  page69_i134
#CELL
  pure_quanta q_cap *
  page69_i135
#CELL
  pure_quanta q_cap *
  page69_i136
#ISCELL
  pure_quanta_power universal_gnd *
  page69_i137
#CELL
  pure_quanta q_cap *
  page69_i138
#CELL
  pure_quanta q_cap *
  page69_i139
#ISCELL
  pure_quanta_power universal_power *
  page69_i14
#CELL
  pure_quanta q_cap *
  page69_i140
#ISCELL
  pure_quanta_power universal_gnd *
  page69_i141
#CELL
  pure_quanta q_cap *
  page69_i142
#CELL
  pure_quanta q_cap *
  page69_i143
#CELL
  pure_quanta q_cap *
  page69_i144
#CELL
  pure_quanta q_cap *
  page69_i145
#CELL
  pure_quanta q_cap *
  page69_i146
#CELL
  pure_quanta q_cap *
  page69_i147
#ISCELL
  pure_quanta_power universal_gnd *
  page69_i148
#CELL
  pure_quanta q_cap *
  page69_i149
#CELL
  pure_quanta q_cap *
  page69_i15
#ISCELL
  pure_quanta_power universal_gnd *
  page69_i150
#CELL
  pure_quanta q_cap *
  page69_i151
#CELL
  pure_quanta q_cap *
  page69_i152
#CELL
  pure_quanta q_cap *
  page69_i153
#CELL
  pure_quanta q_cap *
  page69_i154
#CELL
  pure_quanta q_cap *
  page69_i155
#CELL
  pure_quanta q_cap *
  page69_i156
#CELL
  pure_quanta q_cap *
  page69_i157
#CELL
  pure_quanta q_cap *
  page69_i158
#CELL
  pure_quanta q_cap *
  page69_i159
#CELL
  pure_quanta q_cap *
  page69_i16
#CELL
  pure_quanta q_cap *
  page69_i160
#CELL
  pure_quanta q_cap *
  page69_i161
#CELL
  pure_quanta q_cap *
  page69_i162
#CELL
  pure_quanta q_cap *
  page69_i163
#CELL
  pure_quanta q_cap *
  page69_i164
#CELL
  pure_quanta q_cap *
  page69_i165
#CELL
  pure_quanta q_cap *
  page69_i166
#CELL
  pure_quanta q_cap *
  page69_i167
#CELL
  pure_quanta q_cap *
  page69_i168
#CELL
  pure_quanta q_cap *
  page69_i169
#ISCELL
  pure_quanta_power universal_power *
  page69_i17
#CELL
  pure_quanta q_cap *
  page69_i170
#ISCELL
  pure_quanta_power universal_gnd *
  page69_i171
#CELL
  pure_quanta q_cap *
  page69_i172
#CELL
  pure_quanta q_cap *
  page69_i173
#ISCELL
  pure_quanta_power universal_gnd *
  page69_i174
#CELL
  pure_quanta q_cap *
  page69_i175
#CELL
  pure_quanta q_cap *
  page69_i18
#CELL
  pure_quanta q_cap *
  page69_i19
#ISCELL
  pure_quanta_power universal_power *
  page69_i2
#CELL
  pure_quanta q_cap *
  page69_i20
#ISCELL
  pure_quanta_power universal_power *
  page69_i21
#CELL
  pure_quanta q_cap *
  page69_i22
#ISCELL
  pure_quanta_power universal_power *
  page69_i23
#CELL
  pure_quanta q_cap *
  page69_i24
#CELL
  pure_quanta q_cap *
  page69_i25
#CELL
  pure_quanta q_cap *
  page69_i26
#CELL
  pure_quanta q_cap *
  page69_i27
#CELL
  pure_quanta q_cap *
  page69_i28
#CELL
  pure_quanta q_cap *
  page69_i29
#CELL
  pure_quanta q_cap *
  page69_i3
#CELL
  pure_quanta q_cap *
  page69_i30
#CELL
  pure_quanta q_cap *
  page69_i31
#ISCELL
  pure_quanta_power universal_gnd *
  page69_i32
#CELL
  pure_quanta q_cap *
  page69_i33
#CELL
  pure_quanta q_cap *
  page69_i34
#CELL
  pure_quanta q_cap *
  page69_i35
#CELL
  pure_quanta q_cap *
  page69_i36
#CELL
  pure_quanta q_cap *
  page69_i37
#CELL
  pure_quanta q_cap *
  page69_i38
#CELL
  pure_quanta q_cap *
  page69_i39
#CELL
  pure_quanta q_cap *
  page69_i4
#CELL
  pure_quanta q_cap *
  page69_i40
#CELL
  pure_quanta q_cap *
  page69_i41
#CELL
  pure_quanta q_cap *
  page69_i42
#CELL
  pure_quanta q_cap *
  page69_i43
#CELL
  pure_quanta q_cap *
  page69_i44
#CELL
  pure_quanta q_cap *
  page69_i45
#CELL
  pure_quanta q_cap *
  page69_i46
#CELL
  pure_quanta q_cap *
  page69_i47
#CELL
  pure_quanta q_cap *
  page69_i48
#CELL
  pure_quanta q_cap *
  page69_i49
#ISCELL
  pure_quanta_power universal_power *
  page69_i5
#CELL
  pure_quanta q_cap *
  page69_i50
#CELL
  pure_quanta q_cap *
  page69_i51
#CELL
  pure_quanta q_cap *
  page69_i52
#CELL
  pure_quanta q_cap *
  page69_i53
#ISCELL
  pure_quanta_power universal_power *
  page69_i54
#ISCELL
  pure_quanta_power universal_gnd *
  page69_i55
#CELL
  pure_quanta q_cap *
  page69_i56
#ISCELL
  pure_quanta_power universal_gnd *
  page69_i57
#CELL
  pure_quanta q_cap *
  page69_i58
#ISCELL
  pure_quanta_power universal_power *
  page69_i59
#CELL
  pure_quanta q_cap *
  page69_i6
#CELL
  pure_quanta q_cap *
  page69_i60
#CELL
  pure_quanta q_cap *
  page69_i61
#CELL
  pure_quanta q_cap *
  page69_i62
#CELL
  pure_quanta q_cap *
  page69_i63
#CELL
  pure_quanta q_cap *
  page69_i64
#CELL
  pure_quanta q_cap *
  page69_i65
#CELL
  pure_quanta q_cap *
  page69_i66
#CELL
  pure_quanta q_cap *
  page69_i67
#ISCELL
  pure_quanta_power universal_gnd *
  page69_i68
#CELL
  pure_quanta q_cap *
  page69_i69
#CELL
  pure_quanta q_cap *
  page69_i7
#ISCELL
  pure_quanta_power universal_power *
  page69_i70
#CELL
  pure_quanta q_cap *
  page69_i71
#ISCELL
  pure_quanta_power universal_power *
  page69_i72
#ISCELL
  pure_quanta_power universal_gnd *
  page69_i73
#CELL
  pure_quanta q_cap *
  page69_i74
#ISCELL
  pure_quanta_power universal_gnd *
  page69_i75
#CELL
  pure_quanta q_cap *
  page69_i76
#ISCELL
  pure_quanta_power universal_power *
  page69_i77
#CELL
  pure_quanta q_cap *
  page69_i78
#CELL
  pure_quanta q_cap *
  page69_i79
#ISCELL
  pure_quanta_power universal_power *
  page69_i8
#CELL
  pure_quanta q_cap *
  page69_i80
#CELL
  pure_quanta q_cap *
  page69_i81
#CELL
  pure_quanta q_cap *
  page69_i82
#CELL
  pure_quanta q_cap *
  page69_i83
#CELL
  pure_quanta q_cap *
  page69_i84
#CELL
  pure_quanta q_cap *
  page69_i85
#CELL
  pure_quanta q_cap *
  page69_i86
#CELL
  pure_quanta q_cap *
  page69_i87
#CELL
  pure_quanta q_cap *
  page69_i88
#CELL
  pure_quanta q_cap *
  page69_i89
#CELL
  pure_quanta q_cap *
  page69_i9
#CELL
  pure_quanta q_cap *
  page69_i90
#CELL
  pure_quanta q_cap *
  page69_i91
#CELL
  pure_quanta q_cap *
  page69_i92
#CELL
  pure_quanta q_cap *
  page69_i93
#CELL
  pure_quanta q_cap *
  page69_i94
#CELL
  pure_quanta q_cap *
  page69_i95
#CELL
  pure_quanta q_cap *
  page69_i96
#CELL
  pure_quanta q_cap *
  page69_i97
#CELL
  pure_quanta q_cap *
  page69_i98
#CELL
  pure_quanta q_cap *
  page69_i99
#ISCELL
  pure_quanta quanta_title_block_c *
  *
#CELL
  pure_quanta q_cap *
  page70_i1
#CELL
  pure_quanta q_cap *
  page70_i10
#CELL
  pure_quanta q_cap *
  page70_i11
#CELL
  pure_quanta q_cap *
  page70_i12
#CELL
  pure_quanta q_cap *
  page70_i13
#CELL
  pure_quanta q_cap *
  page70_i14
#CELL
  pure_quanta q_cap *
  page70_i15
#CELL
  pure_quanta q_cap *
  page70_i16
#ISCELL
  pure_quanta_power universal_gnd *
  page70_i17
#CELL
  pure_quanta q_cap *
  page70_i18
#ISCELL
  pure_quanta_power universal_power *
  page70_i2
#ISCELL
  pure_quanta_power universal_power *
  page70_i23
#ISCELL
  pure_quanta_power universal_gnd *
  page70_i24
#CELL
  pure_quanta q_cap *
  page70_i25
#CELL
  pure_quanta q_cap *
  page70_i26
#CELL
  pure_quanta q_cap *
  page70_i3
#ISCELL
  pure_quanta_power universal_power *
  page70_i4
#ISCELL
  pure_quanta_power universal_gnd *
  page70_i7
#CELL
  pure_quanta q_cap *
  page70_i8
#CELL
  pure_quanta q_cap *
  page70_i9
#ISCELL
  pure_quanta quanta_title_block_c *
  *
#CELL
  pure_quanta q_cap *
  page71_i1
#ISCELL
  pure_quanta_power universal_power *
  page71_i10
#CELL
  pure_quanta q_cap *
  page71_i11
#CELL
  pure_quanta q_cap *
  page71_i12
#CELL
  pure_quanta q_cap *
  page71_i13
#CELL
  pure_quanta q_cap *
  page71_i14
#CELL
  pure_quanta q_cap *
  page71_i15
#CELL
  pure_quanta q_cap *
  page71_i16
#ISCELL
  pure_quanta_power universal_gnd *
  page71_i17
#CELL
  pure_quanta q_cap *
  page71_i18
#CELL
  pure_quanta q_cap *
  page71_i19
#ISCELL
  pure_quanta_power universal_power *
  page71_i2
#CELL
  pure_quanta q_cap *
  page71_i20
#CELL
  pure_quanta q_cap *
  page71_i21
#ISCELL
  pure_quanta_power universal_gnd *
  page71_i22
#CELL
  pure_quanta q_cap *
  page71_i23
#CELL
  pure_quanta q_cap *
  page71_i24
#CELL
  pure_quanta q_cap *
  page71_i25
#CELL
  pure_quanta q_cap *
  page71_i26
#ISCELL
  pure_quanta_power universal_gnd *
  page71_i27
#CELL
  pure_quanta q_cap *
  page71_i28
#ISCELL
  pure_quanta_power universal_gnd *
  page71_i29
#CELL
  pure_quanta q_cap *
  page71_i3
#CELL
  pure_quanta q_cap *
  page71_i30
#CELL
  pure_quanta q_cap *
  page71_i31
#CELL
  pure_quanta q_cap *
  page71_i32
#CELL
  pure_quanta q_cap *
  page71_i33
#CELL
  pure_quanta q_cap *
  page71_i34
#CELL
  pure_quanta q_cap *
  page71_i35
#CELL
  pure_quanta q_cap *
  page71_i36
#CELL
  pure_quanta q_cap *
  page71_i37
#CELL
  pure_quanta q_cap *
  page71_i38
#CELL
  pure_quanta q_cap *
  page71_i39
#ISCELL
  pure_quanta_power universal_power *
  page71_i4
#CELL
  pure_quanta q_cap *
  page71_i40
#CELL
  pure_quanta q_cap *
  page71_i41
#CELL
  pure_quanta q_cap *
  page71_i42
#CELL
  pure_quanta q_cap *
  page71_i43
#CELL
  pure_quanta q_cap *
  page71_i44
#CELL
  pure_quanta q_cap *
  page71_i45
#ISCELL
  pure_quanta_power universal_gnd *
  page71_i46
#CELL
  pure_quanta q_cap *
  page71_i47
#ISCELL
  pure_quanta_power universal_power *
  page71_i48
#CELL
  pure_quanta q_cap *
  page71_i49
#CELL
  pure_quanta q_cap *
  page71_i5
#CELL
  pure_quanta q_cap *
  page71_i50
#ISCELL
  pure_quanta_power universal_gnd *
  page71_i51
#CELL
  pure_quanta q_cap *
  page71_i52
#CELL
  pure_quanta q_cap *
  page71_i53
#CELL
  pure_quanta q_cap *
  page71_i54
#ISCELL
  pure_quanta_power universal_power *
  page71_i55
#CELL
  pure_quanta q_cap *
  page71_i56
#CELL
  pure_quanta q_cap *
  page71_i57
#CELL
  pure_quanta q_cap *
  page71_i58
#CELL
  pure_quanta q_cap *
  page71_i59
#ISCELL
  pure_quanta_power universal_power *
  page71_i6
#ISCELL
  pure_quanta_power universal_gnd *
  page71_i60
#CELL
  pure_quanta q_cap *
  page71_i61
#CELL
  pure_quanta q_cap *
  page71_i62
#CELL
  pure_quanta q_cap *
  page71_i7
#ISCELL
  pure_quanta_power universal_power *
  page71_i8
#CELL
  pure_quanta q_cap *
  page71_i9
#ISCELL
  pure_quanta quanta_title_block_c *
  *
#CELL
  pure_quanta q_cap *
  page72_i1
#CELL
  pure_quanta q_cap *
  page72_i10
#CELL
  pure_quanta q_cap *
  page72_i100
#CELL
  pure_quanta q_cap *
  page72_i101
#CELL
  pure_quanta q_cap *
  page72_i102
#CELL
  pure_quanta q_cap *
  page72_i103
#CELL
  pure_quanta q_cap *
  page72_i104
#CELL
  pure_quanta q_cap *
  page72_i105
#CELL
  pure_quanta q_cap *
  page72_i106
#CELL
  pure_quanta q_cap *
  page72_i107
#ISCELL
  pure_quanta_power universal_gnd *
  page72_i108
#CELL
  pure_quanta q_cap *
  page72_i109
#CELL
  pure_quanta q_cap *
  page72_i11
#CELL
  pure_quanta q_cap *
  page72_i110
#CELL
  pure_quanta q_cap *
  page72_i12
#CELL
  pure_quanta q_cap *
  page72_i13
#CELL
  pure_quanta q_cap *
  page72_i14
#CELL
  pure_quanta q_cap *
  page72_i15
#ISCELL
  pure_quanta_power universal_power *
  page72_i16
#CELL
  pure_quanta q_cap *
  page72_i17
#ISCELL
  pure_quanta_power universal_power *
  page72_i18
#CELL
  pure_quanta q_cap *
  page72_i19
#ISCELL
  pure_quanta_power universal_power *
  page72_i2
#CELL
  pure_quanta q_cap *
  page72_i20
#CELL
  pure_quanta q_cap *
  page72_i21
#ISCELL
  pure_quanta_power universal_gnd *
  page72_i22
#CELL
  pure_quanta q_cap *
  page72_i23
#CELL
  pure_quanta q_cap *
  page72_i24
#CELL
  pure_quanta q_cap *
  page72_i25
#CELL
  pure_quanta q_cap *
  page72_i26
#CELL
  pure_quanta q_cap *
  page72_i27
#CELL
  pure_quanta q_cap *
  page72_i28
#CELL
  pure_quanta q_cap *
  page72_i29
#CELL
  pure_quanta q_cap *
  page72_i3
#CELL
  pure_quanta q_cap *
  page72_i30
#CELL
  pure_quanta q_cap *
  page72_i31
#CELL
  pure_quanta q_cap *
  page72_i32
#CELL
  pure_quanta q_cap *
  page72_i33
#CELL
  pure_quanta q_cap *
  page72_i34
#CELL
  pure_quanta q_cap *
  page72_i35
#CELL
  pure_quanta q_cap *
  page72_i36
#CELL
  pure_quanta q_cap *
  page72_i37
#CELL
  pure_quanta q_cap *
  page72_i38
#ISCELL
  pure_quanta_power universal_power *
  page72_i39
#CELL
  pure_quanta q_cap *
  page72_i4
#CELL
  pure_quanta q_cap *
  page72_i40
#CELL
  pure_quanta q_cap *
  page72_i41
#CELL
  pure_quanta q_cap *
  page72_i42
#ISCELL
  pure_quanta_power universal_gnd *
  page72_i43
#CELL
  pure_quanta q_cap *
  page72_i44
#ISCELL
  pure_quanta_power universal_gnd *
  page72_i45
#CELL
  pure_quanta q_cap *
  page72_i46
#CELL
  pure_quanta q_cap *
  page72_i47
#CELL
  pure_quanta q_cap *
  page72_i48
#ISCELL
  pure_quanta_power universal_gnd *
  page72_i49
#CELL
  pure_quanta q_cap *
  page72_i5
#CELL
  pure_quanta q_cap *
  page72_i50
#CELL
  pure_quanta q_cap *
  page72_i51
#ISCELL
  pure_quanta_power universal_power *
  page72_i52
#CELL
  pure_quanta q_cap *
  page72_i53
#ISCELL
  pure_quanta_power universal_power *
  page72_i54
#CELL
  pure_quanta q_cap *
  page72_i55
#CELL
  pure_quanta q_cap *
  page72_i56
#CELL
  pure_quanta q_cap *
  page72_i57
#CELL
  pure_quanta q_cap *
  page72_i58
#CELL
  pure_quanta q_cap *
  page72_i59
#ISCELL
  pure_quanta_power universal_power *
  page72_i6
#CELL
  pure_quanta q_cap *
  page72_i60
#CELL
  pure_quanta q_cap *
  page72_i61
#CELL
  pure_quanta q_cap *
  page72_i62
#CELL
  pure_quanta q_cap *
  page72_i63
#CELL
  pure_quanta q_cap *
  page72_i64
#ISCELL
  pure_quanta_power universal_gnd *
  page72_i65
#CELL
  pure_quanta q_cap *
  page72_i66
#ISCELL
  pure_quanta_power universal_power *
  page72_i67
#CELL
  pure_quanta q_cap *
  page72_i68
#ISCELL
  pure_quanta_power universal_power *
  page72_i69
#CELL
  pure_quanta q_cap *
  page72_i7
#CELL
  pure_quanta q_cap *
  page72_i70
#CELL
  pure_quanta q_cap *
  page72_i71
#CELL
  pure_quanta q_cap *
  page72_i72
#ISCELL
  pure_quanta_power universal_gnd *
  page72_i73
#CELL
  pure_quanta q_cap *
  page72_i74
#CELL
  pure_quanta q_cap *
  page72_i75
#CELL
  pure_quanta q_cap *
  page72_i76
#CELL
  pure_quanta q_cap *
  page72_i77
#CELL
  pure_quanta q_cap *
  page72_i78
#CELL
  pure_quanta q_cap *
  page72_i79
#ISCELL
  pure_quanta_power universal_power *
  page72_i8
#CELL
  pure_quanta q_cap *
  page72_i80
#CELL
  pure_quanta q_cap *
  page72_i81
#CELL
  pure_quanta q_cap *
  page72_i82
#CELL
  pure_quanta q_cap *
  page72_i83
#CELL
  pure_quanta q_cap *
  page72_i84
#CELL
  pure_quanta q_cap *
  page72_i85
#CELL
  pure_quanta q_cap *
  page72_i86
#CELL
  pure_quanta q_cap *
  page72_i87
#CELL
  pure_quanta q_cap *
  page72_i88
#CELL
  pure_quanta q_cap *
  page72_i89
#CELL
  pure_quanta q_cap *
  page72_i9
#CELL
  pure_quanta q_cap *
  page72_i90
#CELL
  pure_quanta q_cap *
  page72_i91
#CELL
  pure_quanta q_cap *
  page72_i92
#CELL
  pure_quanta q_cap *
  page72_i93
#CELL
  pure_quanta q_cap *
  page72_i94
#ISCELL
  pure_quanta_power universal_gnd *
  page72_i95
#CELL
  pure_quanta q_cap *
  page72_i96
#ISCELL
  pure_quanta_power universal_gnd *
  page72_i97
#CELL
  pure_quanta q_cap *
  page72_i98
#ISCELL
  pure_quanta_power universal_gnd *
  page72_i99
#ISCELL
  pure_quanta quanta_title_block_c *
  *
#CELL
  pure_quanta q_cap *
  page73_i1
#ISCELL
  pure_quanta_power universal_power *
  page73_i10
#CELL
  pure_quanta q_cap *
  page73_i100
#CELL
  pure_quanta q_cap *
  page73_i101
#CELL
  pure_quanta q_cap *
  page73_i102
#CELL
  pure_quanta q_cap *
  page73_i103
#CELL
  pure_quanta q_cap *
  page73_i104
#CELL
  pure_quanta q_cap *
  page73_i105
#CELL
  pure_quanta q_cap *
  page73_i106
#CELL
  pure_quanta q_cap *
  page73_i107
#CELL
  pure_quanta q_cap *
  page73_i108
#CELL
  pure_quanta q_cap *
  page73_i109
#CELL
  pure_quanta q_cap *
  page73_i11
#CELL
  pure_quanta q_cap *
  page73_i110
#CELL
  pure_quanta q_cap *
  page73_i111
#CELL
  pure_quanta q_cap *
  page73_i112
#CELL
  pure_quanta q_cap *
  page73_i113
#CELL
  pure_quanta q_cap *
  page73_i114
#ISCELL
  pure_quanta_power universal_gnd *
  page73_i115
#CELL
  pure_quanta q_cap *
  page73_i116
#CELL
  pure_quanta q_cap *
  page73_i117
#CELL
  pure_quanta q_cap *
  page73_i118
#CELL
  pure_quanta q_cap *
  page73_i119
#ISCELL
  pure_quanta_power universal_power *
  page73_i12
#CELL
  pure_quanta q_cap *
  page73_i120
#CELL
  pure_quanta q_cap *
  page73_i121
#CELL
  pure_quanta q_cap *
  page73_i122
#CELL
  pure_quanta q_cap *
  page73_i123
#CELL
  pure_quanta q_cap *
  page73_i124
#CELL
  pure_quanta q_cap *
  page73_i125
#ISCELL
  pure_quanta_power universal_gnd *
  page73_i126
#CELL
  pure_quanta q_cap *
  page73_i127
#ISCELL
  pure_quanta_power universal_gnd *
  page73_i128
#CELL
  pure_quanta q_cap *
  page73_i129
#CELL
  pure_quanta q_cap *
  page73_i13
#ISCELL
  pure_quanta_power universal_power *
  page73_i130
#CELL
  pure_quanta q_cap *
  page73_i131
#ISCELL
  pure_quanta_power universal_gnd *
  page73_i132
#CELL
  pure_quanta q_cap *
  page73_i133
#CELL
  pure_quanta q_cap *
  page73_i134
#ISCELL
  pure_quanta_power universal_power *
  page73_i135
#CELL
  pure_quanta q_cap *
  page73_i136
#CELL
  pure_quanta q_cap *
  page73_i137
#CELL
  pure_quanta q_cap *
  page73_i138
#CELL
  pure_quanta q_cap *
  page73_i139
#CELL
  pure_quanta q_cap *
  page73_i14
#CELL
  pure_quanta q_cap *
  page73_i140
#CELL
  pure_quanta q_cap *
  page73_i141
#CELL
  pure_quanta q_cap *
  page73_i142
#ISCELL
  pure_quanta_power universal_power *
  page73_i143
#CELL
  pure_quanta q_cap *
  page73_i144
#CELL
  pure_quanta q_cap *
  page73_i145
#CELL
  pure_quanta q_cap *
  page73_i146
#CELL
  pure_quanta q_cap *
  page73_i147
#CELL
  pure_quanta q_cap *
  page73_i148
#CELL
  pure_quanta q_cap *
  page73_i149
#ISCELL
  pure_quanta_power universal_power *
  page73_i15
#CELL
  pure_quanta q_cap *
  page73_i150
#CELL
  pure_quanta q_cap *
  page73_i151
#CELL
  pure_quanta q_cap *
  page73_i152
#CELL
  pure_quanta q_cap *
  page73_i153
#CELL
  pure_quanta q_cap *
  page73_i154
#CELL
  pure_quanta q_cap *
  page73_i155
#ISCELL
  pure_quanta_power universal_gnd *
  page73_i156
#CELL
  pure_quanta q_cap *
  page73_i157
#ISCELL
  pure_quanta_power universal_gnd *
  page73_i158
#CELL
  pure_quanta q_cap *
  page73_i159
#CELL
  pure_quanta q_cap *
  page73_i16
#CELL
  pure_quanta q_cap *
  page73_i160
#CELL
  pure_quanta q_cap *
  page73_i161
#ISCELL
  pure_quanta_power universal_gnd *
  page73_i162
#CELL
  pure_quanta q_cap *
  page73_i163
#CELL
  pure_quanta q_cap *
  page73_i164
#ISCELL
  pure_quanta_power universal_gnd *
  page73_i165
#CELL
  pure_quanta q_cap *
  page73_i166
#ISCELL
  pure_quanta_power universal_gnd *
  page73_i167
#CELL
  pure_quanta q_cap *
  page73_i168
#CELL
  pure_quanta q_cap *
  page73_i169
#CELL
  pure_quanta q_cap *
  page73_i17
#CELL
  pure_quanta q_cap *
  page73_i170
#ISCELL
  pure_quanta_power universal_gnd *
  page73_i171
#CELL
  pure_quanta q_cap *
  page73_i172
#CELL
  pure_quanta q_cap *
  page73_i173
#CELL
  pure_quanta q_cap *
  page73_i174
#CELL
  pure_quanta q_cap *
  page73_i175
#CELL
  pure_quanta q_cap *
  page73_i18
#CELL
  pure_quanta q_cap *
  page73_i19
#ISCELL
  pure_quanta_power universal_power *
  page73_i2
#CELL
  pure_quanta q_cap *
  page73_i20
#CELL
  pure_quanta q_cap *
  page73_i21
#CELL
  pure_quanta q_cap *
  page73_i22
#CELL
  pure_quanta q_cap *
  page73_i23
#CELL
  pure_quanta q_cap *
  page73_i24
#CELL
  pure_quanta q_cap *
  page73_i25
#CELL
  pure_quanta q_cap *
  page73_i26
#CELL
  pure_quanta q_cap *
  page73_i27
#CELL
  pure_quanta q_cap *
  page73_i28
#CELL
  pure_quanta q_cap *
  page73_i29
#CELL
  pure_quanta q_cap *
  page73_i3
#CELL
  pure_quanta q_cap *
  page73_i30
#ISCELL
  pure_quanta_power universal_gnd *
  page73_i31
#CELL
  pure_quanta q_cap *
  page73_i32
#CELL
  pure_quanta q_cap *
  page73_i33
#CELL
  pure_quanta q_cap *
  page73_i34
#CELL
  pure_quanta q_cap *
  page73_i35
#CELL
  pure_quanta q_cap *
  page73_i36
#CELL
  pure_quanta q_cap *
  page73_i37
#CELL
  pure_quanta q_cap *
  page73_i38
#CELL
  pure_quanta q_cap *
  page73_i39
#CELL
  pure_quanta q_cap *
  page73_i4
#CELL
  pure_quanta q_cap *
  page73_i40
#CELL
  pure_quanta q_cap *
  page73_i41
#CELL
  pure_quanta q_cap *
  page73_i42
#CELL
  pure_quanta q_cap *
  page73_i43
#CELL
  pure_quanta q_cap *
  page73_i44
#CELL
  pure_quanta q_cap *
  page73_i45
#CELL
  pure_quanta q_cap *
  page73_i46
#CELL
  pure_quanta q_cap *
  page73_i47
#CELL
  pure_quanta q_cap *
  page73_i48
#ISCELL
  pure_quanta_power universal_power *
  page73_i49
#CELL
  pure_quanta q_cap *
  page73_i5
#CELL
  pure_quanta q_cap *
  page73_i50
#ISCELL
  pure_quanta_power universal_power *
  page73_i51
#CELL
  pure_quanta q_cap *
  page73_i52
#CELL
  pure_quanta q_cap *
  page73_i53
#ISCELL
  pure_quanta_power universal_power *
  page73_i54
#CELL
  pure_quanta q_cap *
  page73_i55
#CELL
  pure_quanta q_cap *
  page73_i56
#CELL
  pure_quanta q_cap *
  page73_i57
#CELL
  pure_quanta q_cap *
  page73_i58
#CELL
  pure_quanta q_cap *
  page73_i59
#CELL
  pure_quanta q_cap *
  page73_i6
#CELL
  pure_quanta q_cap *
  page73_i60
#CELL
  pure_quanta q_cap *
  page73_i61
#CELL
  pure_quanta q_cap *
  page73_i62
#ISCELL
  pure_quanta_power universal_power *
  page73_i63
#CELL
  pure_quanta q_cap *
  page73_i64
#CELL
  pure_quanta q_cap *
  page73_i65
#CELL
  pure_quanta q_cap *
  page73_i66
#CELL
  pure_quanta q_cap *
  page73_i67
#CELL
  pure_quanta q_cap *
  page73_i68
#CELL
  pure_quanta q_cap *
  page73_i69
#CELL
  pure_quanta q_cap *
  page73_i7
#CELL
  pure_quanta q_cap *
  page73_i70
#CELL
  pure_quanta q_cap *
  page73_i71
#CELL
  pure_quanta q_cap *
  page73_i72
#CELL
  pure_quanta q_cap *
  page73_i73
#CELL
  pure_quanta q_cap *
  page73_i74
#CELL
  pure_quanta q_cap *
  page73_i75
#CELL
  pure_quanta q_cap *
  page73_i76
#CELL
  pure_quanta q_cap *
  page73_i77
#ISCELL
  pure_quanta_power universal_gnd *
  page73_i78
#CELL
  pure_quanta q_cap *
  page73_i79
#CELL
  pure_quanta q_cap *
  page73_i8
#ISCELL
  pure_quanta_power universal_power *
  page73_i80
#CELL
  pure_quanta q_cap *
  page73_i81
#ISCELL
  pure_quanta_power universal_power *
  page73_i82
#ISCELL
  pure_quanta_power universal_gnd *
  page73_i83
#CELL
  pure_quanta q_cap *
  page73_i84
#CELL
  pure_quanta q_cap *
  page73_i85
#CELL
  pure_quanta q_cap *
  page73_i86
#ISCELL
  pure_quanta_power universal_gnd *
  page73_i87
#CELL
  pure_quanta q_cap *
  page73_i88
#ISCELL
  pure_quanta_power universal_gnd *
  page73_i89
#CELL
  pure_quanta q_cap *
  page73_i9
#CELL
  pure_quanta q_cap *
  page73_i90
#ISCELL
  pure_quanta_power universal_power *
  page73_i91
#CELL
  pure_quanta q_cap *
  page73_i92
#ISCELL
  pure_quanta_power universal_power *
  page73_i93
#CELL
  pure_quanta q_cap *
  page73_i94
#ISCELL
  pure_quanta_power universal_gnd *
  page73_i95
#CELL
  pure_quanta q_cap *
  page73_i96
#CELL
  pure_quanta q_cap *
  page73_i97
#ISCELL
  pure_quanta_power universal_power *
  page73_i98
#CELL
  pure_quanta q_cap *
  page73_i99
#ISCELL
  pure_quanta quanta_title_block_c *
  *
#CELL
  pure_quanta q_cap *
  page74_i1
#CELL
  pure_quanta q_cap *
  page74_i10
#CELL
  pure_quanta q_cap *
  page74_i11
#CELL
  pure_quanta q_cap *
  page74_i12
#CELL
  pure_quanta q_cap *
  page74_i13
#CELL
  pure_quanta q_cap *
  page74_i14
#CELL
  pure_quanta q_cap *
  page74_i15
#CELL
  pure_quanta q_cap *
  page74_i16
#ISCELL
  pure_quanta_power universal_gnd *
  page74_i17
#CELL
  pure_quanta q_cap *
  page74_i18
#ISCELL
  pure_quanta_power universal_power *
  page74_i2
#ISCELL
  pure_quanta_power universal_power *
  page74_i23
#ISCELL
  pure_quanta_power universal_gnd *
  page74_i24
#CELL
  pure_quanta q_cap *
  page74_i25
#CELL
  pure_quanta q_cap *
  page74_i26
#CELL
  pure_quanta q_cap *
  page74_i3
#ISCELL
  pure_quanta_power universal_power *
  page74_i4
#ISCELL
  pure_quanta_power universal_gnd *
  page74_i7
#CELL
  pure_quanta q_cap *
  page74_i8
#CELL
  pure_quanta q_cap *
  page74_i9
#ISCELL
  mstr_misc dns *
  *
#ISCELL
  pure_quanta quanta_title_block_c *
  *
#ISCELL
  standard offpage *
  page75_i1
#CELL
  pure_quanta q_res *
  page75_i12
#ISCELL
  pure_quanta_power universal_gnd *
  page75_i15
#ISCELL
  standard offpage *
  page75_i27
#ISCELL
  standard offpage *
  page75_i28
#ISCELL
  standard offpage *
  page75_i3
#ISCELL
  standard offpage *
  page75_i32
#ISCELL
  standard offpage *
  page75_i33
#ISCELL
  standard offpage *
  page75_i35
#ISCELL
  pure_quanta_power universal_power *
  page75_i39
#ISCELL
  standard offpage *
  page75_i4
#CELL
  pure_quanta q_res *
  page75_i41
#CELL
  pure_quanta q_res *
  page75_i43
#CELL
  pure_quanta q_res *
  page75_i44
#CELL
  pure_quanta q_res *
  page75_i45
#CELL
  pure_quanta q_res *
  page75_i46
#ISCELL
  standard offpage *
  page75_i5
#ISCELL
  standard offpage *
  page75_i7
#CELL
  pure_quanta q_res *
  page75_i74
#CELL
  pure_quanta q_res *
  page75_i75
#CELL
  pure_quanta q_res *
  page75_i8
#ISCELL
  standard offpage *
  page75_i80
#ISCELL
  standard offpage *
  page75_i81
#ISCELL
  standard offpage *
  page75_i82
#ISCELL
  standard offpage *
  page75_i83
#ISCELL
  standard offpage *
  page75_i84
#CELL
  pure_quanta q_res *
  page75_i87
#ISCELL
  pure_quanta_power universal_power *
  page75_i88
#CELL
  pure_quanta q_res *
  page75_i89
#CELL
  pure_quanta q_res *
  page75_i9
#CELL
  pure_quanta q_res *
  page75_i90
#CELL
  pure_quanta q_res *
  page75_i91
#CELL
  pure_quanta q_res *
  page75_i92
#ISCELL
  standard offpage *
  page75_i93
#CELL
  pure_quanta q_res *
  page75_i94
#ISCELL
  pure_quanta_power universal_gnd *
  page75_i95
#ISCELL
  standard offpage *
  page75_i96
#CELL
  pure_quanta q_res *
  page75_i97
#ISCELL
  standard offpage *
  page75_i98
#CELL
  pure_quanta q_res *
  page75_i99
#ISCELL
  mstr_misc dns *
  *
#ISCELL
  pure_quanta quanta_title_block_c *
  *
#ISCELL
  standard offpage *
  page76_i100
#ISCELL
  standard offpage *
  page76_i101
#ISCELL
  standard offpage *
  page76_i102
#ISCELL
  standard offpage *
  page76_i103
#ISCELL
  standard offpage *
  page76_i104
#ISCELL
  pure_quanta_power universal_power *
  page76_i105
#CELL
  pure_quanta q_res *
  page76_i106
#CELL
  pure_quanta q_res *
  page76_i107
#CELL
  pure_quanta q_res *
  page76_i108
#ISCELL
  standard offpage *
  page76_i109
#ISCELL
  standard offpage *
  page76_i110
#ISCELL
  standard offpage *
  page76_i111
#CELL
  pure_quanta q_res *
  page76_i115
#CELL
  pure_quanta q_res *
  page76_i116
#CELL
  pure_quanta q_res *
  page76_i117
#CELL
  pure_quanta q_res *
  page76_i118
#CELL
  pure_quanta q_res *
  page76_i119
#ISCELL
  standard offpage *
  page76_i127
#ISCELL
  standard offpage *
  page76_i128
#ISCELL
  standard offpage *
  page76_i129
#ISCELL
  standard offpage *
  page76_i130
#CELL
  pure_quanta q_res *
  page76_i131
#CELL
  pure_quanta q_res *
  page76_i132
#CELL
  pure_quanta q_res *
  page76_i133
#CELL
  pure_quanta q_res *
  page76_i134
#ISCELL
  standard offpage *
  page76_i136
#ISCELL
  pure_quanta_power universal_gnd *
  page76_i138
#ISCELL
  pure_quanta_power universal_gnd *
  page76_i139
#CELL
  pure_quanta q_res *
  page76_i148
#ISCELL
  standard offpage *
  page76_i149
#CELL
  pure_quanta q_res *
  page76_i150
#ISCELL
  standard offpage *
  page76_i151
#ISCELL
  standard offpage *
  page76_i176
#ISCELL
  standard offpage *
  page76_i177
#ISCELL
  standard offpage *
  page76_i179
#CELL
  pure_quanta q_res *
  page76_i180
#ISCELL
  standard offpage *
  page76_i181
#ISCELL
  standard offpage *
  page76_i189
#ISCELL
  standard offpage *
  page76_i190
#CELL
  pure_quanta q_res *
  page76_i191
#ISCELL
  pure_quanta_power universal_power *
  page76_i192
#CELL
  pure_quanta q_res *
  page76_i205
#ISCELL
  standard offpage *
  page76_i206
#CELL
  pure_quanta q_res *
  page76_i207
#ISCELL
  standard offpage *
  page76_i208
#ISCELL
  standard offpage *
  page76_i218
#CELL
  pure_quanta q_res *
  page76_i219
#ISCELL
  standard offpage *
  page76_i220
#CELL
  pure_quanta q_res *
  page76_i221
#ISCELL
  standard offpage *
  page76_i227
#CELL
  pure_quanta q_res *
  page76_i228
#ISCELL
  standard offpage *
  page76_i229
#CELL
  pure_quanta q_res *
  page76_i230
#ISCELL
  standard offpage *
  page76_i232
#ISCELL
  standard offpage *
  page76_i233
#CELL
  pure_quanta q_res *
  page76_i234
#ISCELL
  standard offpage *
  page76_i235
#ISCELL
  standard offpage *
  page76_i236
#ISCELL
  standard offpage *
  page76_i237
#ISCELL
  standard offpage *
  page76_i238
#CELL
  pure_quanta q_res *
  page76_i239
#CELL
  pure_quanta q_res *
  page76_i240
#CELL
  pure_quanta q_res *
  page76_i241
#CELL
  pure_quanta q_res *
  page76_i242
#ISCELL
  pure_quanta_power universal_power *
  page76_i49
#CELL
  pure_quanta q_cap *
  page76_i50
#ISCELL
  pure_quanta_power universal_gnd *
  page76_i51
#ISCELL
  pure_quanta_power universal_power *
  page76_i52
#CELL
  pure_quanta q_cap *
  page76_i53
#ISCELL
  pure_quanta_power universal_gnd *
  page76_i54
#ISCELL
  pure_quanta_power universal_gnd *
  page76_i56
#ISCELL
  pure_quanta_power universal_power *
  page76_i57
#CELL
  pure_quanta q_cap *
  page76_i59
#ISCELL
  pure_quanta_power universal_gnd *
  page76_i62
#CELL
  pure_quanta sn74avc4t774pwr *
  page76_i63
#ISCELL
  pure_quanta_power universal_power *
  page76_i64
#CELL
  pure_quanta q_cap *
  page76_i65
#CELL
  pure_quanta pi4uls3v304azmaex *
  page76_i67
#ISCELL
  pure_quanta_power universal_power *
  page76_i96
#CELL
  pure_quanta q_res *
  page76_i97
#ISCELL
  standard offpage *
  page76_i99
#ISCELL
  mstr_misc dns *
  *
#ISCELL
  pure_quanta quanta_title_block_c *
  *
#CELL
  pure_quanta q_res *
  page77_i1
#ISCELL
  pure_quanta_power universal_gnd *
  page77_i10
#CELL
  pure_quanta q_cap *
  page77_i11
#ISCELL
  pure_quanta_power universal_power *
  page77_i12
#ISCELL
  standard offpage *
  page77_i13
#ISCELL
  standard offpage *
  page77_i14
#CELL
  pure_quanta sn74lvc2g07dckr *
  page77_i15
#ISCELL
  standard offpage *
  page77_i16
#ISCELL
  standard offpage *
  page77_i17
#CELL
  pure_quanta q_cap *
  page77_i19
#ISCELL
  pure_quanta_power gnd *
  page77_i2
#ISCELL
  pure_quanta_power universal_gnd *
  page77_i20
#CELL
  pure_quanta sn74lvc2g07dckr *
  page77_i21
#ISCELL
  pure_quanta_power universal_gnd *
  page77_i22
#ISCELL
  pure_quanta_power universal_power *
  page77_i23
#ISCELL
  standard offpage *
  page77_i3
#ISCELL
  standard offpage *
  page77_i4
#CELL
  pure_quanta q_res *
  page77_i5
#ISCELL
  pure_quanta_power gnd *
  page77_i6
#ISCELL
  pure_quanta_power universal_gnd *
  page77_i9
#ISCELL
  pure_quanta quanta_title_block_c *
  *
#ISCELL
  mstr_misc dns *
  *
#ISCELL
  pure_quanta quanta_title_block_c *
  *
#ISCELL
  standard offpage *
  page79_i1
#ISCELL
  standard offpage *
  page79_i10
#ISCELL
  standard offpage *
  page79_i100
#ISCELL
  standard offpage *
  page79_i101
#ISCELL
  standard offpage *
  page79_i102
#ISCELL
  standard offpage *
  page79_i103
#ISCELL
  standard offpage *
  page79_i104
#ISCELL
  standard offpage *
  page79_i105
#ISCELL
  standard offpage *
  page79_i106
#ISCELL
  standard offpage *
  page79_i107
#ISCELL
  standard offpage *
  page79_i108
#ISCELL
  standard offpage *
  page79_i11
#ISCELL
  standard offpage *
  page79_i110
#ISCELL
  standard offpage *
  page79_i111
#CELL
  pure_quanta q_res *
  page79_i112
#ISCELL
  standard offpage *
  page79_i113
#ISCELL
  standard offpage *
  page79_i114
#CELL
  pure_quanta q_res *
  page79_i115
#ISCELL
  standard offpage *
  page79_i116
#ISCELL
  standard offpage *
  page79_i117
#ISCELL
  standard offpage *
  page79_i118
#ISCELL
  standard offpage *
  page79_i119
#ISCELL
  standard offpage *
  page79_i12
#ISCELL
  standard offpage *
  page79_i120
#CELL
  pure_quanta q_res *
  page79_i121
#CELL
  pure_quanta q_res *
  page79_i122
#ISCELL
  standard offpage *
  page79_i123
#ISCELL
  standard offpage *
  page79_i124
#ISCELL
  standard offpage *
  page79_i127
#CELL
  pure_quanta q_res *
  page79_i128
#CELL
  pure_quanta q_res *
  page79_i129
#ISCELL
  standard offpage *
  page79_i13
#ISCELL
  standard offpage *
  page79_i130
#CELL
  pure_quanta q_res *
  page79_i131
#ISCELL
  standard offpage *
  page79_i132
#ISCELL
  standard offpage *
  page79_i133
#ISCELL
  standard offpage *
  page79_i134
#ISCELL
  standard offpage *
  page79_i135
#ISCELL
  standard offpage *
  page79_i136
#ISCELL
  standard offpage *
  page79_i137
#CELL
  pure_quanta q_res *
  page79_i139
#ISCELL
  standard offpage *
  page79_i140
#CELL
  pure_quanta q_res *
  page79_i141
#ISCELL
  standard offpage *
  page79_i142
#ISCELL
  standard offpage *
  page79_i143
#CELL
  pure_quanta q_res *
  page79_i144
#ISCELL
  standard offpage *
  page79_i145
#CELL
  pure_quanta q_res *
  page79_i146
#CELL
  pure_quanta q_res *
  page79_i147
#ISCELL
  standard offpage *
  page79_i148
#ISCELL
  standard offpage *
  page79_i149
#ISCELL
  standard offpage *
  page79_i15
#CELL
  pure_quanta q_res *
  page79_i153
#ISCELL
  standard offpage *
  page79_i154
#CELL
  pure_quanta q_res *
  page79_i155
#CELL
  pure_quanta q_res *
  page79_i16
#CELL
  pure_quanta q_res *
  page79_i17
#CELL
  pure_quanta q_res *
  page79_i18
#CELL
  pure_quanta q_res *
  page79_i19
#ISCELL
  standard offpage *
  page79_i2
#CELL
  pure_quanta q_res *
  page79_i20
#CELL
  pure_quanta q_res *
  page79_i21
#CELL
  pure_quanta q_res *
  page79_i23
#CELL
  pure_quanta q_res *
  page79_i24
#CELL
  pure_quanta lcmxo3lf9400c5bg484c *
  page79_i25
#ISCELL
  standard offpage *
  page79_i26
#ISCELL
  standard offpage *
  page79_i27
#ISCELL
  standard offpage *
  page79_i28
#ISCELL
  standard offpage *
  page79_i29
#ISCELL
  standard offpage *
  page79_i3
#ISCELL
  standard offpage *
  page79_i30
#ISCELL
  standard offpage *
  page79_i31
#ISCELL
  standard offpage *
  page79_i32
#ISCELL
  standard offpage *
  page79_i33
#ISCELL
  standard offpage *
  page79_i34
#ISCELL
  standard offpage *
  page79_i35
#ISCELL
  standard offpage *
  page79_i36
#ISCELL
  standard offpage *
  page79_i37
#ISCELL
  standard offpage *
  page79_i38
#ISCELL
  standard offpage *
  page79_i39
#ISCELL
  standard offpage *
  page79_i4
#ISCELL
  standard offpage *
  page79_i40
#ISCELL
  standard offpage *
  page79_i41
#ISCELL
  standard offpage *
  page79_i42
#CELL
  pure_quanta q_res *
  page79_i43
#CELL
  pure_quanta q_res *
  page79_i44
#CELL
  pure_quanta q_res *
  page79_i45
#CELL
  pure_quanta q_res *
  page79_i46
#CELL
  pure_quanta q_res *
  page79_i47
#CELL
  pure_quanta q_res *
  page79_i48
#CELL
  pure_quanta q_res *
  page79_i49
#ISCELL
  standard offpage *
  page79_i5
#CELL
  pure_quanta q_res *
  page79_i50
#CELL
  pure_quanta q_res *
  page79_i51
#CELL
  pure_quanta q_res *
  page79_i52
#CELL
  pure_quanta q_res *
  page79_i53
#CELL
  pure_quanta q_res *
  page79_i54
#CELL
  pure_quanta q_res *
  page79_i55
#ISCELL
  standard offpage *
  page79_i56
#ISCELL
  standard offpage *
  page79_i57
#ISCELL
  standard offpage *
  page79_i58
#ISCELL
  standard offpage *
  page79_i59
#ISCELL
  standard offpage *
  page79_i6
#ISCELL
  standard offpage *
  page79_i60
#ISCELL
  standard offpage *
  page79_i61
#ISCELL
  standard offpage *
  page79_i62
#ISCELL
  standard offpage *
  page79_i63
#CELL
  pure_quanta q_res *
  page79_i64
#CELL
  pure_quanta q_res *
  page79_i65
#ISCELL
  standard offpage *
  page79_i66
#ISCELL
  standard offpage *
  page79_i67
#ISCELL
  standard offpage *
  page79_i68
#ISCELL
  standard offpage *
  page79_i69
#ISCELL
  standard offpage *
  page79_i7
#ISCELL
  standard offpage *
  page79_i70
#ISCELL
  standard offpage *
  page79_i71
#ISCELL
  standard offpage *
  page79_i72
#ISCELL
  standard offpage *
  page79_i73
#ISCELL
  standard offpage *
  page79_i75
#ISCELL
  standard offpage *
  page79_i76
#ISCELL
  standard offpage *
  page79_i77
#ISCELL
  standard offpage *
  page79_i78
#CELL
  pure_quanta q_res *
  page79_i79
#ISCELL
  standard offpage *
  page79_i8
#CELL
  pure_quanta q_res *
  page79_i80
#CELL
  pure_quanta q_res *
  page79_i81
#CELL
  pure_quanta q_res *
  page79_i82
#CELL
  pure_quanta q_res *
  page79_i83
#ISCELL
  standard offpage *
  page79_i84
#ISCELL
  standard offpage *
  page79_i85
#ISCELL
  standard offpage *
  page79_i86
#ISCELL
  standard offpage *
  page79_i87
#ISCELL
  standard offpage *
  page79_i88
#ISCELL
  standard offpage *
  page79_i89
#ISCELL
  standard offpage *
  page79_i9
#ISCELL
  standard offpage *
  page79_i90
#ISCELL
  standard offpage *
  page79_i91
#ISCELL
  standard offpage *
  page79_i92
#CELL
  pure_quanta lcmxo3lf9400c5bg484c *
  page79_i94
#ISCELL
  standard offpage *
  page79_i95
#ISCELL
  standard offpage *
  page79_i99
#ISCELL
  mstr_misc dns *
  *
#ISCELL
  pure_quanta quanta_title_block_c *
  *
#ISCELL
  standard offpage *
  page80_i1
#ISCELL
  standard offpage *
  page80_i10
#CELL
  pure_quanta q_res *
  page80_i100
#CELL
  pure_quanta q_res *
  page80_i101
#CELL
  pure_quanta q_res *
  page80_i102
#CELL
  pure_quanta q_res *
  page80_i103
#CELL
  pure_quanta q_res *
  page80_i104
#CELL
  pure_quanta q_res *
  page80_i105
#CELL
  pure_quanta q_res *
  page80_i106
#CELL
  pure_quanta q_res *
  page80_i107
#CELL
  pure_quanta q_res *
  page80_i108
#CELL
  pure_quanta q_res *
  page80_i109
#ISCELL
  standard offpage *
  page80_i11
#CELL
  pure_quanta q_res *
  page80_i110
#CELL
  pure_quanta q_res *
  page80_i111
#CELL
  pure_quanta q_res *
  page80_i112
#CELL
  pure_quanta q_res *
  page80_i113
#CELL
  pure_quanta q_res *
  page80_i114
#CELL
  pure_quanta q_res *
  page80_i115
#CELL
  pure_quanta q_res *
  page80_i116
#CELL
  pure_quanta q_res *
  page80_i117
#CELL
  pure_quanta q_res *
  page80_i118
#CELL
  pure_quanta q_res *
  page80_i119
#ISCELL
  standard offpage *
  page80_i12
#CELL
  pure_quanta q_res *
  page80_i120
#CELL
  pure_quanta q_res *
  page80_i121
#CELL
  pure_quanta q_res *
  page80_i122
#CELL
  pure_quanta q_res *
  page80_i123
#ISCELL
  standard offpage *
  page80_i124
#CELL
  pure_quanta q_res *
  page80_i125
#CELL
  pure_quanta q_res *
  page80_i126
#CELL
  pure_quanta q_res *
  page80_i127
#CELL
  pure_quanta q_res *
  page80_i128
#CELL
  pure_quanta q_res *
  page80_i129
#ISCELL
  standard offpage *
  page80_i13
#CELL
  pure_quanta q_res *
  page80_i130
#CELL
  pure_quanta q_res *
  page80_i131
#ISCELL
  standard offpage *
  page80_i132
#ISCELL
  standard offpage *
  page80_i133
#ISCELL
  standard offpage *
  page80_i134
#ISCELL
  standard offpage *
  page80_i135
#ISCELL
  standard offpage *
  page80_i136
#ISCELL
  standard offpage *
  page80_i137
#ISCELL
  standard offpage *
  page80_i14
#ISCELL
  standard offpage *
  page80_i140
#ISCELL
  standard offpage *
  page80_i141
#ISCELL
  standard offpage *
  page80_i142
#ISCELL
  standard offpage *
  page80_i143
#ISCELL
  standard offpage *
  page80_i144
#ISCELL
  standard offpage *
  page80_i147
#ISCELL
  standard offpage *
  page80_i148
#ISCELL
  standard offpage *
  page80_i15
#ISCELL
  standard offpage *
  page80_i151
#ISCELL
  standard offpage *
  page80_i152
#CELL
  pure_quanta q_res *
  page80_i154
#CELL
  pure_quanta q_res *
  page80_i155
#CELL
  pure_quanta q_res *
  page80_i156
#CELL
  pure_quanta q_res *
  page80_i157
#CELL
  pure_quanta q_res *
  page80_i158
#CELL
  pure_quanta q_res *
  page80_i159
#ISCELL
  standard offpage *
  page80_i16
#CELL
  pure_quanta q_res *
  page80_i160
#CELL
  pure_quanta q_res *
  page80_i161
#CELL
  pure_quanta q_res *
  page80_i162
#CELL
  pure_quanta q_res *
  page80_i163
#CELL
  pure_quanta q_res *
  page80_i164
#CELL
  pure_quanta q_res *
  page80_i165
#CELL
  pure_quanta q_res *
  page80_i166
#CELL
  pure_quanta q_res *
  page80_i167
#CELL
  pure_quanta q_res *
  page80_i168
#CELL
  pure_quanta q_res *
  page80_i169
#ISCELL
  standard offpage *
  page80_i17
#CELL
  pure_quanta q_res *
  page80_i170
#CELL
  pure_quanta q_res *
  page80_i171
#CELL
  pure_quanta q_res *
  page80_i172
#CELL
  pure_quanta q_res *
  page80_i173
#CELL
  pure_quanta q_res *
  page80_i174
#CELL
  pure_quanta q_res *
  page80_i175
#CELL
  pure_quanta q_res *
  page80_i176
#CELL
  pure_quanta q_res *
  page80_i177
#CELL
  pure_quanta q_res *
  page80_i178
#CELL
  pure_quanta q_res *
  page80_i179
#ISCELL
  standard offpage *
  page80_i18
#CELL
  pure_quanta q_res *
  page80_i180
#ISCELL
  standard offpage *
  page80_i181
#ISCELL
  standard offpage *
  page80_i182
#ISCELL
  standard offpage *
  page80_i183
#ISCELL
  standard offpage *
  page80_i184
#ISCELL
  standard offpage *
  page80_i185
#ISCELL
  standard offpage *
  page80_i186
#ISCELL
  standard offpage *
  page80_i187
#ISCELL
  standard offpage *
  page80_i188
#ISCELL
  standard offpage *
  page80_i189
#ISCELL
  standard offpage *
  page80_i19
#ISCELL
  standard offpage *
  page80_i190
#ISCELL
  standard offpage *
  page80_i191
#ISCELL
  standard offpage *
  page80_i192
#ISCELL
  standard offpage *
  page80_i193
#ISCELL
  standard offpage *
  page80_i194
#ISCELL
  standard offpage *
  page80_i195
#ISCELL
  standard offpage *
  page80_i196
#ISCELL
  standard offpage *
  page80_i197
#ISCELL
  standard offpage *
  page80_i198
#ISCELL
  standard offpage *
  page80_i199
#ISCELL
  standard offpage *
  page80_i2
#ISCELL
  standard offpage *
  page80_i20
#ISCELL
  standard offpage *
  page80_i200
#ISCELL
  standard offpage *
  page80_i201
#ISCELL
  standard offpage *
  page80_i202
#ISCELL
  standard offpage *
  page80_i203
#ISCELL
  standard offpage *
  page80_i204
#ISCELL
  standard offpage *
  page80_i206
#ISCELL
  standard offpage *
  page80_i207
#ISCELL
  standard offpage *
  page80_i209
#ISCELL
  standard offpage *
  page80_i21
#ISCELL
  standard offpage *
  page80_i210
#ISCELL
  standard offpage *
  page80_i211
#ISCELL
  standard offpage *
  page80_i212
#ISCELL
  standard offpage *
  page80_i213
#ISCELL
  standard offpage *
  page80_i214
#CELL
  pure_quanta q_res *
  page80_i215
#CELL
  pure_quanta lcmxo3lf9400c5bg484c *
  page80_i216
#CELL
  pure_quanta lcmxo3lf9400c5bg484c *
  page80_i217
#ISCELL
  standard offpage *
  page80_i218
#ISCELL
  standard offpage *
  page80_i219
#CELL
  pure_quanta q_res *
  page80_i22
#CELL
  pure_quanta q_res *
  page80_i220
#ISCELL
  standard offpage *
  page80_i221
#ISCELL
  standard offpage *
  page80_i222
#CELL
  pure_quanta q_res *
  page80_i223
#CELL
  pure_quanta q_res *
  page80_i224
#ISCELL
  standard offpage *
  page80_i225
#CELL
  pure_quanta q_res *
  page80_i226
#ISCELL
  standard offpage *
  page80_i227
#CELL
  pure_quanta q_res *
  page80_i228
#ISCELL
  standard offpage *
  page80_i229
#CELL
  pure_quanta q_res *
  page80_i231
#ISCELL
  standard offpage *
  page80_i232
#CELL
  pure_quanta q_res *
  page80_i233
#ISCELL
  standard offpage *
  page80_i234
#ISCELL
  standard offpage *
  page80_i235
#ISCELL
  standard offpage *
  page80_i239
#CELL
  pure_quanta q_res *
  page80_i240
#ISCELL
  standard offpage *
  page80_i241
#CELL
  pure_quanta q_res *
  page80_i242
#CELL
  pure_quanta q_res *
  page80_i243
#ISCELL
  standard offpage *
  page80_i244
#ISCELL
  standard offpage *
  page80_i245
#CELL
  pure_quanta q_res *
  page80_i246
#CELL
  pure_quanta q_res *
  page80_i247
#ISCELL
  standard offpage *
  page80_i248
#ISCELL
  standard offpage *
  page80_i249
#CELL
  pure_quanta q_res *
  page80_i25
#CELL
  pure_quanta q_res *
  page80_i250
#CELL
  pure_quanta q_res *
  page80_i251
#ISCELL
  standard offpage *
  page80_i252
#ISCELL
  standard offpage *
  page80_i253
#CELL
  pure_quanta q_res *
  page80_i254
#CELL
  pure_quanta q_res *
  page80_i255
#ISCELL
  standard offpage *
  page80_i256
#ISCELL
  standard offpage *
  page80_i257
#CELL
  pure_quanta q_res *
  page80_i258
#CELL
  pure_quanta q_res *
  page80_i259
#ISCELL
  standard offpage *
  page80_i260
#ISCELL
  standard offpage *
  page80_i261
#CELL
  pure_quanta q_res *
  page80_i262
#CELL
  pure_quanta q_res *
  page80_i263
#ISCELL
  standard offpage *
  page80_i264
#ISCELL
  standard offpage *
  page80_i265
#CELL
  pure_quanta q_res *
  page80_i266
#ISCELL
  standard offpage *
  page80_i267
#CELL
  pure_quanta q_res *
  page80_i268
#ISCELL
  standard offpage *
  page80_i269
#ISCELL
  standard offpage *
  page80_i270
#CELL
  pure_quanta q_res *
  page80_i271
#CELL
  pure_quanta q_res *
  page80_i272
#ISCELL
  standard offpage *
  page80_i273
#CELL
  pure_quanta q_res *
  page80_i274
#ISCELL
  standard offpage *
  page80_i275
#CELL
  pure_quanta q_res *
  page80_i276
#CELL
  pure_quanta q_res *
  page80_i278
#ISCELL
  standard offpage *
  page80_i279
#CELL
  pure_quanta q_res *
  page80_i28
#ISCELL
  standard offpage *
  page80_i280
#CELL
  pure_quanta q_res *
  page80_i281
#CELL
  pure_quanta q_res *
  page80_i284
#ISCELL
  standard offpage *
  page80_i285
#CELL
  pure_quanta q_res *
  page80_i286
#ISCELL
  standard offpage *
  page80_i287
#CELL
  pure_quanta q_res *
  page80_i288
#ISCELL
  standard offpage *
  page80_i289
#CELL
  pure_quanta q_res *
  page80_i29
#CELL
  pure_quanta q_res *
  page80_i290
#ISCELL
  standard offpage *
  page80_i291
#ISCELL
  standard offpage *
  page80_i292
#CELL
  pure_quanta q_res *
  page80_i293
#CELL
  pure_quanta q_res *
  page80_i294
#CELL
  pure_quanta q_res *
  page80_i295
#ISCELL
  standard offpage *
  page80_i296
#ISCELL
  standard offpage *
  page80_i297
#CELL
  pure_quanta q_res *
  page80_i298
#ISCELL
  pure_quanta_power universal_power *
  page80_i299
#CELL
  pure_quanta q_res *
  page80_i30
#CELL
  pure_quanta q_res *
  page80_i301
#ISCELL
  standard offpage *
  page80_i302
#CELL
  pure_quanta q_res *
  page80_i303
#ISCELL
  standard offpage *
  page80_i304
#ISCELL
  standard offpage *
  page80_i305
#ISCELL
  standard offpage *
  page80_i306
#ISCELL
  standard offpage *
  page80_i308
#ISCELL
  standard offpage *
  page80_i309
#CELL
  pure_quanta q_res *
  page80_i31
#ISCELL
  standard offpage *
  page80_i310
#CELL
  pure_quanta q_res *
  page80_i311
#ISCELL
  standard offpage *
  page80_i312
#ISCELL
  standard offpage *
  page80_i313
#ISCELL
  standard offpage *
  page80_i314
#CELL
  pure_quanta q_res *
  page80_i315
#ISCELL
  standard offpage *
  page80_i316
#ISCELL
  standard offpage *
  page80_i317
#CELL
  pure_quanta q_res *
  page80_i318
#CELL
  pure_quanta q_res *
  page80_i319
#CELL
  pure_quanta q_res *
  page80_i32
#ISCELL
  standard offpage *
  page80_i320
#ISCELL
  standard offpage *
  page80_i321
#CELL
  pure_quanta q_res *
  page80_i322
#ISCELL
  standard offpage *
  page80_i323
#CELL
  pure_quanta q_res *
  page80_i324
#ISCELL
  standard offpage *
  page80_i325
#CELL
  pure_quanta q_res *
  page80_i326
#CELL
  pure_quanta q_res *
  page80_i327
#ISCELL
  standard offpage *
  page80_i328
#ISCELL
  standard offpage *
  page80_i329
#CELL
  pure_quanta q_res *
  page80_i33
#CELL
  pure_quanta q_res *
  page80_i330
#ISCELL
  standard offpage *
  page80_i331
#CELL
  pure_quanta q_res *
  page80_i332
#ISCELL
  standard offpage *
  page80_i333
#CELL
  pure_quanta q_res *
  page80_i334
#CELL
  pure_quanta q_res *
  page80_i335
#ISCELL
  standard offpage *
  page80_i336
#ISCELL
  standard offpage *
  page80_i337
#CELL
  pure_quanta q_res *
  page80_i338
#CELL
  pure_quanta q_res *
  page80_i339
#CELL
  pure_quanta q_res *
  page80_i34
#ISCELL
  standard offpage *
  page80_i340
#ISCELL
  standard offpage *
  page80_i341
#CELL
  pure_quanta q_res *
  page80_i342
#CELL
  pure_quanta q_res *
  page80_i343
#CELL
  pure_quanta q_res *
  page80_i344
#CELL
  pure_quanta q_res *
  page80_i345
#ISCELL
  standard offpage *
  page80_i346
#ISCELL
  standard offpage *
  page80_i347
#ISCELL
  standard offpage *
  page80_i348
#ISCELL
  standard offpage *
  page80_i349
#CELL
  pure_quanta q_res *
  page80_i35
#CELL
  pure_quanta q_res *
  page80_i350
#CELL
  pure_quanta q_res *
  page80_i351
#CELL
  pure_quanta q_res *
  page80_i352
#CELL
  pure_quanta q_res *
  page80_i353
#ISCELL
  standard offpage *
  page80_i354
#ISCELL
  standard offpage *
  page80_i355
#ISCELL
  standard offpage *
  page80_i356
#ISCELL
  standard offpage *
  page80_i357
#ISCELL
  standard offpage *
  page80_i358
#ISCELL
  standard offpage *
  page80_i359
#CELL
  pure_quanta q_res *
  page80_i36
#CELL
  pure_quanta q_res *
  page80_i360
#ISCELL
  standard offpage *
  page80_i361
#CELL
  pure_quanta q_res *
  page80_i362
#ISCELL
  standard offpage *
  page80_i363
#CELL
  pure_quanta q_res *
  page80_i364
#ISCELL
  standard offpage *
  page80_i365
#CELL
  pure_quanta q_res *
  page80_i366
#ISCELL
  standard offpage *
  page80_i367
#ISCELL
  standard offpage *
  page80_i37
#ISCELL
  standard offpage *
  page80_i40
#ISCELL
  standard offpage *
  page80_i41
#ISCELL
  standard offpage *
  page80_i42
#ISCELL
  standard offpage *
  page80_i43
#ISCELL
  standard offpage *
  page80_i46
#ISCELL
  standard offpage *
  page80_i47
#ISCELL
  standard offpage *
  page80_i49
#ISCELL
  standard offpage *
  page80_i5
#ISCELL
  standard offpage *
  page80_i50
#ISCELL
  standard offpage *
  page80_i51
#ISCELL
  standard offpage *
  page80_i52
#ISCELL
  standard offpage *
  page80_i53
#ISCELL
  standard offpage *
  page80_i54
#ISCELL
  standard offpage *
  page80_i55
#ISCELL
  standard offpage *
  page80_i56
#CELL
  pure_quanta q_res *
  page80_i57
#CELL
  pure_quanta q_res *
  page80_i58
#CELL
  pure_quanta q_res *
  page80_i59
#ISCELL
  standard offpage *
  page80_i6
#CELL
  pure_quanta q_res *
  page80_i60
#CELL
  pure_quanta q_res *
  page80_i61
#CELL
  pure_quanta q_res *
  page80_i62
#CELL
  pure_quanta q_res *
  page80_i63
#CELL
  pure_quanta q_res *
  page80_i64
#CELL
  pure_quanta q_res *
  page80_i65
#CELL
  pure_quanta q_res *
  page80_i66
#CELL
  pure_quanta q_res *
  page80_i67
#CELL
  pure_quanta q_res *
  page80_i68
#ISCELL
  standard offpage *
  page80_i69
#ISCELL
  standard offpage *
  page80_i70
#ISCELL
  standard offpage *
  page80_i71
#ISCELL
  standard offpage *
  page80_i72
#ISCELL
  standard offpage *
  page80_i73
#ISCELL
  standard offpage *
  page80_i74
#ISCELL
  standard offpage *
  page80_i75
#ISCELL
  standard offpage *
  page80_i76
#ISCELL
  standard offpage *
  page80_i77
#ISCELL
  standard offpage *
  page80_i78
#ISCELL
  standard offpage *
  page80_i79
#ISCELL
  standard offpage *
  page80_i80
#ISCELL
  standard offpage *
  page80_i81
#ISCELL
  standard offpage *
  page80_i82
#ISCELL
  standard offpage *
  page80_i83
#ISCELL
  standard offpage *
  page80_i84
#ISCELL
  standard offpage *
  page80_i85
#ISCELL
  standard offpage *
  page80_i86
#ISCELL
  standard offpage *
  page80_i88
#ISCELL
  standard offpage *
  page80_i89
#ISCELL
  standard offpage *
  page80_i9
#ISCELL
  standard offpage *
  page80_i90
#ISCELL
  standard offpage *
  page80_i91
#ISCELL
  standard offpage *
  page80_i92
#ISCELL
  standard offpage *
  page80_i93
#ISCELL
  standard offpage *
  page80_i94
#ISCELL
  standard offpage *
  page80_i95
#ISCELL
  standard offpage *
  page80_i96
#ISCELL
  standard offpage *
  page80_i97
#ISCELL
  standard offpage *
  page80_i98
#ISCELL
  standard offpage *
  page80_i99
#ISCELL
  pure_quanta quanta_title_block_c *
  *
#CELL
  pure_quanta lcmxo3lf9400c5bg484c *
  page81_i1
#ISCELL
  standard offpage *
  page81_i10
#CELL
  pure_quanta q_res *
  page81_i100
#CELL
  pure_quanta q_res *
  page81_i101
#CELL
  pure_quanta q_res *
  page81_i102
#CELL
  pure_quanta q_res *
  page81_i103
#CELL
  pure_quanta q_res *
  page81_i104
#CELL
  pure_quanta q_res *
  page81_i105
#CELL
  pure_quanta q_res *
  page81_i106
#CELL
  pure_quanta q_res *
  page81_i107
#CELL
  pure_quanta q_res *
  page81_i108
#CELL
  pure_quanta q_res *
  page81_i109
#ISCELL
  standard offpage *
  page81_i11
#CELL
  pure_quanta q_res *
  page81_i110
#CELL
  pure_quanta q_res *
  page81_i111
#CELL
  pure_quanta q_res *
  page81_i112
#CELL
  pure_quanta q_res *
  page81_i113
#ISCELL
  standard offpage *
  page81_i114
#ISCELL
  standard offpage *
  page81_i115
#ISCELL
  standard offpage *
  page81_i116
#ISCELL
  standard offpage *
  page81_i117
#ISCELL
  standard offpage *
  page81_i118
#ISCELL
  standard offpage *
  page81_i119
#ISCELL
  standard offpage *
  page81_i12
#ISCELL
  standard offpage *
  page81_i120
#ISCELL
  standard offpage *
  page81_i121
#ISCELL
  standard offpage *
  page81_i122
#ISCELL
  standard offpage *
  page81_i123
#ISCELL
  standard offpage *
  page81_i124
#ISCELL
  standard offpage *
  page81_i125
#ISCELL
  standard offpage *
  page81_i129
#ISCELL
  standard offpage *
  page81_i13
#ISCELL
  standard offpage *
  page81_i130
#ISCELL
  standard offpage *
  page81_i131
#ISCELL
  standard offpage *
  page81_i132
#ISCELL
  standard offpage *
  page81_i133
#ISCELL
  standard offpage *
  page81_i134
#ISCELL
  standard offpage *
  page81_i135
#ISCELL
  standard offpage *
  page81_i136
#ISCELL
  standard offpage *
  page81_i137
#ISCELL
  standard offpage *
  page81_i138
#ISCELL
  standard offpage *
  page81_i139
#ISCELL
  standard offpage *
  page81_i14
#CELL
  pure_quanta q_res *
  page81_i140
#CELL
  pure_quanta lcmxo3lf9400c5bg484c *
  page81_i141
#ISCELL
  pure_quanta_power universal_power *
  page81_i142
#CELL
  pure_quanta lcmxo3lf9400c5bg484c *
  page81_i143
#ISCELL
  standard offpage *
  page81_i145
#CELL
  pure_quanta q_res *
  page81_i146
#ISCELL
  standard offpage *
  page81_i147
#ISCELL
  standard offpage *
  page81_i148
#ISCELL
  standard offpage *
  page81_i149
#ISCELL
  standard offpage *
  page81_i15
#ISCELL
  standard offpage *
  page81_i150
#ISCELL
  standard offpage *
  page81_i153
#ISCELL
  standard offpage *
  page81_i154
#ISCELL
  standard offpage *
  page81_i155
#ISCELL
  standard offpage *
  page81_i156
#ISCELL
  standard offpage *
  page81_i157
#ISCELL
  standard offpage *
  page81_i158
#ISCELL
  standard offpage *
  page81_i159
#ISCELL
  standard offpage *
  page81_i16
#ISCELL
  standard offpage *
  page81_i160
#CELL
  pure_quanta q_res *
  page81_i164
#CELL
  pure_quanta q_res *
  page81_i165
#ISCELL
  standard offpage *
  page81_i166
#ISCELL
  standard offpage *
  page81_i167
#CELL
  pure_quanta q_res *
  page81_i168
#CELL
  pure_quanta q_res *
  page81_i169
#ISCELL
  standard offpage *
  page81_i17
#ISCELL
  standard offpage *
  page81_i170
#ISCELL
  standard offpage *
  page81_i171
#ISCELL
  standard offpage *
  page81_i172
#ISCELL
  standard offpage *
  page81_i173
#ISCELL
  standard offpage *
  page81_i174
#ISCELL
  standard offpage *
  page81_i175
#CELL
  pure_quanta q_res *
  page81_i176
#ISCELL
  standard offpage *
  page81_i177
#CELL
  pure_quanta q_res *
  page81_i178
#ISCELL
  standard offpage *
  page81_i179
#ISCELL
  standard offpage *
  page81_i18
#CELL
  pure_quanta q_res *
  page81_i180
#ISCELL
  standard offpage *
  page81_i181
#ISCELL
  standard offpage *
  page81_i182
#ISCELL
  standard offpage *
  page81_i19
#ISCELL
  pure_quanta_power gnd *
  page81_i2
#ISCELL
  standard offpage *
  page81_i20
#ISCELL
  standard offpage *
  page81_i21
#ISCELL
  standard offpage *
  page81_i22
#ISCELL
  standard offpage *
  page81_i23
#ISCELL
  standard offpage *
  page81_i24
#ISCELL
  standard offpage *
  page81_i25
#ISCELL
  standard offpage *
  page81_i26
#ISCELL
  standard offpage *
  page81_i27
#ISCELL
  standard offpage *
  page81_i28
#ISCELL
  standard offpage *
  page81_i29
#ISCELL
  standard offpage *
  page81_i3
#ISCELL
  standard offpage *
  page81_i30
#ISCELL
  standard offpage *
  page81_i32
#ISCELL
  standard offpage *
  page81_i33
#ISCELL
  standard offpage *
  page81_i34
#ISCELL
  standard offpage *
  page81_i35
#ISCELL
  standard offpage *
  page81_i36
#ISCELL
  standard offpage *
  page81_i37
#ISCELL
  standard offpage *
  page81_i38
#ISCELL
  standard offpage *
  page81_i39
#ISCELL
  standard offpage *
  page81_i4
#ISCELL
  standard offpage *
  page81_i40
#ISCELL
  standard offpage *
  page81_i41
#ISCELL
  standard offpage *
  page81_i42
#ISCELL
  standard offpage *
  page81_i43
#CELL
  pure_quanta q_res *
  page81_i44
#CELL
  pure_quanta q_res *
  page81_i45
#CELL
  pure_quanta q_res *
  page81_i46
#CELL
  pure_quanta q_res *
  page81_i47
#CELL
  pure_quanta q_res *
  page81_i48
#CELL
  pure_quanta q_res *
  page81_i49
#ISCELL
  standard offpage *
  page81_i5
#CELL
  pure_quanta q_res *
  page81_i50
#CELL
  pure_quanta q_res *
  page81_i51
#CELL
  pure_quanta q_res *
  page81_i52
#CELL
  pure_quanta q_res *
  page81_i53
#CELL
  pure_quanta q_res *
  page81_i54
#CELL
  pure_quanta q_res *
  page81_i55
#CELL
  pure_quanta q_res *
  page81_i56
#CELL
  pure_quanta q_res *
  page81_i57
#CELL
  pure_quanta q_res *
  page81_i58
#CELL
  pure_quanta q_res *
  page81_i59
#CELL
  pure_quanta q_res *
  page81_i60
#CELL
  pure_quanta q_res *
  page81_i61
#CELL
  pure_quanta q_res *
  page81_i62
#CELL
  pure_quanta q_res *
  page81_i63
#CELL
  pure_quanta q_res *
  page81_i64
#CELL
  pure_quanta q_res *
  page81_i65
#CELL
  pure_quanta q_res *
  page81_i66
#CELL
  pure_quanta q_res *
  page81_i67
#CELL
  pure_quanta q_res *
  page81_i68
#CELL
  pure_quanta q_res *
  page81_i69
#CELL
  pure_quanta q_res *
  page81_i70
#CELL
  pure_quanta q_res *
  page81_i71
#CELL
  pure_quanta q_res *
  page81_i72
#CELL
  pure_quanta q_res *
  page81_i73
#CELL
  pure_quanta q_res *
  page81_i74
#CELL
  pure_quanta q_res *
  page81_i75
#ISCELL
  standard offpage *
  page81_i76
#CELL
  pure_quanta q_res *
  page81_i77
#ISCELL
  pure_quanta_power universal_power *
  page81_i78
#ISCELL
  pure_quanta_power vcc_core *
  page81_i79
#CELL
  pure_quanta q_res *
  page81_i80
#CELL
  pure_quanta q_res *
  page81_i81
#CELL
  pure_quanta q_res *
  page81_i82
#CELL
  pure_quanta q_res *
  page81_i83
#CELL
  pure_quanta q_res *
  page81_i84
#CELL
  pure_quanta q_res *
  page81_i85
#CELL
  pure_quanta q_res *
  page81_i86
#ISCELL
  standard offpage *
  page81_i87
#ISCELL
  standard offpage *
  page81_i88
#ISCELL
  standard offpage *
  page81_i89
#ISCELL
  standard offpage *
  page81_i9
#ISCELL
  standard offpage *
  page81_i90
#ISCELL
  standard offpage *
  page81_i91
#ISCELL
  standard offpage *
  page81_i92
#ISCELL
  standard offpage *
  page81_i93
#ISCELL
  standard offpage *
  page81_i94
#ISCELL
  standard offpage *
  page81_i95
#ISCELL
  standard offpage *
  page81_i96
#ISCELL
  pure_quanta_power universal_power *
  page81_i97
#ISCELL
  pure_quanta_power vcc_core *
  page81_i98
#CELL
  pure_quanta q_res *
  page81_i99
#ISCELL
  mstr_misc dns *
  *
#ISCELL
  pure_quanta quanta_title_block_c *
  *
#ISCELL
  pure_quanta_power cad_note *
  *
#ISCELL
  standard offpage *
  page82_i10
#ISCELL
  standard offpage *
  page82_i100
#ISCELL
  standard offpage *
  page82_i101
#CELL
  pure_quanta q_cap *
  page82_i102
#CELL
  pure_quanta q_cap *
  page82_i103
#CELL
  pure_quanta q_cap *
  page82_i104
#CELL
  pure_quanta q_cap *
  page82_i105
#CELL
  pure_quanta q_cap *
  page82_i106
#CELL
  pure_quanta q_cap *
  page82_i107
#CELL
  pure_quanta q_cap *
  page82_i108
#CELL
  pure_quanta q_cap *
  page82_i109
#ISCELL
  standard offpage *
  page82_i11
#CELL
  pure_quanta q_cap *
  page82_i110
#CELL
  pure_quanta q_cap *
  page82_i111
#CELL
  pure_quanta q_cap *
  page82_i112
#CELL
  pure_quanta q_cap *
  page82_i113
#CELL
  pure_quanta q_cap *
  page82_i114
#ISCELL
  pure_quanta_power gnd *
  page82_i115
#ISCELL
  pure_quanta_power vcc_core *
  page82_i116
#ISCELL
  pure_quanta_power gnd *
  page82_i117
#CELL
  pure_quanta q_res *
  page82_i118
#ISCELL
  mstr_symbols gnd *
  page82_i119
#ISCELL
  standard offpage *
  page82_i12
#CELL
  pure_quanta q_res *
  page82_i120
#ISCELL
  pure_quanta_power gnd *
  page82_i121
#ISCELL
  pure_quanta_power gnd *
  page82_i122
#ISCELL
  mstr_symbols gnd *
  page82_i123
#CELL
  pure_quanta q_res *
  page82_i124
#CELL
  pure_quanta q_res *
  page82_i125
#CELL
  pure_quanta q_res *
  page82_i126
#ISCELL
  mstr_symbols gnd *
  page82_i127
#CELL
  pure_quanta q_res *
  page82_i128
#ISCELL
  standard offpage *
  page82_i129
#ISCELL
  standard offpage *
  page82_i13
#ISCELL
  standard offpage *
  page82_i130
#ISCELL
  standard offpage *
  page82_i131
#ISCELL
  standard offpage *
  page82_i132
#ISCELL
  standard offpage *
  page82_i133
#ISCELL
  standard offpage *
  page82_i134
#CELL
  pure_quanta q_cap *
  page82_i135
#CELL
  pure_quanta q_res *
  page82_i137
#ISCELL
  standard offpage *
  page82_i139
#ISCELL
  standard offpage *
  page82_i14
#ISCELL
  pure_quanta_power universal_gnd *
  page82_i140
#CELL
  pure_quanta q_res *
  page82_i141
#ISCELL
  standard offpage *
  page82_i142
#CELL
  pure_quanta q_res *
  page82_i143
#ISCELL
  pure_quanta_power gnd *
  page82_i144
#ISCELL
  standard offpage *
  page82_i145
#CELL
  pure_quanta q_res *
  page82_i146
#ISCELL
  standard offpage *
  page82_i147
#ISCELL
  standard offpage *
  page82_i148
#ISCELL
  standard offpage *
  page82_i15
#ISCELL
  pure_quanta_power gnd *
  page82_i150
#CELL
  pure_quanta q_res *
  page82_i151
#CELL
  pure_quanta q_res *
  page82_i152
#ISCELL
  standard offpage *
  page82_i153
#CELL
  pure_quanta q_res *
  page82_i154
#ISCELL
  standard offpage *
  page82_i155
#CELL
  pure_quanta q_res *
  page82_i156
#CELL
  pure_quanta q_res *
  page82_i157
#ISCELL
  standard offpage *
  page82_i158
#ISCELL
  standard offpage *
  page82_i159
#ISCELL
  standard offpage *
  page82_i16
#ISCELL
  standard offpage *
  page82_i160
#ISCELL
  standard offpage *
  page82_i161
#CELL
  pure_quanta q_res *
  page82_i162
#CELL
  pure_quanta q_res *
  page82_i163
#ISCELL
  pure_quanta_power gnd *
  page82_i164
#ISCELL
  pure_quanta_power gnd *
  page82_i165
#CELL
  pure_quanta q_res *
  page82_i166
#ISCELL
  standard offpage *
  page82_i167
#ISCELL
  pure_quanta_power gnd *
  page82_i169
#ISCELL
  standard offpage *
  page82_i17
#CELL
  pure_quanta q_res *
  page82_i170
#CELL
  pure_quanta q_res *
  page82_i171
#ISCELL
  standard offpage *
  page82_i18
#ISCELL
  standard offpage *
  page82_i19
#ISCELL
  standard offpage *
  page82_i20
#ISCELL
  standard offpage *
  page82_i21
#ISCELL
  standard offpage *
  page82_i22
#CELL
  pure_quanta q_res *
  page82_i33
#CELL
  pure_quanta q_res *
  page82_i35
#CELL
  pure_quanta q_res *
  page82_i36
#ISCELL
  pure_quanta_power universal_power *
  page82_i37
#CELL
  pure_quanta q_res *
  page82_i38
#CELL
  pure_quanta q_res *
  page82_i39
#ISCELL
  standard offpage *
  page82_i4
#CELL
  pure_quanta q_res *
  page82_i40
#CELL
  pure_quanta q_res *
  page82_i41
#ISCELL
  standard offpage *
  page82_i5
#CELL
  pure_quanta q_res *
  page82_i53
#CELL
  pure_quanta q_res *
  page82_i54
#CELL
  pure_quanta q_res *
  page82_i56
#CELL
  pure_quanta q_res *
  page82_i57
#CELL
  pure_quanta q_res *
  page82_i58
#CELL
  pure_quanta q_res *
  page82_i59
#ISCELL
  standard offpage *
  page82_i6
#CELL
  pure_quanta q_res *
  page82_i60
#CELL
  pure_quanta q_res *
  page82_i61
#CELL
  pure_quanta q_res *
  page82_i62
#ISCELL
  pure_quanta_power vcc_core *
  page82_i63
#CELL
  pure_quanta q_res *
  page82_i64
#ISCELL
  standard offpage *
  page82_i65
#ISCELL
  standard offpage *
  page82_i66
#ISCELL
  standard offpage *
  page82_i67
#ISCELL
  standard offpage *
  page82_i68
#ISCELL
  standard offpage *
  page82_i69
#ISCELL
  standard offpage *
  page82_i7
#ISCELL
  pure_quanta_power vcc_core *
  page82_i70
#CELL
  pure_quanta q_res *
  page82_i72
#CELL
  pure_quanta q_res *
  page82_i73
#CELL
  pure_quanta q_res *
  page82_i74
#ISCELL
  pure_quanta_power vcc_core *
  page82_i75
#CELL
  pure_quanta q_res *
  page82_i76
#CELL
  pure_quanta q_res *
  page82_i77
#ISCELL
  pure_quanta_power vcc_core *
  page82_i78
#CELL
  pure_quanta q_cap *
  page82_i79
#ISCELL
  standard offpage *
  page82_i8
#CELL
  pure_quanta q_cap *
  page82_i80
#CELL
  pure_quanta q_cap *
  page82_i81
#CELL
  pure_quanta q_cap *
  page82_i82
#CELL
  pure_quanta q_cap *
  page82_i83
#CELL
  pure_quanta q_cap *
  page82_i84
#CELL
  pure_quanta q_cap *
  page82_i85
#CELL
  pure_quanta q_cap *
  page82_i86
#CELL
  pure_quanta q_cap *
  page82_i87
#ISCELL
  pure_quanta_power gnd *
  page82_i88
#ISCELL
  pure_quanta_power vcc_core *
  page82_i89
#ISCELL
  standard offpage *
  page82_i9
#ISCELL
  pure_quanta_power gnd *
  page82_i90
#ISCELL
  pure_quanta_power gnd *
  page82_i91
#ISCELL
  pure_quanta_power gnd *
  page82_i92
#CELL
  pure_quanta q_res *
  page82_i93
#CELL
  pure_quanta q_res *
  page82_i94
#CELL
  pure_quanta q_res *
  page82_i95
#ISCELL
  pure_quanta_power gnd *
  page82_i96
#CELL
  pure_quanta q_res *
  page82_i97
#ISCELL
  standard offpage *
  page82_i98
#ISCELL
  standard offpage *
  page82_i99
#ISCELL
  mstr_misc dns *
  *
#ISCELL
  pure_quanta quanta_title_block_c *
  *
#ISCELL
  pure_quanta_power universal_gnd *
  page83_i100
#ISCELL
  pure_quanta_power universal_gnd *
  page83_i101
#ISCELL
  pure_quanta_power universal_gnd *
  page83_i102
#ISCELL
  pure_quanta_power universal_gnd *
  page83_i103
#ISCELL
  pure_quanta_power universal_gnd *
  page83_i104
#ISCELL
  pure_quanta_power universal_gnd *
  page83_i105
#ISCELL
  pure_quanta_power universal_gnd *
  page83_i106
#ISCELL
  pure_quanta_power universal_gnd *
  page83_i107
#ISCELL
  pure_quanta_power universal_gnd *
  page83_i108
#ISCELL
  pure_quanta_power universal_gnd *
  page83_i109
#ISCELL
  pure_quanta_power universal_gnd *
  page83_i110
#ISCELL
  pure_quanta_power universal_gnd *
  page83_i111
#ISCELL
  pure_quanta_power universal_gnd *
  page83_i112
#ISCELL
  pure_quanta_power universal_gnd *
  page83_i113
#ISCELL
  pure_quanta_power universal_gnd *
  page83_i114
#CELL
  pure_quanta q_res *
  page83_i115
#CELL
  pure_quanta q_res *
  page83_i116
#CELL
  pure_quanta q_res *
  page83_i117
#CELL
  pure_quanta q_res *
  page83_i118
#CELL
  pure_quanta q_res *
  page83_i119
#CELL
  pure_quanta q_res *
  page83_i120
#CELL
  pure_quanta q_res *
  page83_i121
#CELL
  pure_quanta q_res *
  page83_i122
#CELL
  pure_quanta q_res *
  page83_i131
#CELL
  pure_quanta q_res *
  page83_i132
#CELL
  pure_quanta q_res *
  page83_i133
#CELL
  pure_quanta q_res *
  page83_i134
#CELL
  pure_quanta q_res *
  page83_i135
#CELL
  pure_quanta q_res *
  page83_i136
#CELL
  pure_quanta q_res *
  page83_i137
#CELL
  pure_quanta q_res *
  page83_i138
#CELL
  pure_quanta q_res *
  page83_i139
#CELL
  pure_quanta q_res *
  page83_i140
#CELL
  pure_quanta q_res *
  page83_i141
#CELL
  pure_quanta q_res *
  page83_i142
#ISCELL
  standard offpage *
  page83_i2
#CELL
  pure_quanta q_res *
  page83_i22
#ISCELL
  pure_quanta_power universal_gnd *
  page83_i23
#CELL
  pure_quanta q_cap *
  page83_i24
#ISCELL
  pure_quanta_power universal_power *
  page83_i25
#CELL
  pure_quanta sn74lvc1g07dbvr *
  page83_i26
#CELL
  pure_quanta q_res *
  page83_i27
#ISCELL
  standard offpage *
  page83_i28
#CELL
  pure_quanta q_res *
  page83_i29
#ISCELL
  pure_quanta_power universal_power *
  page83_i30
#CELL
  pure_quanta q_res *
  page83_i36
#CELL
  pure_quanta q_res *
  page83_i39
#ISCELL
  pure_quanta_power universal_power *
  page83_i40
#CELL
  pure_quanta q_res *
  page83_i46
#ISCELL
  pure_quanta_power universal_power *
  page83_i48
#CELL
  pure_quanta q_res *
  page83_i50
#CELL
  pure_quanta q_res *
  page83_i52
#CELL
  pure_quanta q_res *
  page83_i54
#CELL
  pure_quanta q_res *
  page83_i55
#CELL
  pure_quanta q_res *
  page83_i56
#ISCELL
  standard offpage *
  page83_i57
#ISCELL
  standard offpage *
  page83_i58
#ISCELL
  standard offpage *
  page83_i59
#ISCELL
  standard offpage *
  page83_i60
#ISCELL
  standard offpage *
  page83_i61
#CELL
  pure_quanta q_res *
  page83_i64
#CELL
  pure_quanta q_res *
  page83_i65
#ISCELL
  standard offpage *
  page83_i66
#ISCELL
  standard offpage *
  page83_i67
#ISCELL
  standard offpage *
  page83_i68
#ISCELL
  standard offpage *
  page83_i69
#ISCELL
  standard offpage *
  page83_i70
#CELL
  pure_quanta q_res *
  page83_i71
#CELL
  pure_quanta q_res *
  page83_i72
#ISCELL
  pure_quanta_power universal_power *
  page83_i82
#ISCELL
  pure_quanta_power universal_gnd *
  page83_i9
#ISCELL
  standard offpage *
  page83_i92
#ISCELL
  standard offpage *
  page83_i93
#ISCELL
  standard offpage *
  page83_i94
#ISCELL
  standard offpage *
  page83_i95
#ISCELL
  standard offpage *
  page83_i96
#ISCELL
  pure_quanta_power universal_power *
  page83_i97
#ISCELL
  standard offpage *
  page83_i98
#ISCELL
  pure_quanta_power universal_gnd *
  page83_i99
#ISCELL
  mstr_misc dns *
  *
#ISCELL
  pure_quanta quanta_title_block_c *
  *
#ISCELL
  standard offpage *
  page84_i1
#ISCELL
  standard offpage *
  page84_i100
#CELL
  pure_quanta q_cap *
  page84_i101
#ISCELL
  pure_quanta_power universal_gnd *
  page84_i102
#CELL
  pure_quanta q_res *
  page84_i103
#CELL
  pure_quanta q_res *
  page84_i104
#ISCELL
  pure_quanta_power universal_gnd *
  page84_i105
#CELL
  pure_quanta q_res *
  page84_i106
#ISCELL
  standard offpage *
  page84_i107
#ISCELL
  pure_quanta_power universal_gnd *
  page84_i110
#CELL
  pure_quanta mosfet_nch_dual *
  page84_i111
#CELL
  pure_quanta q_res *
  page84_i112
#ISCELL
  pure_quanta_power universal_gnd *
  page84_i113
#CELL
  pure_quanta q_res *
  page84_i114
#ISCELL
  pure_quanta_power universal_gnd *
  page84_i115
#CELL
  pure_quanta q_cap *
  page84_i116
#ISCELL
  standard offpage *
  page84_i117
#CELL
  pure_quanta q_res *
  page84_i118
#ISCELL
  pure_quanta_power universal_power *
  page84_i119
#ISCELL
  pure_quanta_power universal_power *
  page84_i120
#CELL
  pure_quanta mosfet_nch_dual *
  page84_i121
#ISCELL
  standard offpage *
  page84_i25
#ISCELL
  standard offpage *
  page84_i26
#CELL
  pure_quanta q_res *
  page84_i27
#ISCELL
  mstr_standard offpage *
  page84_i28
#ISCELL
  standard offpage *
  page84_i29
#ISCELL
  pure_quanta_power universal_power *
  page84_i30
#ISCELL
  standard offpage *
  page84_i31
#ISCELL
  standard offpage *
  page84_i32
#ISCELL
  standard offpage *
  page84_i33
#ISCELL
  standard offpage *
  page84_i34
#CELL
  pure_quanta q_res *
  page84_i35
#CELL
  pure_quanta q_res *
  page84_i36
#CELL
  pure_quanta q_res *
  page84_i37
#CELL
  pure_quanta q_res *
  page84_i38
#ISCELL
  pure_quanta_power universal_gnd *
  page84_i39
#ISCELL
  pure_quanta_power universal_gnd *
  page84_i40
#CELL
  pure_quanta conn8_hbb1081l200d8h *
  page84_i41
#CELL
  pure_quanta q_cap *
  page84_i42
#ISCELL
  pure_quanta_power universal_power *
  page84_i43
#ISCELL
  standard offpage *
  page84_i44
#CELL
  pure_quanta q_res *
  page84_i45
#CELL
  pure_quanta q_res *
  page84_i46
#ISCELL
  pure_quanta_power universal_gnd *
  page84_i47
#CELL
  pure_quanta mosfet_dual_6p *
  page84_i48
#CELL
  pure_quanta q_res *
  page84_i5
#ISCELL
  pure_quanta_power universal_gnd *
  page84_i51
#ISCELL
  standard offpage *
  page84_i52
#CELL
  pure_quanta q_res *
  page84_i53
#ISCELL
  standard offpage *
  page84_i54
#ISCELL
  standard offpage *
  page84_i55
#ISCELL
  standard offpage *
  page84_i56
#CELL
  pure_quanta q_res *
  page84_i57
#ISCELL
  standard offpage *
  page84_i58
#ISCELL
  standard offpage *
  page84_i59
#CELL
  pure_quanta q_res *
  page84_i6
#ISCELL
  standard offpage *
  page84_i60
#CELL
  pure_quanta q_res *
  page84_i61
#ISCELL
  standard offpage *
  page84_i62
#CELL
  pure_quanta q_res *
  page84_i63
#ISCELL
  pure_quanta_power universal_power *
  page84_i64
#CELL
  pure_quanta mosfet_nch_dual *
  page84_i65
#ISCELL
  pure_quanta_power universal_gnd *
  page84_i66
#CELL
  pure_quanta q_res *
  page84_i67
#ISCELL
  pure_quanta_power universal_power *
  page84_i68
#ISCELL
  pure_quanta_power universal_gnd *
  page84_i69
#ISCELL
  pure_quanta_power vcc_core *
  page84_i7
#CELL
  pure_quanta q_res *
  page84_i70
#ISCELL
  pure_quanta_power universal_power *
  page84_i71
#CELL
  pure_quanta mosfet_nch_dual *
  page84_i73
#ISCELL
  standard offpage *
  page84_i74
#CELL
  pure_quanta q_res *
  page84_i75
#ISCELL
  standard offpage *
  page84_i76
#CELL
  pure_quanta q_res *
  page84_i77
#ISCELL
  pure_quanta_power universal_gnd *
  page84_i78
#ISCELL
  standard offpage *
  page84_i8
#ISCELL
  standard offpage *
  page84_i81
#CELL
  pure_quanta q_res *
  page84_i82
#ISCELL
  standard offpage *
  page84_i83
#CELL
  pure_quanta q_res *
  page84_i84
#ISCELL
  standard offpage *
  page84_i85
#CELL
  pure_quanta q_cap *
  page84_i88
#ISCELL
  pure_quanta_power universal_gnd *
  page84_i89
#ISCELL
  standard offpage *
  page84_i90
#CELL
  pure_quanta q_res *
  page84_i91
#ISCELL
  standard offpage *
  page84_i92
#ISCELL
  standard offpage *
  page84_i93
#CELL
  pure_quanta q_res *
  page84_i94
#ISCELL
  standard offpage *
  page84_i95
#CELL
  pure_quanta q_led *
  page84_i96
#CELL
  pure_quanta q_led *
  page84_i97
#ISCELL
  mstr_misc dns *
  *
#ISCELL
  pure_quanta quanta_title_block_c *
  *
#ISCELL
  mstr_symbols gnd *
  page85_i115
#ISCELL
  mstr_symbols gnd *
  page85_i116
#ISCELL
  mstr_standard tap *
  page85_i210
#ISCELL
  mstr_standard tap *
  page85_i211
#ISCELL
  mstr_standard tap *
  page85_i212
#ISCELL
  mstr_standard tap *
  page85_i213
#ISCELL
  mstr_standard tap *
  page85_i214
#ISCELL
  mstr_standard tap *
  page85_i215
#ISCELL
  mstr_standard tap *
  page85_i216
#ISCELL
  mstr_standard tap *
  page85_i217
#ISCELL
  mstr_standard offpage *
  page85_i218
#ISCELL
  mstr_standard tap *
  page85_i227
#ISCELL
  mstr_standard tap *
  page85_i228
#ISCELL
  mstr_standard tap *
  page85_i229
#ISCELL
  mstr_standard tap *
  page85_i230
#ISCELL
  mstr_standard tap *
  page85_i231
#ISCELL
  mstr_standard tap *
  page85_i232
#ISCELL
  mstr_standard tap *
  page85_i233
#ISCELL
  mstr_standard tap *
  page85_i235
#ISCELL
  mstr_standard tap *
  page85_i236
#ISCELL
  mstr_standard tap *
  page85_i237
#ISCELL
  mstr_standard tap *
  page85_i238
#ISCELL
  mstr_standard tap *
  page85_i239
#ISCELL
  mstr_standard tap *
  page85_i240
#ISCELL
  mstr_standard tap *
  page85_i241
#ISCELL
  mstr_standard offpage *
  page85_i243
#ISCELL
  mstr_standard offpage *
  page85_i252
#ISCELL
  mstr_standard offpage *
  page85_i253
#ISCELL
  mstr_standard offpage *
  page85_i256
#ISCELL
  mstr_standard offpage *
  page85_i257
#ISCELL
  mstr_standard offpage *
  page85_i258
#ISCELL
  mstr_standard offpage *
  page85_i259
#ISCELL
  mstr_standard offpage *
  page85_i260
#ISCELL
  mstr_standard offpage *
  page85_i261
#ISCELL
  mstr_standard offpage *
  page85_i265
#ISCELL
  mstr_standard offpage *
  page85_i266
#ISCELL
  mstr_standard offpage *
  page85_i366
#ISCELL
  mstr_standard tap *
  page85_i367
#ISCELL
  mstr_standard tap *
  page85_i368
#ISCELL
  mstr_standard tap *
  page85_i369
#ISCELL
  mstr_standard tap *
  page85_i370
#ISCELL
  mstr_standard tap *
  page85_i371
#ISCELL
  mstr_standard tap *
  page85_i372
#ISCELL
  mstr_standard tap *
  page85_i373
#ISCELL
  mstr_standard tap *
  page85_i374
#ISCELL
  mstr_standard offpage *
  page85_i376
#ISCELL
  mstr_standard offpage *
  page85_i378
#ISCELL
  mstr_standard tap *
  page85_i383
#ISCELL
  mstr_standard tap *
  page85_i384
#ISCELL
  mstr_standard tap *
  page85_i385
#ISCELL
  mstr_standard tap *
  page85_i386
#ISCELL
  mstr_standard tap *
  page85_i387
#ISCELL
  mstr_standard tap *
  page85_i388
#ISCELL
  mstr_standard tap *
  page85_i389
#ISCELL
  mstr_standard tap *
  page85_i390
#ISCELL
  mstr_standard tap *
  page85_i391
#ISCELL
  mstr_standard tap *
  page85_i392
#ISCELL
  mstr_standard tap *
  page85_i393
#ISCELL
  mstr_standard tap *
  page85_i394
#ISCELL
  mstr_standard tap *
  page85_i395
#ISCELL
  mstr_standard tap *
  page85_i396
#ISCELL
  mstr_standard tap *
  page85_i397
#ISCELL
  mstr_standard tap *
  page85_i398
#ISCELL
  mstr_standard tap *
  page85_i399
#ISCELL
  mstr_standard tap *
  page85_i400
#ISCELL
  mstr_standard tap *
  page85_i401
#ISCELL
  mstr_standard tap *
  page85_i402
#ISCELL
  mstr_standard tap *
  page85_i403
#ISCELL
  mstr_standard tap *
  page85_i404
#ISCELL
  mstr_standard tap *
  page85_i405
#ISCELL
  mstr_standard tap *
  page85_i406
#ISCELL
  mstr_standard tap *
  page85_i407
#ISCELL
  mstr_standard tap *
  page85_i408
#ISCELL
  mstr_standard tap *
  page85_i409
#ISCELL
  mstr_standard tap *
  page85_i410
#ISCELL
  mstr_standard tap *
  page85_i411
#ISCELL
  mstr_standard tap *
  page85_i412
#ISCELL
  mstr_standard tap *
  page85_i413
#ISCELL
  mstr_standard tap *
  page85_i414
#ISCELL
  mstr_standard tap *
  page85_i415
#ISCELL
  mstr_standard tap *
  page85_i416
#ISCELL
  mstr_standard tap *
  page85_i417
#ISCELL
  mstr_standard tap *
  page85_i418
#ISCELL
  mstr_standard tap *
  page85_i419
#ISCELL
  mstr_standard tap *
  page85_i420
#ISCELL
  mstr_standard tap *
  page85_i421
#ISCELL
  mstr_standard tap *
  page85_i422
#ISCELL
  mstr_standard tap *
  page85_i423
#ISCELL
  mstr_standard tap *
  page85_i424
#ISCELL
  mstr_standard tap *
  page85_i425
#ISCELL
  mstr_standard tap *
  page85_i426
#ISCELL
  mstr_standard tap *
  page85_i427
#ISCELL
  mstr_standard tap *
  page85_i428
#ISCELL
  mstr_standard tap *
  page85_i429
#ISCELL
  mstr_standard tap *
  page85_i430
#ISCELL
  mstr_standard tap *
  page85_i431
#ISCELL
  mstr_standard tap *
  page85_i432
#ISCELL
  mstr_standard tap *
  page85_i433
#ISCELL
  mstr_standard tap *
  page85_i434
#ISCELL
  mstr_standard tap *
  page85_i435
#ISCELL
  mstr_standard offpage *
  page85_i436
#ISCELL
  mstr_standard tap *
  page85_i437
#ISCELL
  mstr_standard tap *
  page85_i438
#ISCELL
  mstr_standard tap *
  page85_i439
#ISCELL
  mstr_standard tap *
  page85_i440
#ISCELL
  mstr_standard tap *
  page85_i441
#ISCELL
  mstr_standard tap *
  page85_i442
#ISCELL
  mstr_standard tap *
  page85_i443
#ISCELL
  mstr_standard tap *
  page85_i444
#ISCELL
  mstr_standard tap *
  page85_i445
#ISCELL
  mstr_standard tap *
  page85_i446
#ISCELL
  mstr_standard tap *
  page85_i447
#ISCELL
  mstr_standard offpage *
  page85_i448
#ISCELL
  mstr_standard tap *
  page85_i449
#ISCELL
  mstr_standard tap *
  page85_i450
#ISCELL
  mstr_standard tap *
  page85_i451
#ISCELL
  mstr_standard tap *
  page85_i452
#ISCELL
  mstr_standard tap *
  page85_i453
#ISCELL
  mstr_standard tap *
  page85_i454
#ISCELL
  mstr_standard tap *
  page85_i455
#ISCELL
  mstr_standard tap *
  page85_i456
#ISCELL
  mstr_standard tap *
  page85_i457
#ISCELL
  mstr_standard tap *
  page85_i458
#ISCELL
  mstr_standard tap *
  page85_i459
#ISCELL
  mstr_standard tap *
  page85_i460
#ISCELL
  mstr_standard tap *
  page85_i461
#ISCELL
  mstr_standard tap *
  page85_i462
#ISCELL
  mstr_standard tap *
  page85_i463
#ISCELL
  mstr_standard tap *
  page85_i464
#ISCELL
  mstr_standard tap *
  page85_i465
#ISCELL
  mstr_standard tap *
  page85_i466
#ISCELL
  mstr_standard tap *
  page85_i467
#ISCELL
  mstr_standard tap *
  page85_i468
#ISCELL
  mstr_standard tap *
  page85_i469
#ISCELL
  mstr_standard tap *
  page85_i470
#ISCELL
  mstr_standard tap *
  page85_i471
#ISCELL
  mstr_standard tap *
  page85_i472
#ISCELL
  mstr_standard tap *
  page85_i473
#ISCELL
  mstr_standard tap *
  page85_i474
#ISCELL
  mstr_standard tap *
  page85_i475
#ISCELL
  mstr_standard tap *
  page85_i476
#ISCELL
  mstr_standard tap *
  page85_i477
#ISCELL
  mstr_standard offpage *
  page85_i478
#ISCELL
  mstr_standard offpage *
  page85_i479
#ISCELL
  mstr_standard tap *
  page85_i480
#ISCELL
  mstr_standard tap *
  page85_i481
#ISCELL
  mstr_standard tap *
  page85_i482
#ISCELL
  mstr_standard tap *
  page85_i483
#ISCELL
  mstr_standard tap *
  page85_i484
#ISCELL
  mstr_standard tap *
  page85_i485
#ISCELL
  mstr_standard tap *
  page85_i486
#ISCELL
  mstr_standard tap *
  page85_i487
#ISCELL
  mstr_standard tap *
  page85_i488
#ISCELL
  mstr_standard tap *
  page85_i489
#ISCELL
  mstr_standard tap *
  page85_i490
#ISCELL
  mstr_standard offpage *
  page85_i491
#ISCELL
  mstr_standard offpage *
  page85_i492
#ISCELL
  mstr_symbols vcc_core *
  page85_i493
#ISCELL
  mstr_standard offpage *
  page85_i495
#ISCELL
  mstr_standard offpage *
  page85_i496
#ISCELL
  mstr_standard offpage *
  page85_i497
#ISCELL
  mstr_symbols gnd *
  page85_i498
#CELL
  pure_quanta q_res *
  page85_i499
#ISCELL
  mstr_standard offpage *
  page85_i509
#ISCELL
  mstr_standard offpage *
  page85_i518
#CELL
  pure_quanta q_cap *
  page85_i519
#ISCELL
  mstr_symbols gnd *
  page85_i522
#CELL
  pure_quanta q_cap *
  page85_i523
#ISCELL
  mstr_symbols gnd *
  page85_i524
#CELL
  pure_quanta q_res *
  page85_i525
#CELL
  pure_quanta q_res *
  page85_i526
#ISCELL
  mstr_symbols vcc_core *
  page85_i527
#CELL
  pure_quanta q_res *
  page85_i528
#ISCELL
  mstr_symbols vcc_core *
  page85_i529
#CELL
  pure_quanta q_cap *
  page85_i534
#ISCELL
  pure_quanta_power universal_power *
  page85_i535
#CELL
  pure_quanta sconn288_ddr506112002kq *
  page85_i536
#CELL
  pure_quanta sconn288_ddr506112002kq *
  page85_i537
#CELL
  pure_quanta sconn288_ddr506112002kq *
  page85_i538
#CELL
  pure_quanta q_res *
  page85_i539
#CELL
  pure_quanta q_res *
  page85_i540
#ISCELL
  mstr_symbols vcc_core *
  page85_i541
#ISCELL
  mstr_standard offpage *
  page85_i542
#CELL
  pure_quanta q_res *
  page85_i544
#CELL
  pure_quanta q_res *
  page85_i545
#CELL
  pure_quanta q_res *
  page85_i547
#ISCELL
  mstr_symbols vcc_core *
  page85_i548
#CELL
  pure_quanta schottky_12 *
  page85_i549
#ISCELL
  mstr_symbols vcc_core *
  page85_i550
#ISCELL
  mstr_standard offpage *
  page85_i551
#ISCELL
  mstr_standard offpage *
  page85_i552
#ISCELL
  mstr_standard offpage *
  page85_i553
#CELL
  pure_quanta q_res *
  page85_i554
#ISCELL
  mstr_misc dns *
  *
#ISCELL
  pure_quanta quanta_title_block_c *
  *
#ISCELL
  mstr_symbols gnd *
  page86_i150
#ISCELL
  mstr_symbols gnd *
  page86_i152
#ISCELL
  mstr_standard offpage *
  page86_i167
#ISCELL
  mstr_standard offpage *
  page86_i168
#ISCELL
  mstr_standard offpage *
  page86_i174
#ISCELL
  mstr_standard offpage *
  page86_i176
#ISCELL
  mstr_symbols vcc_core *
  page86_i177
#ISCELL
  mstr_standard offpage *
  page86_i178
#ISCELL
  mstr_standard offpage *
  page86_i179
#ISCELL
  mstr_standard offpage *
  page86_i180
#ISCELL
  mstr_standard offpage *
  page86_i181
#ISCELL
  mstr_standard offpage *
  page86_i182
#ISCELL
  mstr_standard offpage *
  page86_i183
#ISCELL
  mstr_standard offpage *
  page86_i184
#ISCELL
  mstr_standard offpage *
  page86_i185
#ISCELL
  mstr_standard offpage *
  page86_i186
#ISCELL
  mstr_standard tap *
  page86_i187
#ISCELL
  mstr_standard tap *
  page86_i188
#ISCELL
  mstr_standard tap *
  page86_i189
#ISCELL
  mstr_standard tap *
  page86_i190
#ISCELL
  mstr_standard tap *
  page86_i191
#ISCELL
  mstr_standard tap *
  page86_i192
#ISCELL
  mstr_standard tap *
  page86_i193
#ISCELL
  mstr_standard tap *
  page86_i194
#ISCELL
  mstr_standard tap *
  page86_i195
#ISCELL
  mstr_standard tap *
  page86_i196
#ISCELL
  mstr_standard tap *
  page86_i197
#ISCELL
  mstr_standard tap *
  page86_i198
#ISCELL
  mstr_standard tap *
  page86_i199
#ISCELL
  mstr_standard tap *
  page86_i200
#ISCELL
  mstr_standard tap *
  page86_i201
#ISCELL
  mstr_standard tap *
  page86_i202
#ISCELL
  mstr_standard tap *
  page86_i203
#ISCELL
  mstr_standard tap *
  page86_i204
#ISCELL
  mstr_standard tap *
  page86_i205
#ISCELL
  mstr_standard tap *
  page86_i206
#ISCELL
  mstr_standard tap *
  page86_i207
#ISCELL
  mstr_standard tap *
  page86_i208
#ISCELL
  mstr_standard tap *
  page86_i209
#ISCELL
  mstr_standard tap *
  page86_i210
#ISCELL
  mstr_standard tap *
  page86_i211
#ISCELL
  mstr_standard tap *
  page86_i212
#ISCELL
  mstr_standard tap *
  page86_i213
#ISCELL
  mstr_standard tap *
  page86_i214
#ISCELL
  mstr_standard tap *
  page86_i215
#ISCELL
  mstr_standard tap *
  page86_i216
#ISCELL
  mstr_standard tap *
  page86_i217
#ISCELL
  mstr_standard tap *
  page86_i218
#ISCELL
  mstr_standard tap *
  page86_i219
#ISCELL
  mstr_standard tap *
  page86_i220
#ISCELL
  mstr_standard tap *
  page86_i221
#ISCELL
  mstr_standard tap *
  page86_i222
#ISCELL
  mstr_standard tap *
  page86_i223
#ISCELL
  mstr_standard tap *
  page86_i224
#ISCELL
  mstr_standard tap *
  page86_i225
#ISCELL
  mstr_standard tap *
  page86_i226
#ISCELL
  mstr_standard tap *
  page86_i227
#ISCELL
  mstr_standard tap *
  page86_i228
#ISCELL
  mstr_standard tap *
  page86_i229
#ISCELL
  mstr_standard tap *
  page86_i230
#ISCELL
  mstr_standard tap *
  page86_i231
#ISCELL
  mstr_standard tap *
  page86_i232
#ISCELL
  mstr_standard tap *
  page86_i233
#ISCELL
  mstr_standard tap *
  page86_i234
#ISCELL
  mstr_standard tap *
  page86_i235
#ISCELL
  mstr_standard tap *
  page86_i236
#ISCELL
  mstr_standard tap *
  page86_i237
#ISCELL
  mstr_standard tap *
  page86_i238
#ISCELL
  mstr_standard tap *
  page86_i239
#ISCELL
  mstr_standard tap *
  page86_i240
#ISCELL
  mstr_standard tap *
  page86_i241
#ISCELL
  mstr_standard tap *
  page86_i242
#ISCELL
  mstr_standard tap *
  page86_i243
#ISCELL
  mstr_standard tap *
  page86_i244
#ISCELL
  mstr_standard tap *
  page86_i245
#ISCELL
  mstr_standard tap *
  page86_i246
#ISCELL
  mstr_standard tap *
  page86_i247
#ISCELL
  mstr_standard tap *
  page86_i248
#ISCELL
  mstr_standard tap *
  page86_i249
#ISCELL
  mstr_standard tap *
  page86_i250
#ISCELL
  mstr_standard tap *
  page86_i251
#ISCELL
  mstr_standard tap *
  page86_i252
#ISCELL
  mstr_standard tap *
  page86_i253
#ISCELL
  mstr_standard tap *
  page86_i254
#ISCELL
  mstr_standard tap *
  page86_i255
#ISCELL
  mstr_standard tap *
  page86_i256
#ISCELL
  mstr_standard tap *
  page86_i257
#ISCELL
  mstr_standard tap *
  page86_i258
#ISCELL
  mstr_standard tap *
  page86_i259
#ISCELL
  mstr_standard offpage *
  page86_i260
#ISCELL
  mstr_standard offpage *
  page86_i261
#ISCELL
  mstr_standard offpage *
  page86_i262
#ISCELL
  mstr_standard tap *
  page86_i263
#ISCELL
  mstr_standard tap *
  page86_i264
#ISCELL
  mstr_standard tap *
  page86_i265
#ISCELL
  mstr_standard tap *
  page86_i266
#ISCELL
  mstr_standard tap *
  page86_i267
#ISCELL
  mstr_standard tap *
  page86_i268
#ISCELL
  mstr_standard tap *
  page86_i269
#ISCELL
  mstr_standard tap *
  page86_i270
#ISCELL
  mstr_standard tap *
  page86_i271
#ISCELL
  mstr_standard tap *
  page86_i272
#ISCELL
  mstr_standard tap *
  page86_i273
#ISCELL
  mstr_standard tap *
  page86_i274
#ISCELL
  mstr_standard tap *
  page86_i275
#ISCELL
  mstr_standard tap *
  page86_i276
#ISCELL
  mstr_standard tap *
  page86_i277
#ISCELL
  mstr_standard tap *
  page86_i278
#ISCELL
  mstr_standard tap *
  page86_i279
#ISCELL
  mstr_standard tap *
  page86_i280
#ISCELL
  mstr_standard tap *
  page86_i281
#ISCELL
  mstr_standard tap *
  page86_i282
#ISCELL
  mstr_standard tap *
  page86_i283
#ISCELL
  mstr_standard offpage *
  page86_i284
#ISCELL
  mstr_standard tap *
  page86_i285
#ISCELL
  mstr_standard tap *
  page86_i286
#ISCELL
  mstr_standard tap *
  page86_i287
#ISCELL
  mstr_standard tap *
  page86_i288
#ISCELL
  mstr_standard tap *
  page86_i289
#ISCELL
  mstr_standard tap *
  page86_i290
#ISCELL
  mstr_standard tap *
  page86_i291
#ISCELL
  mstr_standard tap *
  page86_i292
#ISCELL
  mstr_standard tap *
  page86_i293
#ISCELL
  mstr_standard tap *
  page86_i294
#ISCELL
  mstr_standard tap *
  page86_i295
#ISCELL
  mstr_standard tap *
  page86_i296
#ISCELL
  mstr_standard tap *
  page86_i297
#ISCELL
  mstr_standard tap *
  page86_i298
#ISCELL
  mstr_standard tap *
  page86_i299
#ISCELL
  mstr_standard tap *
  page86_i300
#ISCELL
  mstr_standard tap *
  page86_i301
#ISCELL
  mstr_standard tap *
  page86_i302
#ISCELL
  mstr_standard tap *
  page86_i303
#ISCELL
  mstr_standard tap *
  page86_i304
#ISCELL
  mstr_standard tap *
  page86_i305
#ISCELL
  mstr_standard tap *
  page86_i306
#ISCELL
  mstr_standard tap *
  page86_i307
#ISCELL
  mstr_standard tap *
  page86_i308
#ISCELL
  mstr_standard tap *
  page86_i309
#ISCELL
  mstr_standard tap *
  page86_i310
#ISCELL
  mstr_standard tap *
  page86_i311
#ISCELL
  mstr_standard tap *
  page86_i312
#ISCELL
  mstr_standard tap *
  page86_i313
#ISCELL
  mstr_standard offpage *
  page86_i314
#ISCELL
  mstr_standard offpage *
  page86_i315
#ISCELL
  mstr_standard tap *
  page86_i316
#ISCELL
  mstr_standard tap *
  page86_i317
#ISCELL
  mstr_standard tap *
  page86_i318
#ISCELL
  mstr_standard tap *
  page86_i319
#ISCELL
  mstr_standard tap *
  page86_i320
#ISCELL
  mstr_standard tap *
  page86_i321
#ISCELL
  mstr_standard tap *
  page86_i322
#ISCELL
  mstr_standard tap *
  page86_i323
#ISCELL
  mstr_standard tap *
  page86_i324
#ISCELL
  mstr_standard tap *
  page86_i325
#ISCELL
  mstr_standard tap *
  page86_i326
#ISCELL
  mstr_standard offpage *
  page86_i327
#ISCELL
  mstr_standard offpage *
  page86_i328
#ISCELL
  mstr_symbols gnd *
  page86_i332
#ISCELL
  mstr_standard offpage *
  page86_i333
#ISCELL
  mstr_standard offpage *
  page86_i334
#CELL
  pure_quanta q_res *
  page86_i349
#CELL
  pure_quanta sconn288_ddr506112002kq *
  page86_i350
#CELL
  pure_quanta sconn288_ddr506112002kq *
  page86_i352
#ISCELL
  mstr_standard offpage *
  page86_i353
#ISCELL
  mstr_standard offpage *
  page86_i354
#ISCELL
  mstr_symbols gnd *
  page86_i361
#CELL
  pure_quanta q_cap *
  page86_i362
#ISCELL
  mstr_standard offpage *
  page86_i363
#CELL
  pure_quanta q_res *
  page86_i364
#CELL
  pure_quanta q_res *
  page86_i365
#ISCELL
  mstr_symbols vcc_core *
  page86_i366
#CELL
  pure_quanta sconn288_ddr506112002kq *
  page86_i367
#ISCELL
  pure_quanta_power gnd *
  page86_i368
#CELL
  pure_quanta q_cap *
  page86_i369
#CELL
  pure_quanta q_cap *
  page86_i370
#ISCELL
  pure_quanta_power universal_power *
  page86_i371
#CELL
  pure_quanta q_res *
  page86_i372
#CELL
  pure_quanta q_res *
  page86_i373
#ISCELL
  mstr_standard offpage *
  page86_i374
#ISCELL
  mstr_misc dns *
  *
#ISCELL
  pure_quanta quanta_title_block_c *
  *
#ISCELL
  mstr_symbols gnd *
  page87_i150
#ISCELL
  mstr_symbols gnd *
  page87_i152
#ISCELL
  mstr_standard offpage *
  page87_i167
#ISCELL
  mstr_standard offpage *
  page87_i168
#ISCELL
  mstr_standard offpage *
  page87_i174
#ISCELL
  mstr_standard offpage *
  page87_i176
#ISCELL
  mstr_symbols vcc_core *
  page87_i177
#ISCELL
  mstr_standard offpage *
  page87_i178
#ISCELL
  mstr_standard offpage *
  page87_i179
#ISCELL
  mstr_standard offpage *
  page87_i180
#ISCELL
  mstr_standard offpage *
  page87_i181
#ISCELL
  mstr_standard offpage *
  page87_i182
#ISCELL
  mstr_standard offpage *
  page87_i183
#ISCELL
  mstr_standard offpage *
  page87_i184
#ISCELL
  mstr_standard offpage *
  page87_i185
#ISCELL
  mstr_standard offpage *
  page87_i186
#ISCELL
  mstr_standard tap *
  page87_i187
#ISCELL
  mstr_standard tap *
  page87_i188
#ISCELL
  mstr_standard tap *
  page87_i189
#ISCELL
  mstr_standard tap *
  page87_i190
#ISCELL
  mstr_standard tap *
  page87_i191
#ISCELL
  mstr_standard tap *
  page87_i192
#ISCELL
  mstr_standard tap *
  page87_i193
#ISCELL
  mstr_standard tap *
  page87_i194
#ISCELL
  mstr_standard tap *
  page87_i195
#ISCELL
  mstr_standard tap *
  page87_i196
#ISCELL
  mstr_standard tap *
  page87_i197
#ISCELL
  mstr_standard tap *
  page87_i198
#ISCELL
  mstr_standard tap *
  page87_i199
#ISCELL
  mstr_standard tap *
  page87_i200
#ISCELL
  mstr_standard tap *
  page87_i201
#ISCELL
  mstr_standard tap *
  page87_i202
#ISCELL
  mstr_standard tap *
  page87_i203
#ISCELL
  mstr_standard tap *
  page87_i204
#ISCELL
  mstr_standard tap *
  page87_i205
#ISCELL
  mstr_standard tap *
  page87_i206
#ISCELL
  mstr_standard tap *
  page87_i207
#ISCELL
  mstr_standard tap *
  page87_i208
#ISCELL
  mstr_standard tap *
  page87_i209
#ISCELL
  mstr_standard tap *
  page87_i210
#ISCELL
  mstr_standard tap *
  page87_i211
#ISCELL
  mstr_standard tap *
  page87_i212
#ISCELL
  mstr_standard tap *
  page87_i213
#ISCELL
  mstr_standard tap *
  page87_i214
#ISCELL
  mstr_standard tap *
  page87_i215
#ISCELL
  mstr_standard tap *
  page87_i216
#ISCELL
  mstr_standard tap *
  page87_i217
#ISCELL
  mstr_standard tap *
  page87_i218
#ISCELL
  mstr_standard tap *
  page87_i219
#ISCELL
  mstr_standard tap *
  page87_i220
#ISCELL
  mstr_standard tap *
  page87_i221
#ISCELL
  mstr_standard tap *
  page87_i222
#ISCELL
  mstr_standard tap *
  page87_i223
#ISCELL
  mstr_standard tap *
  page87_i224
#ISCELL
  mstr_standard tap *
  page87_i225
#ISCELL
  mstr_standard tap *
  page87_i226
#ISCELL
  mstr_standard tap *
  page87_i227
#ISCELL
  mstr_standard tap *
  page87_i228
#ISCELL
  mstr_standard tap *
  page87_i229
#ISCELL
  mstr_standard tap *
  page87_i230
#ISCELL
  mstr_standard tap *
  page87_i231
#ISCELL
  mstr_standard tap *
  page87_i232
#ISCELL
  mstr_standard tap *
  page87_i233
#ISCELL
  mstr_standard tap *
  page87_i234
#ISCELL
  mstr_standard tap *
  page87_i235
#ISCELL
  mstr_standard tap *
  page87_i236
#ISCELL
  mstr_standard tap *
  page87_i237
#ISCELL
  mstr_standard tap *
  page87_i238
#ISCELL
  mstr_standard tap *
  page87_i239
#ISCELL
  mstr_standard tap *
  page87_i240
#ISCELL
  mstr_standard tap *
  page87_i241
#ISCELL
  mstr_standard tap *
  page87_i242
#ISCELL
  mstr_standard tap *
  page87_i243
#ISCELL
  mstr_standard tap *
  page87_i244
#ISCELL
  mstr_standard tap *
  page87_i245
#ISCELL
  mstr_standard tap *
  page87_i246
#ISCELL
  mstr_standard tap *
  page87_i247
#ISCELL
  mstr_standard tap *
  page87_i248
#ISCELL
  mstr_standard tap *
  page87_i249
#ISCELL
  mstr_standard tap *
  page87_i250
#ISCELL
  mstr_standard tap *
  page87_i251
#ISCELL
  mstr_standard tap *
  page87_i252
#ISCELL
  mstr_standard tap *
  page87_i253
#ISCELL
  mstr_standard tap *
  page87_i254
#ISCELL
  mstr_standard tap *
  page87_i255
#ISCELL
  mstr_standard tap *
  page87_i256
#ISCELL
  mstr_standard tap *
  page87_i257
#ISCELL
  mstr_standard tap *
  page87_i258
#ISCELL
  mstr_standard tap *
  page87_i259
#ISCELL
  mstr_standard offpage *
  page87_i260
#ISCELL
  mstr_standard offpage *
  page87_i261
#ISCELL
  mstr_standard offpage *
  page87_i262
#ISCELL
  mstr_standard tap *
  page87_i263
#ISCELL
  mstr_standard tap *
  page87_i264
#ISCELL
  mstr_standard tap *
  page87_i265
#ISCELL
  mstr_standard tap *
  page87_i266
#ISCELL
  mstr_standard tap *
  page87_i267
#ISCELL
  mstr_standard tap *
  page87_i268
#ISCELL
  mstr_standard tap *
  page87_i269
#ISCELL
  mstr_standard tap *
  page87_i270
#ISCELL
  mstr_standard tap *
  page87_i271
#ISCELL
  mstr_standard tap *
  page87_i272
#ISCELL
  mstr_standard tap *
  page87_i273
#ISCELL
  mstr_standard tap *
  page87_i274
#ISCELL
  mstr_standard tap *
  page87_i275
#ISCELL
  mstr_standard tap *
  page87_i276
#ISCELL
  mstr_standard tap *
  page87_i277
#ISCELL
  mstr_standard tap *
  page87_i278
#ISCELL
  mstr_standard tap *
  page87_i279
#ISCELL
  mstr_standard tap *
  page87_i280
#ISCELL
  mstr_standard tap *
  page87_i281
#ISCELL
  mstr_standard tap *
  page87_i282
#ISCELL
  mstr_standard tap *
  page87_i283
#ISCELL
  mstr_standard offpage *
  page87_i284
#ISCELL
  mstr_symbols gnd *
  page87_i332
#ISCELL
  mstr_standard offpage *
  page87_i333
#ISCELL
  mstr_standard offpage *
  page87_i334
#CELL
  pure_quanta q_res *
  page87_i349
#CELL
  pure_quanta sconn288_ddr506112002kq *
  page87_i350
#CELL
  pure_quanta sconn288_ddr506112002kq *
  page87_i352
#ISCELL
  mstr_standard offpage *
  page87_i353
#ISCELL
  mstr_symbols gnd *
  page87_i361
#CELL
  pure_quanta q_cap *
  page87_i362
#ISCELL
  mstr_standard offpage *
  page87_i363
#CELL
  pure_quanta q_res *
  page87_i364
#CELL
  pure_quanta q_res *
  page87_i365
#ISCELL
  mstr_symbols vcc_core *
  page87_i366
#ISCELL
  mstr_standard offpage *
  page87_i367
#ISCELL
  mstr_standard offpage *
  page87_i368
#ISCELL
  mstr_standard offpage *
  page87_i369
#ISCELL
  mstr_standard offpage *
  page87_i370
#ISCELL
  mstr_standard tap *
  page87_i371
#ISCELL
  mstr_standard tap *
  page87_i372
#ISCELL
  mstr_standard tap *
  page87_i373
#ISCELL
  mstr_standard tap *
  page87_i374
#ISCELL
  mstr_standard tap *
  page87_i375
#ISCELL
  mstr_standard tap *
  page87_i376
#ISCELL
  mstr_standard tap *
  page87_i377
#ISCELL
  mstr_standard tap *
  page87_i378
#ISCELL
  mstr_standard tap *
  page87_i379
#ISCELL
  mstr_standard tap *
  page87_i380
#ISCELL
  mstr_standard tap *
  page87_i381
#ISCELL
  mstr_standard tap *
  page87_i382
#ISCELL
  mstr_standard tap *
  page87_i383
#ISCELL
  mstr_standard tap *
  page87_i384
#ISCELL
  mstr_standard tap *
  page87_i385
#ISCELL
  mstr_standard tap *
  page87_i386
#ISCELL
  mstr_standard tap *
  page87_i387
#ISCELL
  mstr_standard tap *
  page87_i388
#ISCELL
  mstr_standard tap *
  page87_i389
#ISCELL
  mstr_standard tap *
  page87_i390
#ISCELL
  mstr_standard tap *
  page87_i391
#ISCELL
  mstr_standard tap *
  page87_i392
#ISCELL
  mstr_standard tap *
  page87_i393
#ISCELL
  mstr_standard tap *
  page87_i394
#ISCELL
  mstr_standard tap *
  page87_i395
#ISCELL
  mstr_standard tap *
  page87_i396
#ISCELL
  mstr_standard tap *
  page87_i397
#ISCELL
  mstr_standard tap *
  page87_i398
#ISCELL
  mstr_standard tap *
  page87_i399
#ISCELL
  mstr_standard tap *
  page87_i400
#ISCELL
  mstr_standard tap *
  page87_i401
#ISCELL
  mstr_standard tap *
  page87_i402
#ISCELL
  mstr_standard tap *
  page87_i403
#ISCELL
  mstr_standard tap *
  page87_i404
#ISCELL
  mstr_standard tap *
  page87_i405
#ISCELL
  mstr_standard tap *
  page87_i406
#ISCELL
  mstr_standard tap *
  page87_i407
#ISCELL
  mstr_standard tap *
  page87_i408
#ISCELL
  mstr_standard tap *
  page87_i409
#ISCELL
  mstr_standard tap *
  page87_i410
#CELL
  pure_quanta sconn288_ddr506112002kq *
  page87_i411
#ISCELL
  pure_quanta_power gnd *
  page87_i412
#CELL
  pure_quanta q_cap *
  page87_i413
#CELL
  pure_quanta q_cap *
  page87_i414
#ISCELL
  pure_quanta_power universal_power *
  page87_i415
#ISCELL
  mstr_standard offpage *
  page87_i416
#CELL
  pure_quanta q_res *
  page87_i417
#CELL
  pure_quanta q_res *
  page87_i418
#ISCELL
  mstr_standard offpage *
  page87_i419
#ISCELL
  mstr_misc dns *
  *
#ISCELL
  pure_quanta quanta_title_block_c *
  *
#ISCELL
  mstr_symbols gnd *
  page88_i150
#ISCELL
  mstr_symbols gnd *
  page88_i152
#ISCELL
  mstr_standard offpage *
  page88_i167
#ISCELL
  mstr_standard offpage *
  page88_i171
#ISCELL
  mstr_standard offpage *
  page88_i174
#ISCELL
  mstr_symbols vcc_core *
  page88_i175
#ISCELL
  mstr_standard offpage *
  page88_i177
#ISCELL
  mstr_standard offpage *
  page88_i178
#ISCELL
  mstr_standard offpage *
  page88_i179
#ISCELL
  mstr_standard offpage *
  page88_i180
#ISCELL
  mstr_standard offpage *
  page88_i181
#ISCELL
  mstr_standard offpage *
  page88_i182
#ISCELL
  mstr_standard offpage *
  page88_i183
#ISCELL
  mstr_standard offpage *
  page88_i184
#ISCELL
  mstr_standard offpage *
  page88_i185
#ISCELL
  mstr_standard offpage *
  page88_i186
#ISCELL
  mstr_standard offpage *
  page88_i187
#ISCELL
  mstr_standard offpage *
  page88_i188
#ISCELL
  mstr_standard tap *
  page88_i189
#ISCELL
  mstr_standard tap *
  page88_i190
#ISCELL
  mstr_standard tap *
  page88_i191
#ISCELL
  mstr_standard tap *
  page88_i192
#ISCELL
  mstr_standard tap *
  page88_i193
#ISCELL
  mstr_standard tap *
  page88_i194
#ISCELL
  mstr_standard tap *
  page88_i195
#ISCELL
  mstr_standard tap *
  page88_i196
#ISCELL
  mstr_standard tap *
  page88_i197
#ISCELL
  mstr_standard tap *
  page88_i198
#ISCELL
  mstr_standard tap *
  page88_i199
#ISCELL
  mstr_standard tap *
  page88_i200
#ISCELL
  mstr_standard tap *
  page88_i201
#ISCELL
  mstr_standard tap *
  page88_i202
#ISCELL
  mstr_standard tap *
  page88_i203
#ISCELL
  mstr_standard tap *
  page88_i204
#ISCELL
  mstr_standard tap *
  page88_i205
#ISCELL
  mstr_standard tap *
  page88_i206
#ISCELL
  mstr_standard tap *
  page88_i207
#ISCELL
  mstr_standard tap *
  page88_i208
#ISCELL
  mstr_standard tap *
  page88_i209
#ISCELL
  mstr_standard tap *
  page88_i210
#ISCELL
  mstr_standard tap *
  page88_i211
#ISCELL
  mstr_standard tap *
  page88_i212
#ISCELL
  mstr_standard tap *
  page88_i213
#ISCELL
  mstr_standard tap *
  page88_i214
#ISCELL
  mstr_standard tap *
  page88_i215
#ISCELL
  mstr_standard tap *
  page88_i216
#ISCELL
  mstr_standard tap *
  page88_i217
#ISCELL
  mstr_standard tap *
  page88_i218
#ISCELL
  mstr_standard tap *
  page88_i219
#ISCELL
  mstr_standard tap *
  page88_i220
#ISCELL
  mstr_standard tap *
  page88_i221
#ISCELL
  mstr_standard tap *
  page88_i222
#ISCELL
  mstr_standard tap *
  page88_i223
#ISCELL
  mstr_standard tap *
  page88_i224
#ISCELL
  mstr_standard tap *
  page88_i225
#ISCELL
  mstr_standard tap *
  page88_i226
#ISCELL
  mstr_standard tap *
  page88_i227
#ISCELL
  mstr_standard tap *
  page88_i228
#ISCELL
  mstr_standard tap *
  page88_i229
#ISCELL
  mstr_standard tap *
  page88_i230
#ISCELL
  mstr_standard tap *
  page88_i231
#ISCELL
  mstr_standard tap *
  page88_i232
#ISCELL
  mstr_standard tap *
  page88_i233
#ISCELL
  mstr_standard tap *
  page88_i234
#ISCELL
  mstr_standard tap *
  page88_i235
#ISCELL
  mstr_standard tap *
  page88_i236
#ISCELL
  mstr_standard tap *
  page88_i237
#ISCELL
  mstr_standard tap *
  page88_i238
#ISCELL
  mstr_standard tap *
  page88_i239
#ISCELL
  mstr_standard tap *
  page88_i240
#ISCELL
  mstr_standard tap *
  page88_i241
#ISCELL
  mstr_standard tap *
  page88_i242
#ISCELL
  mstr_standard tap *
  page88_i243
#ISCELL
  mstr_standard tap *
  page88_i244
#ISCELL
  mstr_standard tap *
  page88_i245
#ISCELL
  mstr_standard tap *
  page88_i246
#ISCELL
  mstr_standard tap *
  page88_i247
#ISCELL
  mstr_standard tap *
  page88_i248
#ISCELL
  mstr_standard tap *
  page88_i249
#ISCELL
  mstr_standard tap *
  page88_i250
#ISCELL
  mstr_standard tap *
  page88_i251
#ISCELL
  mstr_standard tap *
  page88_i252
#ISCELL
  mstr_standard tap *
  page88_i253
#ISCELL
  mstr_standard tap *
  page88_i254
#ISCELL
  mstr_standard tap *
  page88_i255
#ISCELL
  mstr_standard tap *
  page88_i256
#ISCELL
  mstr_standard tap *
  page88_i257
#ISCELL
  mstr_standard tap *
  page88_i258
#ISCELL
  mstr_standard tap *
  page88_i259
#ISCELL
  mstr_standard tap *
  page88_i260
#ISCELL
  mstr_standard tap *
  page88_i261
#ISCELL
  mstr_standard tap *
  page88_i262
#ISCELL
  mstr_standard tap *
  page88_i263
#ISCELL
  mstr_standard tap *
  page88_i264
#ISCELL
  mstr_standard tap *
  page88_i265
#ISCELL
  mstr_standard tap *
  page88_i266
#ISCELL
  mstr_standard tap *
  page88_i267
#ISCELL
  mstr_standard tap *
  page88_i268
#ISCELL
  mstr_standard tap *
  page88_i269
#ISCELL
  mstr_standard tap *
  page88_i270
#ISCELL
  mstr_standard tap *
  page88_i271
#ISCELL
  mstr_standard tap *
  page88_i272
#ISCELL
  mstr_standard tap *
  page88_i273
#ISCELL
  mstr_standard tap *
  page88_i274
#ISCELL
  mstr_standard tap *
  page88_i275
#ISCELL
  mstr_standard tap *
  page88_i276
#ISCELL
  mstr_standard tap *
  page88_i277
#ISCELL
  mstr_standard tap *
  page88_i278
#ISCELL
  mstr_standard tap *
  page88_i279
#ISCELL
  mstr_standard tap *
  page88_i280
#ISCELL
  mstr_standard tap *
  page88_i281
#ISCELL
  mstr_standard tap *
  page88_i282
#ISCELL
  mstr_standard offpage *
  page88_i283
#ISCELL
  mstr_standard offpage *
  page88_i290
#ISCELL
  mstr_symbols gnd *
  page88_i332
#ISCELL
  mstr_standard offpage *
  page88_i333
#ISCELL
  mstr_standard offpage *
  page88_i334
#CELL
  pure_quanta q_res *
  page88_i349
#CELL
  pure_quanta sconn288_ddr506112002kq *
  page88_i350
#CELL
  pure_quanta sconn288_ddr506112002kq *
  page88_i352
#ISCELL
  mstr_standard offpage *
  page88_i353
#ISCELL
  mstr_symbols gnd *
  page88_i361
#CELL
  pure_quanta q_cap *
  page88_i362
#CELL
  pure_quanta q_res *
  page88_i367
#ISCELL
  mstr_symbols vcc_core *
  page88_i368
#CELL
  pure_quanta q_res *
  page88_i369
#ISCELL
  mstr_standard offpage *
  page88_i370
#ISCELL
  mstr_standard offpage *
  page88_i371
#ISCELL
  mstr_standard offpage *
  page88_i372
#ISCELL
  mstr_standard offpage *
  page88_i373
#ISCELL
  mstr_standard offpage *
  page88_i374
#ISCELL
  mstr_standard tap *
  page88_i375
#ISCELL
  mstr_standard tap *
  page88_i376
#ISCELL
  mstr_standard tap *
  page88_i377
#ISCELL
  mstr_standard tap *
  page88_i378
#ISCELL
  mstr_standard tap *
  page88_i379
#ISCELL
  mstr_standard tap *
  page88_i380
#ISCELL
  mstr_standard tap *
  page88_i381
#ISCELL
  mstr_standard tap *
  page88_i382
#ISCELL
  mstr_standard tap *
  page88_i383
#ISCELL
  mstr_standard tap *
  page88_i384
#ISCELL
  mstr_standard tap *
  page88_i385
#ISCELL
  mstr_standard tap *
  page88_i386
#ISCELL
  mstr_standard tap *
  page88_i387
#ISCELL
  mstr_standard tap *
  page88_i388
#ISCELL
  mstr_standard tap *
  page88_i389
#ISCELL
  mstr_standard tap *
  page88_i390
#ISCELL
  mstr_standard tap *
  page88_i391
#ISCELL
  mstr_standard tap *
  page88_i392
#ISCELL
  mstr_standard tap *
  page88_i393
#ISCELL
  mstr_standard tap *
  page88_i394
#ISCELL
  mstr_standard tap *
  page88_i395
#ISCELL
  mstr_standard tap *
  page88_i396
#ISCELL
  mstr_standard tap *
  page88_i397
#ISCELL
  mstr_standard tap *
  page88_i398
#ISCELL
  mstr_standard tap *
  page88_i399
#ISCELL
  mstr_standard tap *
  page88_i400
#ISCELL
  mstr_standard tap *
  page88_i401
#ISCELL
  mstr_standard tap *
  page88_i402
#ISCELL
  mstr_standard tap *
  page88_i403
#ISCELL
  mstr_standard tap *
  page88_i404
#ISCELL
  mstr_standard tap *
  page88_i405
#ISCELL
  mstr_standard tap *
  page88_i406
#ISCELL
  mstr_standard tap *
  page88_i407
#ISCELL
  mstr_standard tap *
  page88_i408
#ISCELL
  mstr_standard tap *
  page88_i409
#ISCELL
  mstr_standard tap *
  page88_i410
#ISCELL
  mstr_standard tap *
  page88_i411
#ISCELL
  mstr_standard tap *
  page88_i412
#ISCELL
  mstr_standard tap *
  page88_i413
#ISCELL
  mstr_standard tap *
  page88_i414
#CELL
  pure_quanta sconn288_ddr506112002kq *
  page88_i415
#ISCELL
  pure_quanta_power gnd *
  page88_i416
#CELL
  pure_quanta q_cap *
  page88_i417
#CELL
  pure_quanta q_cap *
  page88_i418
#ISCELL
  pure_quanta_power universal_power *
  page88_i419
#ISCELL
  mstr_standard offpage *
  page88_i420
#CELL
  pure_quanta q_res *
  page88_i421
#CELL
  pure_quanta q_res *
  page88_i422
#ISCELL
  mstr_standard offpage *
  page88_i423
#ISCELL
  mstr_misc dns *
  *
#ISCELL
  pure_quanta quanta_title_block_c *
  *
#ISCELL
  mstr_symbols gnd *
  page89_i150
#ISCELL
  mstr_symbols gnd *
  page89_i152
#ISCELL
  mstr_standard offpage *
  page89_i167
#ISCELL
  mstr_standard offpage *
  page89_i168
#ISCELL
  mstr_standard offpage *
  page89_i174
#ISCELL
  mstr_standard offpage *
  page89_i176
#ISCELL
  mstr_symbols vcc_core *
  page89_i177
#ISCELL
  mstr_standard offpage *
  page89_i178
#ISCELL
  mstr_standard offpage *
  page89_i179
#ISCELL
  mstr_standard offpage *
  page89_i180
#ISCELL
  mstr_standard offpage *
  page89_i181
#ISCELL
  mstr_standard offpage *
  page89_i182
#ISCELL
  mstr_standard offpage *
  page89_i183
#ISCELL
  mstr_standard offpage *
  page89_i184
#ISCELL
  mstr_standard offpage *
  page89_i185
#ISCELL
  mstr_standard offpage *
  page89_i186
#ISCELL
  mstr_standard tap *
  page89_i187
#ISCELL
  mstr_standard tap *
  page89_i188
#ISCELL
  mstr_standard tap *
  page89_i189
#ISCELL
  mstr_standard tap *
  page89_i190
#ISCELL
  mstr_standard tap *
  page89_i191
#ISCELL
  mstr_standard tap *
  page89_i192
#ISCELL
  mstr_standard tap *
  page89_i193
#ISCELL
  mstr_standard tap *
  page89_i194
#ISCELL
  mstr_standard tap *
  page89_i195
#ISCELL
  mstr_standard tap *
  page89_i196
#ISCELL
  mstr_standard tap *
  page89_i197
#ISCELL
  mstr_standard tap *
  page89_i198
#ISCELL
  mstr_standard tap *
  page89_i199
#ISCELL
  mstr_standard tap *
  page89_i200
#ISCELL
  mstr_standard tap *
  page89_i201
#ISCELL
  mstr_standard tap *
  page89_i202
#ISCELL
  mstr_standard tap *
  page89_i203
#ISCELL
  mstr_standard tap *
  page89_i204
#ISCELL
  mstr_standard tap *
  page89_i205
#ISCELL
  mstr_standard tap *
  page89_i206
#ISCELL
  mstr_standard tap *
  page89_i207
#ISCELL
  mstr_standard tap *
  page89_i208
#ISCELL
  mstr_standard tap *
  page89_i209
#ISCELL
  mstr_standard tap *
  page89_i210
#ISCELL
  mstr_standard tap *
  page89_i211
#ISCELL
  mstr_standard tap *
  page89_i212
#ISCELL
  mstr_standard tap *
  page89_i213
#ISCELL
  mstr_standard tap *
  page89_i214
#ISCELL
  mstr_standard tap *
  page89_i215
#ISCELL
  mstr_standard tap *
  page89_i216
#ISCELL
  mstr_standard tap *
  page89_i217
#ISCELL
  mstr_standard tap *
  page89_i218
#ISCELL
  mstr_standard tap *
  page89_i219
#ISCELL
  mstr_standard tap *
  page89_i220
#ISCELL
  mstr_standard tap *
  page89_i221
#ISCELL
  mstr_standard tap *
  page89_i222
#ISCELL
  mstr_standard tap *
  page89_i223
#ISCELL
  mstr_standard tap *
  page89_i224
#ISCELL
  mstr_standard tap *
  page89_i225
#ISCELL
  mstr_standard tap *
  page89_i226
#ISCELL
  mstr_standard tap *
  page89_i227
#ISCELL
  mstr_standard tap *
  page89_i228
#ISCELL
  mstr_standard tap *
  page89_i229
#ISCELL
  mstr_standard tap *
  page89_i230
#ISCELL
  mstr_standard tap *
  page89_i231
#ISCELL
  mstr_standard tap *
  page89_i232
#ISCELL
  mstr_standard tap *
  page89_i233
#ISCELL
  mstr_standard tap *
  page89_i234
#ISCELL
  mstr_standard tap *
  page89_i235
#ISCELL
  mstr_standard tap *
  page89_i236
#ISCELL
  mstr_standard tap *
  page89_i237
#ISCELL
  mstr_standard tap *
  page89_i238
#ISCELL
  mstr_standard tap *
  page89_i239
#ISCELL
  mstr_standard tap *
  page89_i240
#ISCELL
  mstr_standard tap *
  page89_i241
#ISCELL
  mstr_standard tap *
  page89_i242
#ISCELL
  mstr_standard tap *
  page89_i243
#ISCELL
  mstr_standard tap *
  page89_i244
#ISCELL
  mstr_standard tap *
  page89_i245
#ISCELL
  mstr_standard tap *
  page89_i246
#ISCELL
  mstr_standard tap *
  page89_i247
#ISCELL
  mstr_standard tap *
  page89_i248
#ISCELL
  mstr_standard tap *
  page89_i249
#ISCELL
  mstr_standard tap *
  page89_i250
#ISCELL
  mstr_standard tap *
  page89_i251
#ISCELL
  mstr_standard tap *
  page89_i252
#ISCELL
  mstr_standard tap *
  page89_i253
#ISCELL
  mstr_standard tap *
  page89_i254
#ISCELL
  mstr_standard tap *
  page89_i255
#ISCELL
  mstr_standard tap *
  page89_i256
#ISCELL
  mstr_standard tap *
  page89_i257
#ISCELL
  mstr_standard tap *
  page89_i258
#ISCELL
  mstr_standard tap *
  page89_i259
#ISCELL
  mstr_standard offpage *
  page89_i260
#ISCELL
  mstr_standard offpage *
  page89_i261
#ISCELL
  mstr_standard offpage *
  page89_i262
#ISCELL
  mstr_standard tap *
  page89_i263
#ISCELL
  mstr_standard tap *
  page89_i264
#ISCELL
  mstr_standard tap *
  page89_i265
#ISCELL
  mstr_standard tap *
  page89_i266
#ISCELL
  mstr_standard tap *
  page89_i267
#ISCELL
  mstr_standard tap *
  page89_i268
#ISCELL
  mstr_standard tap *
  page89_i269
#ISCELL
  mstr_standard tap *
  page89_i270
#ISCELL
  mstr_standard tap *
  page89_i271
#ISCELL
  mstr_standard tap *
  page89_i272
#ISCELL
  mstr_standard tap *
  page89_i273
#ISCELL
  mstr_standard tap *
  page89_i274
#ISCELL
  mstr_standard tap *
  page89_i275
#ISCELL
  mstr_standard tap *
  page89_i276
#ISCELL
  mstr_standard tap *
  page89_i277
#ISCELL
  mstr_standard tap *
  page89_i278
#ISCELL
  mstr_standard tap *
  page89_i279
#ISCELL
  mstr_standard tap *
  page89_i280
#ISCELL
  mstr_standard tap *
  page89_i281
#ISCELL
  mstr_standard tap *
  page89_i282
#ISCELL
  mstr_standard tap *
  page89_i283
#ISCELL
  mstr_standard offpage *
  page89_i284
#CELL
  pure_quanta q_res *
  page89_i331
#ISCELL
  mstr_symbols gnd *
  page89_i332
#ISCELL
  mstr_standard offpage *
  page89_i333
#ISCELL
  mstr_standard offpage *
  page89_i334
#CELL
  pure_quanta sconn288_ddr506112002kq *
  page89_i348
#CELL
  pure_quanta sconn288_ddr506112002kq *
  page89_i350
#ISCELL
  mstr_standard offpage *
  page89_i351
#ISCELL
  mstr_symbols gnd *
  page89_i359
#CELL
  pure_quanta q_cap *
  page89_i360
#ISCELL
  mstr_standard offpage *
  page89_i361
#CELL
  pure_quanta q_res *
  page89_i362
#ISCELL
  mstr_symbols vcc_core *
  page89_i363
#CELL
  pure_quanta q_res *
  page89_i364
#ISCELL
  mstr_standard offpage *
  page89_i366
#ISCELL
  mstr_standard offpage *
  page89_i367
#ISCELL
  mstr_standard tap *
  page89_i368
#ISCELL
  mstr_standard tap *
  page89_i369
#ISCELL
  mstr_standard tap *
  page89_i370
#ISCELL
  mstr_standard tap *
  page89_i371
#ISCELL
  mstr_standard tap *
  page89_i372
#ISCELL
  mstr_standard tap *
  page89_i373
#ISCELL
  mstr_standard tap *
  page89_i374
#ISCELL
  mstr_standard tap *
  page89_i375
#ISCELL
  mstr_standard offpage *
  page89_i376
#ISCELL
  mstr_standard offpage *
  page89_i377
#ISCELL
  mstr_standard tap *
  page89_i378
#ISCELL
  mstr_standard tap *
  page89_i379
#ISCELL
  mstr_standard tap *
  page89_i380
#ISCELL
  mstr_standard tap *
  page89_i381
#ISCELL
  mstr_standard tap *
  page89_i382
#ISCELL
  mstr_standard tap *
  page89_i383
#ISCELL
  mstr_standard tap *
  page89_i384
#ISCELL
  mstr_standard tap *
  page89_i385
#ISCELL
  mstr_standard tap *
  page89_i386
#ISCELL
  mstr_standard tap *
  page89_i387
#ISCELL
  mstr_standard tap *
  page89_i388
#ISCELL
  mstr_standard tap *
  page89_i389
#ISCELL
  mstr_standard tap *
  page89_i390
#ISCELL
  mstr_standard tap *
  page89_i391
#ISCELL
  mstr_standard tap *
  page89_i392
#ISCELL
  mstr_standard tap *
  page89_i393
#ISCELL
  mstr_standard tap *
  page89_i394
#ISCELL
  mstr_standard tap *
  page89_i395
#ISCELL
  mstr_standard tap *
  page89_i396
#ISCELL
  mstr_standard tap *
  page89_i397
#ISCELL
  mstr_standard tap *
  page89_i398
#ISCELL
  mstr_standard tap *
  page89_i399
#ISCELL
  mstr_standard tap *
  page89_i400
#ISCELL
  mstr_standard tap *
  page89_i401
#ISCELL
  mstr_standard tap *
  page89_i402
#ISCELL
  mstr_standard tap *
  page89_i403
#ISCELL
  mstr_standard tap *
  page89_i404
#ISCELL
  mstr_standard tap *
  page89_i405
#ISCELL
  mstr_standard tap *
  page89_i406
#ISCELL
  mstr_standard tap *
  page89_i407
#ISCELL
  mstr_standard tap *
  page89_i408
#ISCELL
  mstr_standard tap *
  page89_i409
#CELL
  pure_quanta sconn288_ddr506112002kq *
  page89_i410
#ISCELL
  pure_quanta_power gnd *
  page89_i411
#CELL
  pure_quanta q_cap *
  page89_i412
#CELL
  pure_quanta q_cap *
  page89_i413
#ISCELL
  pure_quanta_power universal_power *
  page89_i414
#ISCELL
  mstr_standard offpage *
  page89_i415
#CELL
  pure_quanta q_res *
  page89_i416
#ISCELL
  mstr_standard offpage *
  page89_i417
#CELL
  pure_quanta q_res *
  page89_i418
#ISCELL
  mstr_misc dns *
  *
#ISCELL
  pure_quanta quanta_title_block_c *
  *
#ISCELL
  mstr_symbols gnd *
  page90_i150
#ISCELL
  mstr_symbols gnd *
  page90_i152
#ISCELL
  mstr_standard offpage *
  page90_i167
#ISCELL
  mstr_standard offpage *
  page90_i168
#ISCELL
  mstr_symbols vcc_core *
  page90_i175
#ISCELL
  mstr_standard offpage *
  page90_i176
#ISCELL
  mstr_standard tap *
  page90_i177
#ISCELL
  mstr_standard tap *
  page90_i178
#ISCELL
  mstr_standard tap *
  page90_i179
#ISCELL
  mstr_standard offpage *
  page90_i180
#ISCELL
  mstr_standard offpage *
  page90_i181
#ISCELL
  mstr_standard offpage *
  page90_i182
#ISCELL
  mstr_standard offpage *
  page90_i183
#ISCELL
  mstr_standard offpage *
  page90_i184
#ISCELL
  mstr_standard offpage *
  page90_i185
#ISCELL
  mstr_standard offpage *
  page90_i186
#ISCELL
  mstr_standard offpage *
  page90_i187
#ISCELL
  mstr_standard offpage *
  page90_i188
#ISCELL
  mstr_standard offpage *
  page90_i189
#ISCELL
  mstr_standard offpage *
  page90_i190
#ISCELL
  mstr_standard offpage *
  page90_i191
#ISCELL
  mstr_standard tap *
  page90_i192
#ISCELL
  mstr_standard tap *
  page90_i193
#ISCELL
  mstr_standard tap *
  page90_i194
#ISCELL
  mstr_standard tap *
  page90_i195
#ISCELL
  mstr_standard tap *
  page90_i196
#ISCELL
  mstr_standard tap *
  page90_i197
#ISCELL
  mstr_standard tap *
  page90_i198
#ISCELL
  mstr_standard tap *
  page90_i199
#ISCELL
  mstr_standard tap *
  page90_i200
#ISCELL
  mstr_standard tap *
  page90_i201
#ISCELL
  mstr_standard tap *
  page90_i202
#ISCELL
  mstr_standard tap *
  page90_i203
#ISCELL
  mstr_standard tap *
  page90_i204
#ISCELL
  mstr_standard tap *
  page90_i205
#ISCELL
  mstr_standard tap *
  page90_i206
#ISCELL
  mstr_standard tap *
  page90_i207
#ISCELL
  mstr_standard tap *
  page90_i208
#ISCELL
  mstr_standard tap *
  page90_i209
#ISCELL
  mstr_standard tap *
  page90_i210
#ISCELL
  mstr_standard tap *
  page90_i211
#ISCELL
  mstr_standard tap *
  page90_i212
#ISCELL
  mstr_standard tap *
  page90_i213
#ISCELL
  mstr_standard tap *
  page90_i214
#ISCELL
  mstr_standard tap *
  page90_i215
#ISCELL
  mstr_standard tap *
  page90_i216
#ISCELL
  mstr_standard tap *
  page90_i217
#ISCELL
  mstr_standard tap *
  page90_i218
#ISCELL
  mstr_standard tap *
  page90_i219
#ISCELL
  mstr_standard tap *
  page90_i220
#ISCELL
  mstr_standard tap *
  page90_i221
#ISCELL
  mstr_standard tap *
  page90_i222
#ISCELL
  mstr_standard tap *
  page90_i223
#ISCELL
  mstr_standard tap *
  page90_i224
#ISCELL
  mstr_standard tap *
  page90_i225
#ISCELL
  mstr_standard tap *
  page90_i226
#ISCELL
  mstr_standard tap *
  page90_i227
#ISCELL
  mstr_standard tap *
  page90_i228
#ISCELL
  mstr_standard tap *
  page90_i229
#ISCELL
  mstr_standard tap *
  page90_i230
#ISCELL
  mstr_standard tap *
  page90_i231
#ISCELL
  mstr_standard tap *
  page90_i232
#ISCELL
  mstr_standard tap *
  page90_i233
#ISCELL
  mstr_standard tap *
  page90_i234
#ISCELL
  mstr_standard tap *
  page90_i235
#ISCELL
  mstr_standard tap *
  page90_i236
#ISCELL
  mstr_standard tap *
  page90_i237
#ISCELL
  mstr_standard tap *
  page90_i238
#ISCELL
  mstr_standard tap *
  page90_i239
#ISCELL
  mstr_standard tap *
  page90_i240
#ISCELL
  mstr_standard tap *
  page90_i241
#ISCELL
  mstr_standard tap *
  page90_i242
#ISCELL
  mstr_standard tap *
  page90_i243
#ISCELL
  mstr_standard tap *
  page90_i244
#ISCELL
  mstr_standard tap *
  page90_i245
#ISCELL
  mstr_standard tap *
  page90_i246
#ISCELL
  mstr_standard tap *
  page90_i247
#ISCELL
  mstr_standard tap *
  page90_i248
#ISCELL
  mstr_standard tap *
  page90_i249
#ISCELL
  mstr_standard tap *
  page90_i250
#ISCELL
  mstr_standard tap *
  page90_i251
#ISCELL
  mstr_standard tap *
  page90_i252
#ISCELL
  mstr_standard tap *
  page90_i253
#ISCELL
  mstr_standard tap *
  page90_i254
#ISCELL
  mstr_standard tap *
  page90_i255
#ISCELL
  mstr_standard tap *
  page90_i256
#ISCELL
  mstr_standard tap *
  page90_i257
#ISCELL
  mstr_standard tap *
  page90_i258
#ISCELL
  mstr_standard tap *
  page90_i259
#ISCELL
  mstr_standard tap *
  page90_i260
#ISCELL
  mstr_standard tap *
  page90_i261
#ISCELL
  mstr_standard tap *
  page90_i262
#ISCELL
  mstr_standard tap *
  page90_i263
#ISCELL
  mstr_standard tap *
  page90_i264
#ISCELL
  mstr_standard tap *
  page90_i265
#ISCELL
  mstr_standard tap *
  page90_i266
#ISCELL
  mstr_standard tap *
  page90_i267
#ISCELL
  mstr_standard tap *
  page90_i268
#ISCELL
  mstr_standard tap *
  page90_i269
#ISCELL
  mstr_standard tap *
  page90_i270
#ISCELL
  mstr_standard tap *
  page90_i271
#ISCELL
  mstr_standard tap *
  page90_i272
#ISCELL
  mstr_standard tap *
  page90_i273
#ISCELL
  mstr_standard tap *
  page90_i274
#ISCELL
  mstr_standard tap *
  page90_i275
#ISCELL
  mstr_standard tap *
  page90_i276
#ISCELL
  mstr_standard tap *
  page90_i277
#ISCELL
  mstr_standard tap *
  page90_i278
#ISCELL
  mstr_standard tap *
  page90_i279
#ISCELL
  mstr_standard tap *
  page90_i280
#ISCELL
  mstr_standard tap *
  page90_i281
#ISCELL
  mstr_standard tap *
  page90_i282
#ISCELL
  mstr_standard offpage *
  page90_i283
#ISCELL
  mstr_standard offpage *
  page90_i284
#ISCELL
  mstr_symbols gnd *
  page90_i332
#ISCELL
  mstr_standard offpage *
  page90_i333
#ISCELL
  mstr_standard offpage *
  page90_i334
#CELL
  pure_quanta q_res *
  page90_i349
#CELL
  pure_quanta sconn288_ddr506112002kq *
  page90_i350
#CELL
  pure_quanta sconn288_ddr506112002kq *
  page90_i352
#ISCELL
  mstr_standard offpage *
  page90_i353
#CELL
  pure_quanta q_cap *
  page90_i361
#ISCELL
  mstr_symbols gnd *
  page90_i362
#ISCELL
  mstr_standard offpage *
  page90_i363
#CELL
  pure_quanta q_res *
  page90_i364
#CELL
  pure_quanta q_res *
  page90_i365
#ISCELL
  mstr_symbols vcc_core *
  page90_i366
#ISCELL
  mstr_standard offpage *
  page90_i368
#ISCELL
  mstr_standard offpage *
  page90_i369
#ISCELL
  mstr_standard offpage *
  page90_i370
#ISCELL
  mstr_standard offpage *
  page90_i371
#ISCELL
  mstr_standard tap *
  page90_i372
#ISCELL
  mstr_standard tap *
  page90_i373
#ISCELL
  mstr_standard tap *
  page90_i374
#ISCELL
  mstr_standard tap *
  page90_i375
#ISCELL
  mstr_standard tap *
  page90_i376
#ISCELL
  mstr_standard tap *
  page90_i377
#ISCELL
  mstr_standard tap *
  page90_i378
#ISCELL
  mstr_standard tap *
  page90_i379
#ISCELL
  mstr_standard tap *
  page90_i380
#ISCELL
  mstr_standard tap *
  page90_i381
#ISCELL
  mstr_standard tap *
  page90_i382
#ISCELL
  mstr_standard tap *
  page90_i383
#ISCELL
  mstr_standard tap *
  page90_i384
#ISCELL
  mstr_standard tap *
  page90_i385
#ISCELL
  mstr_standard tap *
  page90_i386
#ISCELL
  mstr_standard tap *
  page90_i387
#ISCELL
  mstr_standard tap *
  page90_i388
#ISCELL
  mstr_standard tap *
  page90_i389
#ISCELL
  mstr_standard tap *
  page90_i390
#ISCELL
  mstr_standard tap *
  page90_i391
#ISCELL
  mstr_standard tap *
  page90_i392
#ISCELL
  mstr_standard tap *
  page90_i393
#ISCELL
  mstr_standard tap *
  page90_i394
#ISCELL
  mstr_standard tap *
  page90_i395
#ISCELL
  mstr_standard tap *
  page90_i396
#ISCELL
  mstr_standard tap *
  page90_i397
#ISCELL
  mstr_standard tap *
  page90_i398
#ISCELL
  mstr_standard tap *
  page90_i399
#ISCELL
  mstr_standard tap *
  page90_i400
#ISCELL
  mstr_standard tap *
  page90_i401
#ISCELL
  mstr_standard tap *
  page90_i402
#ISCELL
  mstr_standard tap *
  page90_i403
#ISCELL
  mstr_standard tap *
  page90_i404
#ISCELL
  mstr_standard tap *
  page90_i405
#ISCELL
  mstr_standard tap *
  page90_i406
#ISCELL
  mstr_standard tap *
  page90_i407
#ISCELL
  mstr_standard tap *
  page90_i408
#ISCELL
  mstr_standard tap *
  page90_i409
#ISCELL
  mstr_standard tap *
  page90_i410
#ISCELL
  mstr_standard tap *
  page90_i411
#CELL
  pure_quanta sconn288_ddr506112002kq *
  page90_i412
#ISCELL
  pure_quanta_power gnd *
  page90_i413
#CELL
  pure_quanta q_cap *
  page90_i414
#CELL
  pure_quanta q_cap *
  page90_i415
#ISCELL
  pure_quanta_power universal_power *
  page90_i416
#ISCELL
  mstr_standard offpage *
  page90_i417
#CELL
  pure_quanta q_res *
  page90_i418
#CELL
  pure_quanta q_res *
  page90_i419
#ISCELL
  mstr_standard offpage *
  page90_i420
#ISCELL
  mstr_misc dns *
  *
#ISCELL
  pure_quanta quanta_title_block_c *
  *
#ISCELL
  mstr_standard offpage *
  page91_i1
#ISCELL
  mstr_standard offpage *
  page91_i10
#ISCELL
  mstr_standard tap *
  page91_i100
#ISCELL
  mstr_standard tap *
  page91_i101
#ISCELL
  mstr_standard tap *
  page91_i102
#ISCELL
  mstr_standard tap *
  page91_i103
#ISCELL
  mstr_standard tap *
  page91_i104
#ISCELL
  mstr_standard tap *
  page91_i105
#ISCELL
  mstr_standard tap *
  page91_i106
#ISCELL
  mstr_standard tap *
  page91_i107
#ISCELL
  mstr_standard tap *
  page91_i108
#ISCELL
  mstr_standard tap *
  page91_i109
#ISCELL
  mstr_standard offpage *
  page91_i11
#ISCELL
  mstr_standard tap *
  page91_i110
#ISCELL
  mstr_standard tap *
  page91_i111
#ISCELL
  mstr_standard tap *
  page91_i112
#ISCELL
  mstr_standard tap *
  page91_i113
#ISCELL
  mstr_standard tap *
  page91_i114
#ISCELL
  mstr_standard tap *
  page91_i115
#ISCELL
  mstr_standard tap *
  page91_i116
#ISCELL
  mstr_standard tap *
  page91_i117
#ISCELL
  mstr_standard tap *
  page91_i118
#ISCELL
  mstr_standard tap *
  page91_i119
#ISCELL
  mstr_standard offpage *
  page91_i12
#ISCELL
  mstr_standard tap *
  page91_i120
#ISCELL
  mstr_standard tap *
  page91_i121
#ISCELL
  mstr_standard tap *
  page91_i122
#ISCELL
  mstr_standard tap *
  page91_i123
#ISCELL
  mstr_standard tap *
  page91_i124
#ISCELL
  mstr_standard tap *
  page91_i125
#ISCELL
  mstr_standard offpage *
  page91_i126
#ISCELL
  mstr_standard offpage *
  page91_i127
#ISCELL
  mstr_symbols gnd *
  page91_i128
#CELL
  pure_quanta q_res *
  page91_i129
#ISCELL
  mstr_standard offpage *
  page91_i13
#ISCELL
  mstr_symbols gnd *
  page91_i130
#ISCELL
  mstr_standard offpage *
  page91_i14
#ISCELL
  mstr_symbols gnd *
  page91_i146
#ISCELL
  mstr_standard offpage *
  page91_i15
#ISCELL
  mstr_standard offpage *
  page91_i16
#ISCELL
  mstr_standard offpage *
  page91_i17
#CELL
  pure_quanta sconn288_ddr506112002kq *
  page91_i177
#ISCELL
  mstr_standard offpage *
  page91_i18
#CELL
  pure_quanta q_cap *
  page91_i183
#ISCELL
  mstr_symbols gnd *
  page91_i184
#ISCELL
  mstr_standard offpage *
  page91_i185
#CELL
  pure_quanta q_res *
  page91_i186
#CELL
  pure_quanta q_res *
  page91_i187
#ISCELL
  mstr_symbols vcc_core *
  page91_i188
#ISCELL
  mstr_symbols vcc_core *
  page91_i189
#ISCELL
  mstr_standard offpage *
  page91_i19
#CELL
  pure_quanta q_res *
  page91_i190
#ISCELL
  mstr_standard offpage *
  page91_i192
#ISCELL
  mstr_standard offpage *
  page91_i193
#ISCELL
  mstr_standard offpage *
  page91_i194
#ISCELL
  mstr_standard offpage *
  page91_i195
#ISCELL
  mstr_standard tap *
  page91_i196
#ISCELL
  mstr_standard tap *
  page91_i197
#ISCELL
  mstr_standard tap *
  page91_i198
#ISCELL
  mstr_standard tap *
  page91_i199
#ISCELL
  mstr_standard offpage *
  page91_i2
#ISCELL
  mstr_standard offpage *
  page91_i20
#ISCELL
  mstr_standard tap *
  page91_i200
#ISCELL
  mstr_standard tap *
  page91_i201
#ISCELL
  mstr_standard tap *
  page91_i202
#ISCELL
  mstr_standard tap *
  page91_i203
#ISCELL
  mstr_standard tap *
  page91_i204
#ISCELL
  mstr_standard tap *
  page91_i205
#ISCELL
  mstr_standard tap *
  page91_i206
#ISCELL
  mstr_standard tap *
  page91_i207
#ISCELL
  mstr_standard tap *
  page91_i208
#ISCELL
  mstr_standard tap *
  page91_i209
#ISCELL
  mstr_standard offpage *
  page91_i21
#ISCELL
  mstr_standard tap *
  page91_i210
#ISCELL
  mstr_standard tap *
  page91_i211
#ISCELL
  mstr_standard tap *
  page91_i212
#ISCELL
  mstr_standard tap *
  page91_i213
#ISCELL
  mstr_standard tap *
  page91_i214
#ISCELL
  mstr_standard tap *
  page91_i215
#ISCELL
  mstr_standard tap *
  page91_i216
#ISCELL
  mstr_standard tap *
  page91_i217
#ISCELL
  mstr_standard tap *
  page91_i218
#ISCELL
  mstr_standard tap *
  page91_i219
#CELL
  pure_quanta sconn288_ddr506112002kq *
  page91_i22
#ISCELL
  mstr_standard tap *
  page91_i220
#ISCELL
  mstr_standard tap *
  page91_i221
#ISCELL
  mstr_standard tap *
  page91_i222
#ISCELL
  mstr_standard tap *
  page91_i223
#ISCELL
  mstr_standard tap *
  page91_i224
#ISCELL
  mstr_standard tap *
  page91_i225
#ISCELL
  mstr_standard tap *
  page91_i226
#ISCELL
  mstr_standard tap *
  page91_i227
#ISCELL
  mstr_standard tap *
  page91_i228
#ISCELL
  mstr_standard tap *
  page91_i229
#ISCELL
  mstr_standard tap *
  page91_i23
#ISCELL
  mstr_standard tap *
  page91_i230
#ISCELL
  mstr_standard tap *
  page91_i231
#ISCELL
  mstr_standard tap *
  page91_i232
#ISCELL
  mstr_standard tap *
  page91_i233
#ISCELL
  mstr_standard tap *
  page91_i234
#ISCELL
  mstr_standard tap *
  page91_i235
#CELL
  pure_quanta sconn288_ddr506112002kq *
  page91_i236
#ISCELL
  pure_quanta_power gnd *
  page91_i237
#CELL
  pure_quanta q_cap *
  page91_i238
#CELL
  pure_quanta q_cap *
  page91_i239
#ISCELL
  mstr_standard tap *
  page91_i24
#ISCELL
  pure_quanta_power universal_power *
  page91_i240
#ISCELL
  mstr_standard offpage *
  page91_i241
#CELL
  pure_quanta q_res *
  page91_i242
#CELL
  pure_quanta q_res *
  page91_i243
#ISCELL
  pure_quanta_power vcc_core *
  page91_i244
#ISCELL
  standard offpage *
  page91_i245
#ISCELL
  standard offpage *
  page91_i246
#ISCELL
  pure_quanta_power vcc_core *
  page91_i247
#CELL
  pure_quanta q_res *
  page91_i248
#CELL
  pure_quanta q_res *
  page91_i249
#ISCELL
  mstr_standard tap *
  page91_i25
#CELL
  pure_quanta q_res *
  page91_i250
#CELL
  pure_quanta schottky_12 *
  page91_i251
#ISCELL
  pure_quanta_power vcc_core *
  page91_i252
#ISCELL
  standard offpage *
  page91_i253
#CELL
  pure_quanta q_res *
  page91_i254
#ISCELL
  mstr_standard offpage *
  page91_i255
#ISCELL
  mstr_standard tap *
  page91_i26
#ISCELL
  mstr_standard tap *
  page91_i27
#ISCELL
  mstr_standard tap *
  page91_i28
#ISCELL
  mstr_standard tap *
  page91_i29
#ISCELL
  mstr_standard tap *
  page91_i30
#ISCELL
  mstr_standard tap *
  page91_i31
#ISCELL
  mstr_standard tap *
  page91_i32
#ISCELL
  mstr_standard tap *
  page91_i33
#ISCELL
  mstr_standard tap *
  page91_i34
#ISCELL
  mstr_standard tap *
  page91_i35
#ISCELL
  mstr_standard tap *
  page91_i36
#ISCELL
  mstr_standard tap *
  page91_i37
#ISCELL
  mstr_standard tap *
  page91_i38
#ISCELL
  mstr_standard tap *
  page91_i46
#ISCELL
  mstr_standard tap *
  page91_i47
#ISCELL
  mstr_standard tap *
  page91_i48
#ISCELL
  mstr_standard tap *
  page91_i49
#ISCELL
  mstr_standard tap *
  page91_i50
#ISCELL
  mstr_standard tap *
  page91_i51
#ISCELL
  mstr_standard tap *
  page91_i52
#ISCELL
  mstr_standard tap *
  page91_i53
#ISCELL
  mstr_standard tap *
  page91_i54
#ISCELL
  mstr_standard tap *
  page91_i55
#ISCELL
  mstr_standard tap *
  page91_i56
#ISCELL
  mstr_standard tap *
  page91_i57
#ISCELL
  mstr_standard tap *
  page91_i58
#ISCELL
  mstr_standard tap *
  page91_i59
#ISCELL
  mstr_standard offpage *
  page91_i6
#ISCELL
  mstr_standard tap *
  page91_i60
#ISCELL
  mstr_standard tap *
  page91_i61
#ISCELL
  mstr_standard tap *
  page91_i62
#ISCELL
  mstr_standard tap *
  page91_i63
#ISCELL
  mstr_standard tap *
  page91_i64
#ISCELL
  mstr_standard tap *
  page91_i65
#ISCELL
  mstr_standard tap *
  page91_i66
#ISCELL
  mstr_standard tap *
  page91_i67
#ISCELL
  mstr_standard tap *
  page91_i68
#ISCELL
  mstr_standard tap *
  page91_i69
#ISCELL
  mstr_standard offpage *
  page91_i7
#ISCELL
  mstr_standard tap *
  page91_i70
#ISCELL
  mstr_standard tap *
  page91_i71
#ISCELL
  mstr_standard tap *
  page91_i72
#ISCELL
  mstr_standard tap *
  page91_i73
#ISCELL
  mstr_standard tap *
  page91_i74
#ISCELL
  mstr_standard tap *
  page91_i75
#ISCELL
  mstr_standard tap *
  page91_i76
#ISCELL
  mstr_standard tap *
  page91_i77
#ISCELL
  mstr_standard tap *
  page91_i78
#ISCELL
  mstr_standard tap *
  page91_i79
#ISCELL
  mstr_symbols vcc_core *
  page91_i8
#ISCELL
  mstr_standard tap *
  page91_i80
#ISCELL
  mstr_standard tap *
  page91_i81
#ISCELL
  mstr_standard tap *
  page91_i82
#ISCELL
  mstr_standard offpage *
  page91_i83
#ISCELL
  mstr_standard tap *
  page91_i85
#ISCELL
  mstr_standard tap *
  page91_i86
#ISCELL
  mstr_standard tap *
  page91_i87
#ISCELL
  mstr_standard tap *
  page91_i88
#ISCELL
  mstr_standard tap *
  page91_i89
#ISCELL
  mstr_standard offpage *
  page91_i9
#ISCELL
  mstr_standard tap *
  page91_i90
#ISCELL
  mstr_standard tap *
  page91_i91
#ISCELL
  mstr_standard tap *
  page91_i92
#ISCELL
  mstr_standard tap *
  page91_i93
#ISCELL
  mstr_standard tap *
  page91_i94
#ISCELL
  mstr_standard tap *
  page91_i95
#ISCELL
  mstr_standard tap *
  page91_i96
#ISCELL
  mstr_standard tap *
  page91_i97
#ISCELL
  mstr_standard tap *
  page91_i98
#ISCELL
  mstr_standard tap *
  page91_i99
#ISCELL
  mstr_misc dns *
  *
#ISCELL
  pure_quanta quanta_title_block_c *
  *
#ISCELL
  mstr_standard offpage *
  page92_i1
#ISCELL
  mstr_standard offpage *
  page92_i10
#ISCELL
  mstr_standard tap *
  page92_i100
#ISCELL
  mstr_standard tap *
  page92_i101
#ISCELL
  mstr_standard tap *
  page92_i102
#ISCELL
  mstr_standard tap *
  page92_i103
#ISCELL
  mstr_standard tap *
  page92_i104
#ISCELL
  mstr_standard tap *
  page92_i105
#ISCELL
  mstr_standard tap *
  page92_i106
#ISCELL
  mstr_standard tap *
  page92_i107
#ISCELL
  mstr_standard tap *
  page92_i108
#ISCELL
  mstr_standard tap *
  page92_i109
#ISCELL
  mstr_standard offpage *
  page92_i11
#ISCELL
  mstr_standard tap *
  page92_i110
#ISCELL
  mstr_standard tap *
  page92_i111
#ISCELL
  mstr_standard tap *
  page92_i112
#ISCELL
  mstr_standard tap *
  page92_i113
#ISCELL
  mstr_standard tap *
  page92_i114
#ISCELL
  mstr_standard tap *
  page92_i115
#ISCELL
  mstr_standard tap *
  page92_i116
#ISCELL
  mstr_standard tap *
  page92_i117
#ISCELL
  mstr_standard tap *
  page92_i118
#ISCELL
  mstr_standard tap *
  page92_i119
#ISCELL
  mstr_standard offpage *
  page92_i12
#ISCELL
  mstr_standard tap *
  page92_i120
#ISCELL
  mstr_standard tap *
  page92_i121
#ISCELL
  mstr_standard tap *
  page92_i122
#ISCELL
  mstr_standard tap *
  page92_i123
#ISCELL
  mstr_standard tap *
  page92_i124
#ISCELL
  mstr_standard tap *
  page92_i125
#ISCELL
  mstr_standard offpage *
  page92_i126
#ISCELL
  mstr_standard offpage *
  page92_i127
#ISCELL
  mstr_symbols gnd *
  page92_i128
#CELL
  pure_quanta q_res *
  page92_i129
#ISCELL
  mstr_standard offpage *
  page92_i13
#ISCELL
  mstr_standard offpage *
  page92_i14
#ISCELL
  mstr_symbols gnd *
  page92_i140
#ISCELL
  mstr_symbols gnd *
  page92_i141
#ISCELL
  mstr_standard offpage *
  page92_i15
#ISCELL
  mstr_standard offpage *
  page92_i16
#ISCELL
  mstr_standard offpage *
  page92_i17
#CELL
  pure_quanta sconn288_ddr506112002kq *
  page92_i177
#ISCELL
  mstr_standard offpage *
  page92_i178
#ISCELL
  mstr_standard offpage *
  page92_i18
#CELL
  pure_quanta q_cap *
  page92_i186
#ISCELL
  mstr_symbols gnd *
  page92_i187
#ISCELL
  mstr_standard offpage *
  page92_i188
#CELL
  pure_quanta q_res *
  page92_i189
#ISCELL
  mstr_standard offpage *
  page92_i19
#ISCELL
  mstr_symbols vcc_core *
  page92_i190
#CELL
  pure_quanta q_res *
  page92_i191
#ISCELL
  mstr_standard offpage *
  page92_i193
#ISCELL
  mstr_standard offpage *
  page92_i194
#ISCELL
  mstr_standard offpage *
  page92_i195
#ISCELL
  mstr_standard offpage *
  page92_i196
#ISCELL
  mstr_standard tap *
  page92_i197
#ISCELL
  mstr_standard tap *
  page92_i198
#ISCELL
  mstr_standard tap *
  page92_i199
#ISCELL
  mstr_standard offpage *
  page92_i2
#ISCELL
  mstr_standard offpage *
  page92_i20
#ISCELL
  mstr_standard tap *
  page92_i200
#ISCELL
  mstr_standard tap *
  page92_i201
#ISCELL
  mstr_standard tap *
  page92_i202
#ISCELL
  mstr_standard tap *
  page92_i203
#ISCELL
  mstr_standard tap *
  page92_i204
#ISCELL
  mstr_standard tap *
  page92_i205
#ISCELL
  mstr_standard tap *
  page92_i206
#ISCELL
  mstr_standard tap *
  page92_i207
#ISCELL
  mstr_standard tap *
  page92_i208
#ISCELL
  mstr_standard tap *
  page92_i209
#ISCELL
  mstr_standard offpage *
  page92_i21
#ISCELL
  mstr_standard tap *
  page92_i210
#ISCELL
  mstr_standard tap *
  page92_i211
#ISCELL
  mstr_standard tap *
  page92_i212
#ISCELL
  mstr_standard tap *
  page92_i213
#ISCELL
  mstr_standard tap *
  page92_i214
#ISCELL
  mstr_standard tap *
  page92_i215
#ISCELL
  mstr_standard tap *
  page92_i216
#ISCELL
  mstr_standard tap *
  page92_i217
#ISCELL
  mstr_standard tap *
  page92_i218
#ISCELL
  mstr_standard tap *
  page92_i219
#CELL
  pure_quanta sconn288_ddr506112002kq *
  page92_i22
#ISCELL
  mstr_standard tap *
  page92_i220
#ISCELL
  mstr_standard tap *
  page92_i221
#ISCELL
  mstr_standard tap *
  page92_i222
#ISCELL
  mstr_standard tap *
  page92_i223
#ISCELL
  mstr_standard tap *
  page92_i224
#ISCELL
  mstr_standard tap *
  page92_i225
#ISCELL
  mstr_standard tap *
  page92_i226
#ISCELL
  mstr_standard tap *
  page92_i227
#ISCELL
  mstr_standard tap *
  page92_i228
#ISCELL
  mstr_standard tap *
  page92_i229
#ISCELL
  mstr_standard tap *
  page92_i23
#ISCELL
  mstr_standard tap *
  page92_i230
#ISCELL
  mstr_standard tap *
  page92_i231
#ISCELL
  mstr_standard tap *
  page92_i232
#ISCELL
  mstr_standard tap *
  page92_i233
#ISCELL
  mstr_standard tap *
  page92_i234
#ISCELL
  mstr_standard tap *
  page92_i235
#ISCELL
  mstr_standard tap *
  page92_i236
#CELL
  pure_quanta sconn288_ddr506112002kq *
  page92_i237
#ISCELL
  pure_quanta_power gnd *
  page92_i238
#CELL
  pure_quanta q_cap *
  page92_i239
#ISCELL
  mstr_standard tap *
  page92_i24
#CELL
  pure_quanta q_cap *
  page92_i240
#ISCELL
  pure_quanta_power universal_power *
  page92_i241
#ISCELL
  mstr_standard offpage *
  page92_i242
#CELL
  pure_quanta q_res *
  page92_i243
#CELL
  pure_quanta q_res *
  page92_i244
#ISCELL
  mstr_standard offpage *
  page92_i245
#ISCELL
  mstr_standard tap *
  page92_i25
#ISCELL
  mstr_standard tap *
  page92_i26
#ISCELL
  mstr_standard tap *
  page92_i27
#ISCELL
  mstr_standard tap *
  page92_i28
#ISCELL
  mstr_standard tap *
  page92_i29
#ISCELL
  mstr_standard tap *
  page92_i30
#ISCELL
  mstr_standard tap *
  page92_i31
#ISCELL
  mstr_standard tap *
  page92_i32
#ISCELL
  mstr_standard tap *
  page92_i33
#ISCELL
  mstr_standard tap *
  page92_i34
#ISCELL
  mstr_standard tap *
  page92_i35
#ISCELL
  mstr_standard tap *
  page92_i36
#ISCELL
  mstr_standard tap *
  page92_i37
#ISCELL
  mstr_standard tap *
  page92_i38
#ISCELL
  mstr_standard tap *
  page92_i39
#ISCELL
  mstr_standard tap *
  page92_i40
#ISCELL
  mstr_standard tap *
  page92_i41
#ISCELL
  mstr_standard tap *
  page92_i42
#ISCELL
  mstr_standard tap *
  page92_i43
#ISCELL
  mstr_standard tap *
  page92_i44
#ISCELL
  mstr_standard tap *
  page92_i45
#ISCELL
  mstr_standard tap *
  page92_i46
#ISCELL
  mstr_standard tap *
  page92_i47
#ISCELL
  mstr_standard tap *
  page92_i48
#ISCELL
  mstr_standard tap *
  page92_i49
#ISCELL
  mstr_symbols vcc_core *
  page92_i5
#ISCELL
  mstr_standard tap *
  page92_i50
#ISCELL
  mstr_standard tap *
  page92_i51
#ISCELL
  mstr_standard tap *
  page92_i52
#ISCELL
  mstr_standard tap *
  page92_i53
#ISCELL
  mstr_standard tap *
  page92_i54
#ISCELL
  mstr_standard tap *
  page92_i55
#ISCELL
  mstr_standard tap *
  page92_i56
#ISCELL
  mstr_standard tap *
  page92_i57
#ISCELL
  mstr_standard tap *
  page92_i58
#ISCELL
  mstr_standard tap *
  page92_i59
#ISCELL
  mstr_standard tap *
  page92_i60
#ISCELL
  mstr_standard tap *
  page92_i61
#ISCELL
  mstr_standard tap *
  page92_i62
#ISCELL
  mstr_standard tap *
  page92_i63
#ISCELL
  mstr_standard tap *
  page92_i64
#ISCELL
  mstr_standard tap *
  page92_i65
#ISCELL
  mstr_standard tap *
  page92_i66
#ISCELL
  mstr_standard offpage *
  page92_i73
#ISCELL
  mstr_standard tap *
  page92_i76
#ISCELL
  mstr_standard tap *
  page92_i77
#ISCELL
  mstr_standard tap *
  page92_i78
#ISCELL
  mstr_standard tap *
  page92_i79
#ISCELL
  mstr_standard offpage *
  page92_i8
#ISCELL
  mstr_standard tap *
  page92_i80
#ISCELL
  mstr_standard tap *
  page92_i81
#ISCELL
  mstr_standard tap *
  page92_i82
#ISCELL
  mstr_standard tap *
  page92_i83
#ISCELL
  mstr_standard tap *
  page92_i84
#ISCELL
  mstr_standard tap *
  page92_i85
#ISCELL
  mstr_standard tap *
  page92_i86
#ISCELL
  mstr_standard tap *
  page92_i87
#ISCELL
  mstr_standard tap *
  page92_i88
#ISCELL
  mstr_standard tap *
  page92_i89
#ISCELL
  mstr_standard offpage *
  page92_i9
#ISCELL
  mstr_standard tap *
  page92_i90
#ISCELL
  mstr_standard tap *
  page92_i91
#ISCELL
  mstr_standard tap *
  page92_i92
#ISCELL
  mstr_standard tap *
  page92_i93
#ISCELL
  mstr_standard tap *
  page92_i94
#ISCELL
  mstr_standard tap *
  page92_i95
#ISCELL
  mstr_standard tap *
  page92_i96
#ISCELL
  mstr_standard tap *
  page92_i97
#ISCELL
  mstr_standard tap *
  page92_i98
#ISCELL
  mstr_standard tap *
  page92_i99
#ISCELL
  mstr_misc dns *
  *
#ISCELL
  pure_quanta quanta_title_block_c *
  *
#ISCELL
  mstr_standard offpage *
  page93_i1
#ISCELL
  mstr_standard offpage *
  page93_i10
#ISCELL
  mstr_standard tap *
  page93_i100
#ISCELL
  mstr_standard tap *
  page93_i101
#ISCELL
  mstr_standard tap *
  page93_i102
#ISCELL
  mstr_standard tap *
  page93_i103
#ISCELL
  mstr_standard tap *
  page93_i104
#ISCELL
  mstr_standard tap *
  page93_i105
#ISCELL
  mstr_standard tap *
  page93_i106
#ISCELL
  mstr_standard tap *
  page93_i107
#ISCELL
  mstr_standard tap *
  page93_i108
#ISCELL
  mstr_standard tap *
  page93_i109
#ISCELL
  mstr_standard offpage *
  page93_i11
#ISCELL
  mstr_standard tap *
  page93_i110
#ISCELL
  mstr_standard tap *
  page93_i111
#ISCELL
  mstr_standard tap *
  page93_i112
#ISCELL
  mstr_standard tap *
  page93_i113
#ISCELL
  mstr_standard tap *
  page93_i114
#ISCELL
  mstr_standard tap *
  page93_i115
#ISCELL
  mstr_standard tap *
  page93_i116
#ISCELL
  mstr_standard tap *
  page93_i117
#ISCELL
  mstr_standard tap *
  page93_i118
#ISCELL
  mstr_standard tap *
  page93_i119
#ISCELL
  mstr_standard offpage *
  page93_i12
#ISCELL
  mstr_standard tap *
  page93_i120
#ISCELL
  mstr_standard tap *
  page93_i121
#ISCELL
  mstr_standard tap *
  page93_i122
#ISCELL
  mstr_standard tap *
  page93_i123
#ISCELL
  mstr_standard tap *
  page93_i124
#ISCELL
  mstr_standard offpage *
  page93_i125
#ISCELL
  mstr_standard offpage *
  page93_i126
#ISCELL
  mstr_symbols gnd *
  page93_i127
#CELL
  pure_quanta q_res *
  page93_i128
#ISCELL
  mstr_standard offpage *
  page93_i13
#ISCELL
  mstr_standard offpage *
  page93_i14
#ISCELL
  mstr_symbols gnd *
  page93_i141
#ISCELL
  mstr_symbols gnd *
  page93_i142
#CELL
  pure_quanta sconn288_ddr506112002kq *
  page93_i143
#ISCELL
  mstr_standard offpage *
  page93_i15
#ISCELL
  mstr_standard offpage *
  page93_i16
#ISCELL
  mstr_standard offpage *
  page93_i17
#ISCELL
  mstr_standard offpage *
  page93_i18
#CELL
  pure_quanta q_cap *
  page93_i185
#ISCELL
  mstr_symbols gnd *
  page93_i186
#ISCELL
  mstr_standard offpage *
  page93_i187
#CELL
  pure_quanta q_res *
  page93_i188
#CELL
  pure_quanta q_res *
  page93_i189
#ISCELL
  mstr_standard offpage *
  page93_i19
#ISCELL
  mstr_symbols vcc_core *
  page93_i190
#ISCELL
  mstr_standard tap *
  page93_i191
#ISCELL
  mstr_standard offpage *
  page93_i193
#ISCELL
  mstr_standard offpage *
  page93_i194
#ISCELL
  mstr_standard offpage *
  page93_i195
#ISCELL
  mstr_standard offpage *
  page93_i196
#ISCELL
  mstr_standard tap *
  page93_i197
#ISCELL
  mstr_standard tap *
  page93_i198
#ISCELL
  mstr_standard tap *
  page93_i199
#ISCELL
  mstr_standard offpage *
  page93_i2
#ISCELL
  mstr_standard offpage *
  page93_i20
#ISCELL
  mstr_standard tap *
  page93_i200
#ISCELL
  mstr_standard tap *
  page93_i201
#ISCELL
  mstr_standard tap *
  page93_i202
#ISCELL
  mstr_standard tap *
  page93_i203
#ISCELL
  mstr_standard tap *
  page93_i204
#ISCELL
  mstr_standard tap *
  page93_i205
#ISCELL
  mstr_standard tap *
  page93_i206
#ISCELL
  mstr_standard tap *
  page93_i207
#ISCELL
  mstr_standard tap *
  page93_i208
#ISCELL
  mstr_standard tap *
  page93_i209
#ISCELL
  mstr_standard offpage *
  page93_i21
#ISCELL
  mstr_standard tap *
  page93_i210
#ISCELL
  mstr_standard tap *
  page93_i211
#ISCELL
  mstr_standard tap *
  page93_i212
#ISCELL
  mstr_standard tap *
  page93_i213
#ISCELL
  mstr_standard tap *
  page93_i214
#ISCELL
  mstr_standard tap *
  page93_i215
#ISCELL
  mstr_standard tap *
  page93_i216
#ISCELL
  mstr_standard tap *
  page93_i217
#ISCELL
  mstr_standard tap *
  page93_i218
#ISCELL
  mstr_standard tap *
  page93_i219
#CELL
  pure_quanta sconn288_ddr506112002kq *
  page93_i22
#ISCELL
  mstr_standard tap *
  page93_i220
#ISCELL
  mstr_standard tap *
  page93_i221
#ISCELL
  mstr_standard tap *
  page93_i222
#ISCELL
  mstr_standard tap *
  page93_i223
#ISCELL
  mstr_standard tap *
  page93_i224
#ISCELL
  mstr_standard tap *
  page93_i225
#ISCELL
  mstr_standard tap *
  page93_i226
#ISCELL
  mstr_standard tap *
  page93_i227
#ISCELL
  mstr_standard tap *
  page93_i228
#ISCELL
  mstr_standard tap *
  page93_i229
#ISCELL
  mstr_standard tap *
  page93_i23
#ISCELL
  mstr_standard tap *
  page93_i230
#ISCELL
  mstr_standard tap *
  page93_i231
#ISCELL
  mstr_standard tap *
  page93_i232
#ISCELL
  mstr_standard tap *
  page93_i233
#ISCELL
  mstr_standard tap *
  page93_i234
#ISCELL
  mstr_standard tap *
  page93_i235
#CELL
  pure_quanta sconn288_ddr506112002kq *
  page93_i236
#ISCELL
  pure_quanta_power gnd *
  page93_i237
#CELL
  pure_quanta q_cap *
  page93_i238
#CELL
  pure_quanta q_cap *
  page93_i239
#ISCELL
  mstr_standard tap *
  page93_i24
#ISCELL
  pure_quanta_power universal_power *
  page93_i240
#ISCELL
  mstr_standard offpage *
  page93_i241
#CELL
  pure_quanta q_res *
  page93_i242
#CELL
  pure_quanta q_res *
  page93_i243
#ISCELL
  mstr_standard offpage *
  page93_i244
#ISCELL
  mstr_standard tap *
  page93_i25
#ISCELL
  mstr_standard tap *
  page93_i26
#ISCELL
  mstr_standard tap *
  page93_i27
#ISCELL
  mstr_standard tap *
  page93_i28
#ISCELL
  mstr_standard tap *
  page93_i29
#ISCELL
  mstr_standard tap *
  page93_i30
#ISCELL
  mstr_standard tap *
  page93_i31
#ISCELL
  mstr_standard tap *
  page93_i32
#ISCELL
  mstr_standard tap *
  page93_i33
#ISCELL
  mstr_standard tap *
  page93_i34
#ISCELL
  mstr_standard tap *
  page93_i35
#ISCELL
  mstr_standard tap *
  page93_i36
#ISCELL
  mstr_standard tap *
  page93_i37
#ISCELL
  mstr_standard tap *
  page93_i38
#ISCELL
  mstr_standard tap *
  page93_i39
#ISCELL
  mstr_standard tap *
  page93_i40
#ISCELL
  mstr_standard tap *
  page93_i41
#ISCELL
  mstr_standard tap *
  page93_i42
#ISCELL
  mstr_standard tap *
  page93_i43
#ISCELL
  mstr_standard tap *
  page93_i44
#ISCELL
  mstr_standard tap *
  page93_i45
#ISCELL
  mstr_standard tap *
  page93_i46
#ISCELL
  mstr_standard tap *
  page93_i47
#ISCELL
  mstr_standard tap *
  page93_i48
#ISCELL
  mstr_standard tap *
  page93_i49
#ISCELL
  mstr_standard tap *
  page93_i50
#ISCELL
  mstr_standard tap *
  page93_i51
#ISCELL
  mstr_standard tap *
  page93_i52
#ISCELL
  mstr_standard tap *
  page93_i53
#ISCELL
  mstr_standard tap *
  page93_i54
#ISCELL
  mstr_standard tap *
  page93_i55
#ISCELL
  mstr_standard tap *
  page93_i56
#ISCELL
  mstr_standard tap *
  page93_i57
#ISCELL
  mstr_standard tap *
  page93_i58
#ISCELL
  mstr_standard tap *
  page93_i59
#ISCELL
  mstr_standard offpage *
  page93_i6
#ISCELL
  mstr_standard tap *
  page93_i60
#ISCELL
  mstr_standard tap *
  page93_i61
#ISCELL
  mstr_standard tap *
  page93_i62
#ISCELL
  mstr_standard tap *
  page93_i63
#ISCELL
  mstr_standard tap *
  page93_i64
#ISCELL
  mstr_standard tap *
  page93_i65
#ISCELL
  mstr_standard tap *
  page93_i66
#ISCELL
  mstr_standard tap *
  page93_i67
#ISCELL
  mstr_standard tap *
  page93_i68
#ISCELL
  mstr_standard offpage *
  page93_i7
#ISCELL
  mstr_standard offpage *
  page93_i76
#ISCELL
  mstr_standard tap *
  page93_i77
#ISCELL
  mstr_standard tap *
  page93_i78
#ISCELL
  mstr_standard tap *
  page93_i79
#ISCELL
  mstr_standard offpage *
  page93_i8
#ISCELL
  mstr_standard tap *
  page93_i80
#ISCELL
  mstr_standard tap *
  page93_i81
#ISCELL
  mstr_standard tap *
  page93_i82
#ISCELL
  mstr_standard tap *
  page93_i83
#ISCELL
  mstr_standard tap *
  page93_i84
#ISCELL
  mstr_standard tap *
  page93_i85
#ISCELL
  mstr_standard tap *
  page93_i86
#ISCELL
  mstr_standard tap *
  page93_i87
#ISCELL
  mstr_standard tap *
  page93_i88
#ISCELL
  mstr_standard tap *
  page93_i89
#ISCELL
  mstr_symbols vcc_core *
  page93_i9
#ISCELL
  mstr_standard tap *
  page93_i90
#ISCELL
  mstr_standard tap *
  page93_i91
#ISCELL
  mstr_standard tap *
  page93_i92
#ISCELL
  mstr_standard tap *
  page93_i93
#ISCELL
  mstr_standard tap *
  page93_i94
#ISCELL
  mstr_standard tap *
  page93_i95
#ISCELL
  mstr_standard tap *
  page93_i96
#ISCELL
  mstr_standard tap *
  page93_i97
#ISCELL
  mstr_standard tap *
  page93_i98
#ISCELL
  mstr_standard tap *
  page93_i99
#ISCELL
  mstr_misc dns *
  *
#ISCELL
  pure_quanta quanta_title_block_c *
  *
#ISCELL
  mstr_standard offpage *
  page94_i1
#ISCELL
  mstr_standard offpage *
  page94_i10
#ISCELL
  mstr_standard tap *
  page94_i100
#ISCELL
  mstr_standard tap *
  page94_i101
#ISCELL
  mstr_standard tap *
  page94_i102
#ISCELL
  mstr_standard tap *
  page94_i103
#ISCELL
  mstr_standard tap *
  page94_i104
#ISCELL
  mstr_standard tap *
  page94_i105
#ISCELL
  mstr_standard tap *
  page94_i106
#ISCELL
  mstr_standard tap *
  page94_i107
#ISCELL
  mstr_standard tap *
  page94_i108
#ISCELL
  mstr_standard tap *
  page94_i109
#ISCELL
  mstr_standard offpage *
  page94_i11
#ISCELL
  mstr_standard tap *
  page94_i110
#ISCELL
  mstr_standard tap *
  page94_i111
#ISCELL
  mstr_standard tap *
  page94_i112
#ISCELL
  mstr_standard tap *
  page94_i113
#ISCELL
  mstr_standard tap *
  page94_i114
#ISCELL
  mstr_standard tap *
  page94_i115
#ISCELL
  mstr_standard tap *
  page94_i116
#ISCELL
  mstr_standard tap *
  page94_i117
#ISCELL
  mstr_standard tap *
  page94_i118
#ISCELL
  mstr_standard tap *
  page94_i119
#ISCELL
  mstr_standard offpage *
  page94_i12
#ISCELL
  mstr_standard tap *
  page94_i120
#ISCELL
  mstr_standard tap *
  page94_i121
#ISCELL
  mstr_standard tap *
  page94_i122
#ISCELL
  mstr_standard tap *
  page94_i123
#ISCELL
  mstr_standard tap *
  page94_i124
#ISCELL
  mstr_standard tap *
  page94_i125
#ISCELL
  mstr_standard offpage *
  page94_i126
#ISCELL
  mstr_standard offpage *
  page94_i127
#ISCELL
  mstr_symbols gnd *
  page94_i128
#CELL
  pure_quanta q_res *
  page94_i129
#ISCELL
  mstr_standard offpage *
  page94_i13
#ISCELL
  mstr_standard offpage *
  page94_i14
#ISCELL
  mstr_symbols gnd *
  page94_i141
#ISCELL
  mstr_symbols gnd *
  page94_i142
#ISCELL
  mstr_standard offpage *
  page94_i15
#ISCELL
  mstr_standard offpage *
  page94_i16
#ISCELL
  mstr_standard offpage *
  page94_i17
#CELL
  pure_quanta sconn288_ddr506112002kq *
  page94_i177
#ISCELL
  mstr_standard offpage *
  page94_i18
#CELL
  pure_quanta q_cap *
  page94_i185
#ISCELL
  mstr_symbols gnd *
  page94_i186
#ISCELL
  mstr_standard offpage *
  page94_i187
#CELL
  pure_quanta q_res *
  page94_i188
#CELL
  pure_quanta q_res *
  page94_i189
#ISCELL
  mstr_standard offpage *
  page94_i19
#ISCELL
  mstr_symbols vcc_core *
  page94_i190
#ISCELL
  mstr_standard offpage *
  page94_i192
#ISCELL
  mstr_standard offpage *
  page94_i193
#ISCELL
  mstr_standard offpage *
  page94_i194
#ISCELL
  mstr_standard offpage *
  page94_i195
#ISCELL
  mstr_standard tap *
  page94_i196
#ISCELL
  mstr_standard tap *
  page94_i197
#ISCELL
  mstr_standard tap *
  page94_i198
#ISCELL
  mstr_standard tap *
  page94_i199
#ISCELL
  mstr_standard offpage *
  page94_i2
#ISCELL
  mstr_standard offpage *
  page94_i20
#ISCELL
  mstr_standard tap *
  page94_i200
#ISCELL
  mstr_standard tap *
  page94_i201
#ISCELL
  mstr_standard tap *
  page94_i202
#ISCELL
  mstr_standard tap *
  page94_i203
#ISCELL
  mstr_standard tap *
  page94_i204
#ISCELL
  mstr_standard tap *
  page94_i205
#ISCELL
  mstr_standard tap *
  page94_i206
#ISCELL
  mstr_standard tap *
  page94_i207
#ISCELL
  mstr_standard tap *
  page94_i208
#ISCELL
  mstr_standard tap *
  page94_i209
#ISCELL
  mstr_standard offpage *
  page94_i21
#ISCELL
  mstr_standard tap *
  page94_i210
#ISCELL
  mstr_standard tap *
  page94_i211
#ISCELL
  mstr_standard tap *
  page94_i212
#ISCELL
  mstr_standard tap *
  page94_i213
#ISCELL
  mstr_standard tap *
  page94_i214
#ISCELL
  mstr_standard tap *
  page94_i215
#ISCELL
  mstr_standard tap *
  page94_i216
#ISCELL
  mstr_standard tap *
  page94_i217
#ISCELL
  mstr_standard tap *
  page94_i218
#ISCELL
  mstr_standard tap *
  page94_i219
#CELL
  pure_quanta sconn288_ddr506112002kq *
  page94_i22
#ISCELL
  mstr_standard tap *
  page94_i220
#ISCELL
  mstr_standard tap *
  page94_i221
#ISCELL
  mstr_standard tap *
  page94_i222
#ISCELL
  mstr_standard tap *
  page94_i223
#ISCELL
  mstr_standard tap *
  page94_i224
#ISCELL
  mstr_standard tap *
  page94_i225
#ISCELL
  mstr_standard tap *
  page94_i226
#ISCELL
  mstr_standard tap *
  page94_i227
#ISCELL
  mstr_standard tap *
  page94_i228
#ISCELL
  mstr_standard tap *
  page94_i229
#ISCELL
  mstr_standard tap *
  page94_i23
#ISCELL
  mstr_standard tap *
  page94_i230
#ISCELL
  mstr_standard tap *
  page94_i231
#ISCELL
  mstr_standard tap *
  page94_i232
#ISCELL
  mstr_standard tap *
  page94_i233
#ISCELL
  mstr_standard tap *
  page94_i234
#ISCELL
  mstr_standard tap *
  page94_i235
#CELL
  pure_quanta sconn288_ddr506112002kq *
  page94_i236
#ISCELL
  pure_quanta_power gnd *
  page94_i237
#CELL
  pure_quanta q_cap *
  page94_i238
#CELL
  pure_quanta q_cap *
  page94_i239
#ISCELL
  mstr_standard tap *
  page94_i24
#ISCELL
  pure_quanta_power universal_power *
  page94_i240
#ISCELL
  mstr_standard offpage *
  page94_i241
#CELL
  pure_quanta q_res *
  page94_i242
#CELL
  pure_quanta q_res *
  page94_i243
#ISCELL
  mstr_standard offpage *
  page94_i244
#ISCELL
  mstr_standard tap *
  page94_i25
#ISCELL
  mstr_standard tap *
  page94_i26
#ISCELL
  mstr_standard tap *
  page94_i27
#ISCELL
  mstr_standard tap *
  page94_i28
#ISCELL
  mstr_standard tap *
  page94_i29
#ISCELL
  mstr_standard tap *
  page94_i30
#ISCELL
  mstr_standard tap *
  page94_i31
#ISCELL
  mstr_standard tap *
  page94_i32
#ISCELL
  mstr_standard tap *
  page94_i33
#ISCELL
  mstr_standard tap *
  page94_i34
#ISCELL
  mstr_standard tap *
  page94_i35
#ISCELL
  mstr_standard tap *
  page94_i36
#ISCELL
  mstr_standard tap *
  page94_i37
#ISCELL
  mstr_standard tap *
  page94_i38
#ISCELL
  mstr_standard tap *
  page94_i39
#ISCELL
  mstr_standard tap *
  page94_i40
#ISCELL
  mstr_standard tap *
  page94_i41
#ISCELL
  mstr_standard tap *
  page94_i42
#ISCELL
  mstr_standard tap *
  page94_i43
#ISCELL
  mstr_standard tap *
  page94_i44
#ISCELL
  mstr_standard tap *
  page94_i45
#ISCELL
  mstr_standard tap *
  page94_i46
#ISCELL
  mstr_standard tap *
  page94_i47
#ISCELL
  mstr_standard tap *
  page94_i48
#ISCELL
  mstr_standard tap *
  page94_i49
#ISCELL
  mstr_standard tap *
  page94_i50
#ISCELL
  mstr_standard tap *
  page94_i51
#ISCELL
  mstr_standard tap *
  page94_i52
#ISCELL
  mstr_standard tap *
  page94_i53
#ISCELL
  mstr_standard tap *
  page94_i54
#ISCELL
  mstr_standard tap *
  page94_i55
#ISCELL
  mstr_standard tap *
  page94_i56
#ISCELL
  mstr_standard tap *
  page94_i57
#ISCELL
  mstr_standard tap *
  page94_i58
#ISCELL
  mstr_standard tap *
  page94_i59
#ISCELL
  mstr_standard offpage *
  page94_i6
#ISCELL
  mstr_standard tap *
  page94_i60
#ISCELL
  mstr_standard tap *
  page94_i61
#ISCELL
  mstr_standard tap *
  page94_i62
#ISCELL
  mstr_standard tap *
  page94_i63
#ISCELL
  mstr_standard tap *
  page94_i64
#ISCELL
  mstr_standard tap *
  page94_i65
#ISCELL
  mstr_standard tap *
  page94_i66
#ISCELL
  mstr_standard offpage *
  page94_i7
#ISCELL
  mstr_standard offpage *
  page94_i74
#ISCELL
  mstr_standard tap *
  page94_i76
#ISCELL
  mstr_standard tap *
  page94_i77
#ISCELL
  mstr_standard tap *
  page94_i78
#ISCELL
  mstr_standard tap *
  page94_i79
#ISCELL
  mstr_standard offpage *
  page94_i8
#ISCELL
  mstr_standard tap *
  page94_i80
#ISCELL
  mstr_standard tap *
  page94_i81
#ISCELL
  mstr_standard tap *
  page94_i82
#ISCELL
  mstr_standard tap *
  page94_i83
#ISCELL
  mstr_standard tap *
  page94_i84
#ISCELL
  mstr_standard tap *
  page94_i85
#ISCELL
  mstr_standard tap *
  page94_i86
#ISCELL
  mstr_standard tap *
  page94_i87
#ISCELL
  mstr_standard tap *
  page94_i88
#ISCELL
  mstr_standard tap *
  page94_i89
#ISCELL
  mstr_symbols vcc_core *
  page94_i9
#ISCELL
  mstr_standard tap *
  page94_i90
#ISCELL
  mstr_standard tap *
  page94_i91
#ISCELL
  mstr_standard tap *
  page94_i92
#ISCELL
  mstr_standard tap *
  page94_i93
#ISCELL
  mstr_standard tap *
  page94_i94
#ISCELL
  mstr_standard tap *
  page94_i95
#ISCELL
  mstr_standard tap *
  page94_i96
#ISCELL
  mstr_standard tap *
  page94_i97
#ISCELL
  mstr_standard tap *
  page94_i98
#ISCELL
  mstr_standard tap *
  page94_i99
#ISCELL
  mstr_misc dns *
  *
#ISCELL
  pure_quanta quanta_title_block_c *
  *
#ISCELL
  mstr_standard offpage *
  page95_i10
#ISCELL
  mstr_standard tap *
  page95_i100
#ISCELL
  mstr_standard tap *
  page95_i101
#ISCELL
  mstr_standard tap *
  page95_i102
#ISCELL
  mstr_standard tap *
  page95_i103
#ISCELL
  mstr_standard tap *
  page95_i104
#ISCELL
  mstr_standard tap *
  page95_i105
#ISCELL
  mstr_standard tap *
  page95_i106
#ISCELL
  mstr_standard tap *
  page95_i107
#ISCELL
  mstr_standard tap *
  page95_i108
#ISCELL
  mstr_standard tap *
  page95_i109
#ISCELL
  mstr_standard offpage *
  page95_i11
#ISCELL
  mstr_standard tap *
  page95_i110
#ISCELL
  mstr_standard tap *
  page95_i111
#ISCELL
  mstr_standard tap *
  page95_i112
#ISCELL
  mstr_standard tap *
  page95_i113
#ISCELL
  mstr_standard tap *
  page95_i114
#ISCELL
  mstr_standard tap *
  page95_i115
#ISCELL
  mstr_standard tap *
  page95_i116
#ISCELL
  mstr_standard tap *
  page95_i117
#ISCELL
  mstr_standard tap *
  page95_i118
#ISCELL
  mstr_standard tap *
  page95_i119
#ISCELL
  mstr_standard offpage *
  page95_i12
#ISCELL
  mstr_standard tap *
  page95_i120
#ISCELL
  mstr_standard tap *
  page95_i121
#ISCELL
  mstr_standard tap *
  page95_i122
#ISCELL
  mstr_standard tap *
  page95_i123
#ISCELL
  mstr_standard tap *
  page95_i124
#ISCELL
  mstr_standard tap *
  page95_i125
#ISCELL
  mstr_standard offpage *
  page95_i126
#ISCELL
  mstr_standard offpage *
  page95_i127
#ISCELL
  mstr_symbols gnd *
  page95_i128
#CELL
  pure_quanta q_res *
  page95_i129
#ISCELL
  mstr_standard offpage *
  page95_i13
#ISCELL
  mstr_symbols gnd *
  page95_i130
#ISCELL
  mstr_standard offpage *
  page95_i14
#ISCELL
  mstr_symbols gnd *
  page95_i144
#ISCELL
  mstr_standard offpage *
  page95_i15
#ISCELL
  mstr_standard offpage *
  page95_i16
#ISCELL
  mstr_standard offpage *
  page95_i17
#CELL
  pure_quanta sconn288_ddr506112002kq *
  page95_i177
#ISCELL
  mstr_standard offpage *
  page95_i18
#CELL
  pure_quanta q_cap *
  page95_i185
#ISCELL
  mstr_symbols gnd *
  page95_i186
#ISCELL
  mstr_standard offpage *
  page95_i187
#CELL
  pure_quanta q_res *
  page95_i188
#CELL
  pure_quanta q_res *
  page95_i189
#ISCELL
  mstr_standard offpage *
  page95_i19
#ISCELL
  mstr_symbols vcc_core *
  page95_i190
#ISCELL
  mstr_standard tap *
  page95_i191
#ISCELL
  mstr_standard tap *
  page95_i192
#ISCELL
  mstr_standard tap *
  page95_i193
#ISCELL
  mstr_standard offpage *
  page95_i195
#ISCELL
  mstr_standard offpage *
  page95_i196
#ISCELL
  mstr_standard offpage *
  page95_i197
#ISCELL
  mstr_standard offpage *
  page95_i198
#ISCELL
  mstr_standard tap *
  page95_i199
#ISCELL
  mstr_standard offpage *
  page95_i20
#ISCELL
  mstr_standard tap *
  page95_i200
#ISCELL
  mstr_standard tap *
  page95_i201
#ISCELL
  mstr_standard tap *
  page95_i202
#ISCELL
  mstr_standard tap *
  page95_i203
#ISCELL
  mstr_standard tap *
  page95_i204
#ISCELL
  mstr_standard tap *
  page95_i205
#ISCELL
  mstr_standard tap *
  page95_i206
#ISCELL
  mstr_standard tap *
  page95_i207
#ISCELL
  mstr_standard tap *
  page95_i208
#ISCELL
  mstr_standard tap *
  page95_i209
#ISCELL
  mstr_standard offpage *
  page95_i21
#ISCELL
  mstr_standard tap *
  page95_i210
#ISCELL
  mstr_standard tap *
  page95_i211
#ISCELL
  mstr_standard tap *
  page95_i212
#ISCELL
  mstr_standard tap *
  page95_i213
#ISCELL
  mstr_standard tap *
  page95_i214
#ISCELL
  mstr_standard tap *
  page95_i215
#ISCELL
  mstr_standard tap *
  page95_i216
#ISCELL
  mstr_standard tap *
  page95_i217
#ISCELL
  mstr_standard tap *
  page95_i218
#ISCELL
  mstr_standard tap *
  page95_i219
#CELL
  pure_quanta sconn288_ddr506112002kq *
  page95_i22
#ISCELL
  mstr_standard tap *
  page95_i220
#ISCELL
  mstr_standard tap *
  page95_i221
#ISCELL
  mstr_standard tap *
  page95_i222
#ISCELL
  mstr_standard tap *
  page95_i223
#ISCELL
  mstr_standard tap *
  page95_i224
#ISCELL
  mstr_standard tap *
  page95_i225
#ISCELL
  mstr_standard tap *
  page95_i226
#ISCELL
  mstr_standard tap *
  page95_i227
#ISCELL
  mstr_standard tap *
  page95_i228
#ISCELL
  mstr_standard tap *
  page95_i229
#ISCELL
  mstr_standard tap *
  page95_i23
#ISCELL
  mstr_standard tap *
  page95_i230
#ISCELL
  mstr_standard tap *
  page95_i231
#ISCELL
  mstr_standard tap *
  page95_i232
#ISCELL
  mstr_standard tap *
  page95_i233
#ISCELL
  mstr_standard tap *
  page95_i234
#ISCELL
  mstr_standard tap *
  page95_i235
#CELL
  pure_quanta sconn288_ddr506112002kq *
  page95_i236
#ISCELL
  pure_quanta_power gnd *
  page95_i237
#CELL
  pure_quanta q_cap *
  page95_i238
#CELL
  pure_quanta q_cap *
  page95_i239
#ISCELL
  mstr_standard tap *
  page95_i24
#ISCELL
  pure_quanta_power universal_power *
  page95_i240
#ISCELL
  mstr_standard offpage *
  page95_i241
#CELL
  pure_quanta q_res *
  page95_i242
#CELL
  pure_quanta q_res *
  page95_i243
#ISCELL
  mstr_standard offpage *
  page95_i244
#ISCELL
  mstr_standard tap *
  page95_i25
#ISCELL
  mstr_standard tap *
  page95_i26
#ISCELL
  mstr_standard tap *
  page95_i27
#ISCELL
  mstr_standard tap *
  page95_i28
#ISCELL
  mstr_standard tap *
  page95_i29
#ISCELL
  mstr_standard tap *
  page95_i30
#ISCELL
  mstr_standard tap *
  page95_i31
#ISCELL
  mstr_standard tap *
  page95_i32
#ISCELL
  mstr_standard tap *
  page95_i33
#ISCELL
  mstr_standard tap *
  page95_i34
#ISCELL
  mstr_standard tap *
  page95_i35
#ISCELL
  mstr_standard tap *
  page95_i36
#ISCELL
  mstr_standard tap *
  page95_i37
#ISCELL
  mstr_standard tap *
  page95_i38
#ISCELL
  mstr_standard tap *
  page95_i39
#ISCELL
  mstr_standard offpage *
  page95_i4
#ISCELL
  mstr_standard tap *
  page95_i40
#ISCELL
  mstr_standard tap *
  page95_i41
#ISCELL
  mstr_standard tap *
  page95_i42
#ISCELL
  mstr_standard tap *
  page95_i43
#ISCELL
  mstr_standard tap *
  page95_i44
#ISCELL
  mstr_standard tap *
  page95_i45
#ISCELL
  mstr_standard tap *
  page95_i46
#ISCELL
  mstr_standard tap *
  page95_i47
#ISCELL
  mstr_standard tap *
  page95_i48
#ISCELL
  mstr_standard tap *
  page95_i49
#ISCELL
  mstr_standard offpage *
  page95_i5
#ISCELL
  mstr_standard tap *
  page95_i50
#ISCELL
  mstr_standard tap *
  page95_i51
#ISCELL
  mstr_standard tap *
  page95_i52
#ISCELL
  mstr_standard tap *
  page95_i53
#ISCELL
  mstr_standard tap *
  page95_i54
#ISCELL
  mstr_standard tap *
  page95_i55
#ISCELL
  mstr_standard tap *
  page95_i56
#ISCELL
  mstr_standard tap *
  page95_i57
#ISCELL
  mstr_standard tap *
  page95_i58
#ISCELL
  mstr_standard tap *
  page95_i59
#ISCELL
  mstr_standard offpage *
  page95_i6
#ISCELL
  mstr_standard tap *
  page95_i60
#ISCELL
  mstr_standard tap *
  page95_i61
#ISCELL
  mstr_standard tap *
  page95_i62
#ISCELL
  mstr_standard tap *
  page95_i63
#ISCELL
  mstr_standard tap *
  page95_i64
#ISCELL
  mstr_standard tap *
  page95_i65
#ISCELL
  mstr_standard tap *
  page95_i66
#ISCELL
  mstr_standard tap *
  page95_i67
#ISCELL
  mstr_standard tap *
  page95_i68
#ISCELL
  mstr_standard tap *
  page95_i69
#ISCELL
  mstr_standard offpage *
  page95_i7
#ISCELL
  mstr_standard tap *
  page95_i70
#ISCELL
  mstr_standard offpage *
  page95_i78
#ISCELL
  mstr_standard offpage *
  page95_i8
#ISCELL
  mstr_standard tap *
  page95_i80
#ISCELL
  mstr_standard tap *
  page95_i81
#ISCELL
  mstr_standard tap *
  page95_i82
#ISCELL
  mstr_standard tap *
  page95_i83
#ISCELL
  mstr_standard tap *
  page95_i84
#ISCELL
  mstr_standard tap *
  page95_i85
#ISCELL
  mstr_standard tap *
  page95_i86
#ISCELL
  mstr_standard tap *
  page95_i87
#ISCELL
  mstr_standard tap *
  page95_i88
#ISCELL
  mstr_standard tap *
  page95_i89
#ISCELL
  mstr_symbols vcc_core *
  page95_i9
#ISCELL
  mstr_standard tap *
  page95_i90
#ISCELL
  mstr_standard tap *
  page95_i91
#ISCELL
  mstr_standard tap *
  page95_i92
#ISCELL
  mstr_standard tap *
  page95_i93
#ISCELL
  mstr_standard tap *
  page95_i94
#ISCELL
  mstr_standard tap *
  page95_i95
#ISCELL
  mstr_standard tap *
  page95_i96
#ISCELL
  mstr_standard tap *
  page95_i97
#ISCELL
  mstr_standard tap *
  page95_i98
#ISCELL
  mstr_standard tap *
  page95_i99
#ISCELL
  mstr_misc dns *
  *
#ISCELL
  pure_quanta quanta_title_block_c *
  *
#ISCELL
  mstr_standard offpage *
  page96_i1
#ISCELL
  mstr_standard offpage *
  page96_i10
#ISCELL
  mstr_standard tap *
  page96_i100
#ISCELL
  mstr_standard tap *
  page96_i101
#ISCELL
  mstr_standard tap *
  page96_i102
#ISCELL
  mstr_standard tap *
  page96_i103
#ISCELL
  mstr_standard tap *
  page96_i104
#ISCELL
  mstr_standard tap *
  page96_i105
#ISCELL
  mstr_standard tap *
  page96_i106
#ISCELL
  mstr_standard tap *
  page96_i107
#ISCELL
  mstr_standard tap *
  page96_i108
#ISCELL
  mstr_standard tap *
  page96_i109
#ISCELL
  mstr_standard offpage *
  page96_i11
#ISCELL
  mstr_standard tap *
  page96_i110
#ISCELL
  mstr_standard tap *
  page96_i111
#ISCELL
  mstr_standard tap *
  page96_i112
#ISCELL
  mstr_standard tap *
  page96_i113
#ISCELL
  mstr_standard tap *
  page96_i114
#ISCELL
  mstr_standard tap *
  page96_i115
#ISCELL
  mstr_standard tap *
  page96_i116
#ISCELL
  mstr_standard tap *
  page96_i117
#ISCELL
  mstr_standard tap *
  page96_i118
#ISCELL
  mstr_standard tap *
  page96_i119
#ISCELL
  mstr_standard offpage *
  page96_i12
#ISCELL
  mstr_standard tap *
  page96_i120
#ISCELL
  mstr_standard tap *
  page96_i121
#ISCELL
  mstr_standard tap *
  page96_i122
#ISCELL
  mstr_standard tap *
  page96_i123
#ISCELL
  mstr_standard offpage *
  page96_i124
#ISCELL
  mstr_standard offpage *
  page96_i125
#ISCELL
  mstr_symbols gnd *
  page96_i126
#CELL
  pure_quanta q_res *
  page96_i127
#ISCELL
  mstr_standard offpage *
  page96_i128
#ISCELL
  mstr_standard offpage *
  page96_i13
#ISCELL
  mstr_symbols gnd *
  page96_i138
#ISCELL
  mstr_symbols gnd *
  page96_i139
#ISCELL
  mstr_standard offpage *
  page96_i14
#CELL
  pure_quanta sconn288_ddr506112002kq *
  page96_i140
#ISCELL
  mstr_standard offpage *
  page96_i15
#ISCELL
  mstr_standard offpage *
  page96_i16
#ISCELL
  mstr_standard offpage *
  page96_i17
#ISCELL
  mstr_standard offpage *
  page96_i18
#CELL
  pure_quanta q_cap *
  page96_i185
#ISCELL
  mstr_symbols gnd *
  page96_i186
#ISCELL
  mstr_standard offpage *
  page96_i187
#CELL
  pure_quanta q_res *
  page96_i188
#CELL
  pure_quanta q_res *
  page96_i189
#ISCELL
  mstr_standard offpage *
  page96_i19
#ISCELL
  mstr_symbols vcc_core *
  page96_i190
#ISCELL
  mstr_standard offpage *
  page96_i192
#ISCELL
  mstr_standard offpage *
  page96_i193
#ISCELL
  mstr_standard tap *
  page96_i194
#ISCELL
  mstr_standard tap *
  page96_i195
#ISCELL
  mstr_standard tap *
  page96_i196
#ISCELL
  mstr_standard tap *
  page96_i197
#ISCELL
  mstr_standard tap *
  page96_i198
#ISCELL
  mstr_standard tap *
  page96_i199
#ISCELL
  mstr_standard offpage *
  page96_i2
#ISCELL
  mstr_standard offpage *
  page96_i20
#ISCELL
  mstr_standard tap *
  page96_i200
#ISCELL
  mstr_standard tap *
  page96_i201
#ISCELL
  mstr_standard tap *
  page96_i202
#ISCELL
  mstr_standard tap *
  page96_i203
#ISCELL
  mstr_standard tap *
  page96_i204
#ISCELL
  mstr_standard tap *
  page96_i205
#ISCELL
  mstr_standard tap *
  page96_i206
#ISCELL
  mstr_standard tap *
  page96_i207
#ISCELL
  mstr_standard tap *
  page96_i208
#ISCELL
  mstr_standard tap *
  page96_i209
#ISCELL
  mstr_standard offpage *
  page96_i21
#ISCELL
  mstr_standard tap *
  page96_i210
#ISCELL
  mstr_standard tap *
  page96_i211
#ISCELL
  mstr_standard offpage *
  page96_i212
#ISCELL
  mstr_standard offpage *
  page96_i213
#ISCELL
  mstr_standard tap *
  page96_i214
#ISCELL
  mstr_standard tap *
  page96_i215
#ISCELL
  mstr_standard tap *
  page96_i216
#ISCELL
  mstr_standard tap *
  page96_i217
#ISCELL
  mstr_standard tap *
  page96_i218
#ISCELL
  mstr_standard tap *
  page96_i219
#CELL
  pure_quanta sconn288_ddr506112002kq *
  page96_i22
#ISCELL
  mstr_standard tap *
  page96_i220
#ISCELL
  mstr_standard tap *
  page96_i221
#ISCELL
  mstr_standard tap *
  page96_i222
#ISCELL
  mstr_standard tap *
  page96_i223
#ISCELL
  mstr_standard tap *
  page96_i224
#ISCELL
  mstr_standard tap *
  page96_i225
#ISCELL
  mstr_standard tap *
  page96_i226
#ISCELL
  mstr_standard tap *
  page96_i227
#ISCELL
  mstr_standard tap *
  page96_i228
#ISCELL
  mstr_standard tap *
  page96_i229
#ISCELL
  mstr_standard tap *
  page96_i23
#ISCELL
  mstr_standard tap *
  page96_i230
#ISCELL
  mstr_standard tap *
  page96_i231
#ISCELL
  mstr_standard tap *
  page96_i232
#ISCELL
  mstr_standard tap *
  page96_i233
#ISCELL
  mstr_standard tap *
  page96_i234
#ISCELL
  mstr_standard tap *
  page96_i235
#CELL
  pure_quanta sconn288_ddr506112002kq *
  page96_i236
#ISCELL
  pure_quanta_power gnd *
  page96_i237
#CELL
  pure_quanta q_cap *
  page96_i238
#CELL
  pure_quanta q_cap *
  page96_i239
#ISCELL
  mstr_standard tap *
  page96_i24
#ISCELL
  pure_quanta_power universal_power *
  page96_i240
#ISCELL
  mstr_standard offpage *
  page96_i241
#CELL
  pure_quanta q_res *
  page96_i242
#CELL
  pure_quanta q_res *
  page96_i243
#ISCELL
  mstr_standard offpage *
  page96_i244
#ISCELL
  mstr_standard tap *
  page96_i25
#ISCELL
  mstr_standard tap *
  page96_i26
#ISCELL
  mstr_standard tap *
  page96_i27
#ISCELL
  mstr_standard tap *
  page96_i28
#ISCELL
  mstr_standard tap *
  page96_i29
#ISCELL
  mstr_standard tap *
  page96_i30
#ISCELL
  mstr_standard tap *
  page96_i31
#ISCELL
  mstr_standard tap *
  page96_i32
#ISCELL
  mstr_standard tap *
  page96_i33
#ISCELL
  mstr_standard tap *
  page96_i34
#ISCELL
  mstr_standard tap *
  page96_i35
#ISCELL
  mstr_standard tap *
  page96_i36
#ISCELL
  mstr_standard tap *
  page96_i37
#ISCELL
  mstr_standard tap *
  page96_i38
#ISCELL
  mstr_standard tap *
  page96_i39
#ISCELL
  mstr_standard tap *
  page96_i40
#ISCELL
  mstr_standard tap *
  page96_i41
#ISCELL
  mstr_standard tap *
  page96_i42
#ISCELL
  mstr_standard tap *
  page96_i43
#ISCELL
  mstr_standard tap *
  page96_i44
#ISCELL
  mstr_standard tap *
  page96_i45
#ISCELL
  mstr_standard tap *
  page96_i46
#ISCELL
  mstr_standard tap *
  page96_i47
#ISCELL
  mstr_standard tap *
  page96_i48
#ISCELL
  mstr_standard tap *
  page96_i49
#ISCELL
  mstr_standard tap *
  page96_i50
#ISCELL
  mstr_standard tap *
  page96_i51
#ISCELL
  mstr_standard tap *
  page96_i52
#ISCELL
  mstr_standard tap *
  page96_i53
#ISCELL
  mstr_standard tap *
  page96_i54
#ISCELL
  mstr_standard tap *
  page96_i55
#ISCELL
  mstr_standard tap *
  page96_i56
#ISCELL
  mstr_standard tap *
  page96_i57
#ISCELL
  mstr_standard tap *
  page96_i58
#ISCELL
  mstr_standard tap *
  page96_i59
#ISCELL
  mstr_standard offpage *
  page96_i6
#ISCELL
  mstr_standard tap *
  page96_i60
#ISCELL
  mstr_standard tap *
  page96_i61
#ISCELL
  mstr_standard tap *
  page96_i62
#ISCELL
  mstr_standard tap *
  page96_i63
#ISCELL
  mstr_standard offpage *
  page96_i7
#ISCELL
  mstr_standard tap *
  page96_i71
#ISCELL
  mstr_standard tap *
  page96_i72
#ISCELL
  mstr_standard tap *
  page96_i73
#ISCELL
  mstr_standard tap *
  page96_i74
#ISCELL
  mstr_standard tap *
  page96_i75
#ISCELL
  mstr_standard tap *
  page96_i76
#ISCELL
  mstr_standard tap *
  page96_i77
#ISCELL
  mstr_standard tap *
  page96_i78
#ISCELL
  mstr_standard tap *
  page96_i79
#ISCELL
  mstr_standard offpage *
  page96_i8
#ISCELL
  mstr_standard tap *
  page96_i80
#ISCELL
  mstr_standard tap *
  page96_i81
#ISCELL
  mstr_standard tap *
  page96_i82
#ISCELL
  mstr_standard tap *
  page96_i83
#ISCELL
  mstr_standard tap *
  page96_i84
#ISCELL
  mstr_standard tap *
  page96_i85
#ISCELL
  mstr_standard tap *
  page96_i86
#ISCELL
  mstr_standard tap *
  page96_i87
#ISCELL
  mstr_standard tap *
  page96_i88
#ISCELL
  mstr_standard tap *
  page96_i89
#ISCELL
  mstr_symbols vcc_core *
  page96_i9
#ISCELL
  mstr_standard tap *
  page96_i90
#ISCELL
  mstr_standard tap *
  page96_i91
#ISCELL
  mstr_standard tap *
  page96_i92
#ISCELL
  mstr_standard tap *
  page96_i93
#ISCELL
  mstr_standard tap *
  page96_i94
#ISCELL
  mstr_standard tap *
  page96_i95
#ISCELL
  mstr_standard tap *
  page96_i96
#ISCELL
  mstr_standard tap *
  page96_i97
#ISCELL
  mstr_standard tap *
  page96_i98
#ISCELL
  mstr_standard tap *
  page96_i99
#ISCELL
  mstr_misc dns *
  *
#ISCELL
  pure_quanta quanta_title_block_c *
  *
#ISCELL
  mstr_standard offpage *
  page97_i1
#ISCELL
  mstr_standard offpage *
  page97_i10
#ISCELL
  mstr_standard tap *
  page97_i100
#ISCELL
  mstr_standard tap *
  page97_i101
#ISCELL
  mstr_standard tap *
  page97_i102
#ISCELL
  mstr_standard tap *
  page97_i103
#ISCELL
  mstr_standard tap *
  page97_i104
#ISCELL
  mstr_standard tap *
  page97_i105
#ISCELL
  mstr_standard tap *
  page97_i106
#ISCELL
  mstr_standard tap *
  page97_i107
#ISCELL
  mstr_standard tap *
  page97_i108
#ISCELL
  mstr_standard tap *
  page97_i109
#ISCELL
  mstr_standard offpage *
  page97_i11
#ISCELL
  mstr_standard tap *
  page97_i110
#ISCELL
  mstr_standard tap *
  page97_i111
#ISCELL
  mstr_standard tap *
  page97_i112
#ISCELL
  mstr_standard tap *
  page97_i113
#ISCELL
  mstr_standard tap *
  page97_i114
#ISCELL
  mstr_standard tap *
  page97_i115
#ISCELL
  mstr_standard tap *
  page97_i116
#ISCELL
  mstr_standard tap *
  page97_i117
#ISCELL
  mstr_standard tap *
  page97_i118
#ISCELL
  mstr_standard tap *
  page97_i119
#ISCELL
  mstr_standard offpage *
  page97_i12
#ISCELL
  mstr_standard tap *
  page97_i120
#ISCELL
  mstr_standard tap *
  page97_i121
#ISCELL
  mstr_standard tap *
  page97_i122
#ISCELL
  mstr_standard tap *
  page97_i123
#ISCELL
  mstr_standard tap *
  page97_i124
#ISCELL
  mstr_standard tap *
  page97_i125
#ISCELL
  mstr_standard offpage *
  page97_i126
#ISCELL
  mstr_standard offpage *
  page97_i127
#ISCELL
  mstr_symbols gnd *
  page97_i128
#CELL
  pure_quanta q_res *
  page97_i129
#ISCELL
  mstr_standard offpage *
  page97_i13
#ISCELL
  mstr_symbols gnd *
  page97_i130
#ISCELL
  mstr_standard offpage *
  page97_i14
#ISCELL
  mstr_symbols gnd *
  page97_i146
#ISCELL
  mstr_standard offpage *
  page97_i15
#ISCELL
  mstr_standard offpage *
  page97_i16
#ISCELL
  mstr_standard offpage *
  page97_i17
#CELL
  pure_quanta sconn288_ddr506112002kq *
  page97_i177
#ISCELL
  mstr_standard offpage *
  page97_i18
#CELL
  pure_quanta q_cap *
  page97_i185
#ISCELL
  mstr_symbols gnd *
  page97_i186
#ISCELL
  mstr_standard offpage *
  page97_i187
#ISCELL
  mstr_symbols vcc_core *
  page97_i188
#CELL
  pure_quanta q_res *
  page97_i189
#ISCELL
  mstr_standard offpage *
  page97_i19
#CELL
  pure_quanta q_res *
  page97_i190
#CELL
  pure_quanta q_res *
  page97_i191
#ISCELL
  mstr_symbols vcc_core *
  page97_i192
#ISCELL
  mstr_standard offpage *
  page97_i194
#ISCELL
  mstr_standard offpage *
  page97_i195
#ISCELL
  mstr_standard offpage *
  page97_i196
#ISCELL
  mstr_standard offpage *
  page97_i197
#ISCELL
  mstr_standard tap *
  page97_i198
#ISCELL
  mstr_standard tap *
  page97_i199
#ISCELL
  mstr_standard offpage *
  page97_i2
#ISCELL
  mstr_standard offpage *
  page97_i20
#ISCELL
  mstr_standard tap *
  page97_i200
#ISCELL
  mstr_standard tap *
  page97_i201
#ISCELL
  mstr_standard tap *
  page97_i202
#ISCELL
  mstr_standard tap *
  page97_i203
#ISCELL
  mstr_standard tap *
  page97_i204
#ISCELL
  mstr_standard tap *
  page97_i205
#ISCELL
  mstr_standard tap *
  page97_i206
#ISCELL
  mstr_standard tap *
  page97_i207
#ISCELL
  mstr_standard tap *
  page97_i208
#ISCELL
  mstr_standard tap *
  page97_i209
#ISCELL
  mstr_standard offpage *
  page97_i21
#ISCELL
  mstr_standard tap *
  page97_i210
#ISCELL
  mstr_standard tap *
  page97_i211
#ISCELL
  mstr_standard tap *
  page97_i212
#ISCELL
  mstr_standard tap *
  page97_i213
#ISCELL
  mstr_standard tap *
  page97_i214
#ISCELL
  mstr_standard tap *
  page97_i215
#ISCELL
  mstr_standard tap *
  page97_i216
#ISCELL
  mstr_standard tap *
  page97_i217
#ISCELL
  mstr_standard tap *
  page97_i218
#ISCELL
  mstr_standard tap *
  page97_i219
#CELL
  pure_quanta sconn288_ddr506112002kq *
  page97_i22
#ISCELL
  mstr_standard tap *
  page97_i220
#ISCELL
  mstr_standard tap *
  page97_i221
#ISCELL
  mstr_standard tap *
  page97_i222
#ISCELL
  mstr_standard tap *
  page97_i223
#ISCELL
  mstr_standard tap *
  page97_i224
#ISCELL
  mstr_standard tap *
  page97_i225
#ISCELL
  mstr_standard tap *
  page97_i226
#ISCELL
  mstr_standard tap *
  page97_i227
#ISCELL
  mstr_standard tap *
  page97_i228
#ISCELL
  mstr_standard tap *
  page97_i229
#ISCELL
  mstr_standard tap *
  page97_i23
#ISCELL
  mstr_standard tap *
  page97_i230
#ISCELL
  mstr_standard tap *
  page97_i231
#ISCELL
  mstr_standard tap *
  page97_i232
#ISCELL
  mstr_standard tap *
  page97_i233
#ISCELL
  mstr_standard tap *
  page97_i234
#ISCELL
  mstr_standard tap *
  page97_i235
#ISCELL
  mstr_standard tap *
  page97_i236
#ISCELL
  mstr_standard tap *
  page97_i237
#CELL
  pure_quanta sconn288_ddr506112002kq *
  page97_i238
#ISCELL
  pure_quanta_power gnd *
  page97_i239
#ISCELL
  mstr_standard tap *
  page97_i24
#CELL
  pure_quanta q_cap *
  page97_i240
#CELL
  pure_quanta q_cap *
  page97_i241
#ISCELL
  pure_quanta_power universal_power *
  page97_i242
#ISCELL
  mstr_standard offpage *
  page97_i243
#CELL
  pure_quanta q_res *
  page97_i244
#CELL
  pure_quanta q_res *
  page97_i245
#ISCELL
  pure_quanta_power vcc_core *
  page97_i246
#ISCELL
  standard offpage *
  page97_i247
#ISCELL
  standard offpage *
  page97_i248
#ISCELL
  pure_quanta_power vcc_core *
  page97_i249
#ISCELL
  mstr_standard tap *
  page97_i25
#CELL
  pure_quanta q_res *
  page97_i250
#CELL
  pure_quanta q_res *
  page97_i251
#CELL
  pure_quanta q_res *
  page97_i252
#CELL
  pure_quanta schottky_12 *
  page97_i253
#ISCELL
  pure_quanta_power vcc_core *
  page97_i254
#ISCELL
  standard offpage *
  page97_i255
#CELL
  pure_quanta q_res *
  page97_i256
#ISCELL
  mstr_standard offpage *
  page97_i257
#ISCELL
  mstr_standard tap *
  page97_i26
#ISCELL
  mstr_standard tap *
  page97_i27
#ISCELL
  mstr_standard tap *
  page97_i28
#ISCELL
  mstr_standard tap *
  page97_i29
#ISCELL
  mstr_standard tap *
  page97_i30
#ISCELL
  mstr_standard tap *
  page97_i31
#ISCELL
  mstr_standard tap *
  page97_i32
#ISCELL
  mstr_standard tap *
  page97_i33
#ISCELL
  mstr_standard tap *
  page97_i34
#ISCELL
  mstr_standard tap *
  page97_i35
#ISCELL
  mstr_standard tap *
  page97_i36
#ISCELL
  mstr_standard tap *
  page97_i37
#ISCELL
  mstr_standard tap *
  page97_i38
#ISCELL
  mstr_standard tap *
  page97_i46
#ISCELL
  mstr_standard tap *
  page97_i47
#ISCELL
  mstr_standard tap *
  page97_i48
#ISCELL
  mstr_standard tap *
  page97_i49
#ISCELL
  mstr_standard tap *
  page97_i50
#ISCELL
  mstr_standard tap *
  page97_i51
#ISCELL
  mstr_standard tap *
  page97_i52
#ISCELL
  mstr_standard tap *
  page97_i53
#ISCELL
  mstr_standard tap *
  page97_i54
#ISCELL
  mstr_standard tap *
  page97_i55
#ISCELL
  mstr_standard tap *
  page97_i56
#ISCELL
  mstr_standard tap *
  page97_i57
#ISCELL
  mstr_standard tap *
  page97_i58
#ISCELL
  mstr_standard tap *
  page97_i59
#ISCELL
  mstr_standard offpage *
  page97_i6
#ISCELL
  mstr_standard tap *
  page97_i60
#ISCELL
  mstr_standard tap *
  page97_i61
#ISCELL
  mstr_standard tap *
  page97_i62
#ISCELL
  mstr_standard tap *
  page97_i63
#ISCELL
  mstr_standard tap *
  page97_i64
#ISCELL
  mstr_standard tap *
  page97_i65
#ISCELL
  mstr_standard tap *
  page97_i66
#ISCELL
  mstr_standard tap *
  page97_i67
#ISCELL
  mstr_standard tap *
  page97_i68
#ISCELL
  mstr_standard tap *
  page97_i69
#ISCELL
  mstr_standard offpage *
  page97_i7
#ISCELL
  mstr_standard tap *
  page97_i70
#ISCELL
  mstr_standard tap *
  page97_i71
#ISCELL
  mstr_standard tap *
  page97_i72
#ISCELL
  mstr_standard tap *
  page97_i73
#ISCELL
  mstr_standard tap *
  page97_i74
#ISCELL
  mstr_standard tap *
  page97_i75
#ISCELL
  mstr_standard tap *
  page97_i76
#ISCELL
  mstr_standard tap *
  page97_i77
#ISCELL
  mstr_standard tap *
  page97_i78
#ISCELL
  mstr_standard tap *
  page97_i79
#ISCELL
  mstr_symbols vcc_core *
  page97_i8
#ISCELL
  mstr_standard tap *
  page97_i80
#ISCELL
  mstr_standard tap *
  page97_i81
#ISCELL
  mstr_standard tap *
  page97_i82
#ISCELL
  mstr_standard offpage *
  page97_i83
#ISCELL
  mstr_standard tap *
  page97_i85
#ISCELL
  mstr_standard tap *
  page97_i86
#ISCELL
  mstr_standard tap *
  page97_i87
#ISCELL
  mstr_standard tap *
  page97_i88
#ISCELL
  mstr_standard tap *
  page97_i89
#ISCELL
  mstr_standard offpage *
  page97_i9
#ISCELL
  mstr_standard tap *
  page97_i90
#ISCELL
  mstr_standard tap *
  page97_i91
#ISCELL
  mstr_standard tap *
  page97_i92
#ISCELL
  mstr_standard tap *
  page97_i93
#ISCELL
  mstr_standard tap *
  page97_i94
#ISCELL
  mstr_standard tap *
  page97_i95
#ISCELL
  mstr_standard tap *
  page97_i96
#ISCELL
  mstr_standard tap *
  page97_i97
#ISCELL
  mstr_standard tap *
  page97_i98
#ISCELL
  mstr_standard tap *
  page97_i99
#ISCELL
  mstr_misc dns *
  *
#ISCELL
  pure_quanta quanta_title_block_c *
  *
#ISCELL
  mstr_standard offpage *
  page98_i1
#ISCELL
  mstr_standard offpage *
  page98_i10
#ISCELL
  mstr_standard tap *
  page98_i100
#ISCELL
  mstr_standard tap *
  page98_i101
#ISCELL
  mstr_standard tap *
  page98_i102
#ISCELL
  mstr_standard tap *
  page98_i103
#ISCELL
  mstr_standard tap *
  page98_i104
#ISCELL
  mstr_standard tap *
  page98_i105
#ISCELL
  mstr_standard tap *
  page98_i106
#ISCELL
  mstr_standard tap *
  page98_i107
#ISCELL
  mstr_standard tap *
  page98_i108
#ISCELL
  mstr_standard tap *
  page98_i109
#ISCELL
  mstr_standard offpage *
  page98_i11
#ISCELL
  mstr_standard tap *
  page98_i110
#ISCELL
  mstr_standard tap *
  page98_i111
#ISCELL
  mstr_standard tap *
  page98_i112
#ISCELL
  mstr_standard tap *
  page98_i113
#ISCELL
  mstr_standard tap *
  page98_i114
#ISCELL
  mstr_standard tap *
  page98_i115
#ISCELL
  mstr_standard tap *
  page98_i116
#ISCELL
  mstr_standard tap *
  page98_i117
#ISCELL
  mstr_standard tap *
  page98_i118
#ISCELL
  mstr_standard tap *
  page98_i119
#ISCELL
  mstr_standard offpage *
  page98_i12
#ISCELL
  mstr_standard tap *
  page98_i120
#ISCELL
  mstr_standard tap *
  page98_i121
#ISCELL
  mstr_standard tap *
  page98_i122
#ISCELL
  mstr_standard tap *
  page98_i123
#ISCELL
  mstr_standard tap *
  page98_i124
#ISCELL
  mstr_standard offpage *
  page98_i125
#ISCELL
  mstr_symbols gnd *
  page98_i126
#CELL
  pure_quanta q_res *
  page98_i127
#ISCELL
  mstr_symbols gnd *
  page98_i128
#ISCELL
  mstr_standard offpage *
  page98_i129
#ISCELL
  mstr_standard offpage *
  page98_i13
#ISCELL
  mstr_standard offpage *
  page98_i14
#ISCELL
  mstr_standard offpage *
  page98_i15
#ISCELL
  mstr_standard offpage *
  page98_i16
#CELL
  pure_quanta sconn288_ddr506112002kq *
  page98_i160
#ISCELL
  mstr_symbols gnd *
  page98_i161
#ISCELL
  mstr_standard offpage *
  page98_i17
#ISCELL
  mstr_standard offpage *
  page98_i18
#CELL
  pure_quanta q_cap *
  page98_i185
#ISCELL
  mstr_symbols gnd *
  page98_i186
#ISCELL
  mstr_standard offpage *
  page98_i187
#CELL
  pure_quanta q_res *
  page98_i188
#ISCELL
  mstr_symbols vcc_core *
  page98_i189
#ISCELL
  mstr_standard offpage *
  page98_i19
#CELL
  pure_quanta q_res *
  page98_i190
#ISCELL
  mstr_standard tap *
  page98_i191
#ISCELL
  mstr_standard offpage *
  page98_i193
#ISCELL
  mstr_standard offpage *
  page98_i194
#ISCELL
  mstr_standard tap *
  page98_i195
#ISCELL
  mstr_standard tap *
  page98_i196
#ISCELL
  mstr_standard tap *
  page98_i197
#ISCELL
  mstr_standard tap *
  page98_i198
#ISCELL
  mstr_standard tap *
  page98_i199
#ISCELL
  mstr_standard offpage *
  page98_i2
#ISCELL
  mstr_standard offpage *
  page98_i20
#ISCELL
  mstr_standard tap *
  page98_i200
#ISCELL
  mstr_standard tap *
  page98_i201
#ISCELL
  mstr_standard tap *
  page98_i202
#ISCELL
  mstr_standard tap *
  page98_i203
#ISCELL
  mstr_standard tap *
  page98_i204
#ISCELL
  mstr_standard offpage *
  page98_i205
#ISCELL
  mstr_standard offpage *
  page98_i206
#ISCELL
  mstr_standard tap *
  page98_i207
#ISCELL
  mstr_standard tap *
  page98_i208
#ISCELL
  mstr_standard tap *
  page98_i209
#ISCELL
  mstr_standard offpage *
  page98_i21
#ISCELL
  mstr_standard tap *
  page98_i210
#ISCELL
  mstr_standard tap *
  page98_i211
#ISCELL
  mstr_standard tap *
  page98_i212
#ISCELL
  mstr_standard tap *
  page98_i213
#ISCELL
  mstr_standard tap *
  page98_i214
#ISCELL
  mstr_standard tap *
  page98_i215
#ISCELL
  mstr_standard tap *
  page98_i216
#ISCELL
  mstr_standard tap *
  page98_i217
#ISCELL
  mstr_standard tap *
  page98_i218
#ISCELL
  mstr_standard tap *
  page98_i219
#CELL
  pure_quanta sconn288_ddr506112002kq *
  page98_i22
#ISCELL
  mstr_standard tap *
  page98_i220
#ISCELL
  mstr_standard tap *
  page98_i221
#ISCELL
  mstr_standard tap *
  page98_i222
#ISCELL
  mstr_standard tap *
  page98_i223
#ISCELL
  mstr_standard tap *
  page98_i224
#ISCELL
  mstr_standard tap *
  page98_i225
#ISCELL
  mstr_standard tap *
  page98_i226
#ISCELL
  mstr_standard tap *
  page98_i227
#ISCELL
  mstr_standard tap *
  page98_i228
#ISCELL
  mstr_standard tap *
  page98_i229
#ISCELL
  mstr_standard tap *
  page98_i23
#ISCELL
  mstr_standard tap *
  page98_i230
#ISCELL
  mstr_standard tap *
  page98_i231
#ISCELL
  mstr_standard tap *
  page98_i232
#ISCELL
  mstr_standard tap *
  page98_i233
#ISCELL
  mstr_standard tap *
  page98_i234
#ISCELL
  mstr_standard tap *
  page98_i235
#CELL
  pure_quanta sconn288_ddr506112002kq *
  page98_i236
#ISCELL
  pure_quanta_power gnd *
  page98_i237
#CELL
  pure_quanta q_cap *
  page98_i238
#CELL
  pure_quanta q_cap *
  page98_i239
#ISCELL
  mstr_standard tap *
  page98_i24
#ISCELL
  pure_quanta_power universal_power *
  page98_i240
#ISCELL
  mstr_standard offpage *
  page98_i241
#CELL
  pure_quanta q_res *
  page98_i242
#CELL
  pure_quanta q_res *
  page98_i243
#ISCELL
  mstr_standard offpage *
  page98_i244
#ISCELL
  mstr_standard tap *
  page98_i25
#ISCELL
  mstr_standard tap *
  page98_i26
#ISCELL
  mstr_standard tap *
  page98_i27
#ISCELL
  mstr_standard tap *
  page98_i28
#ISCELL
  mstr_standard tap *
  page98_i29
#ISCELL
  mstr_standard tap *
  page98_i30
#ISCELL
  mstr_standard tap *
  page98_i31
#ISCELL
  mstr_standard tap *
  page98_i32
#ISCELL
  mstr_standard tap *
  page98_i33
#ISCELL
  mstr_standard tap *
  page98_i34
#ISCELL
  mstr_standard tap *
  page98_i35
#ISCELL
  mstr_standard tap *
  page98_i36
#ISCELL
  mstr_standard tap *
  page98_i37
#ISCELL
  mstr_standard tap *
  page98_i38
#ISCELL
  mstr_standard tap *
  page98_i39
#ISCELL
  mstr_standard tap *
  page98_i40
#ISCELL
  mstr_standard tap *
  page98_i41
#ISCELL
  mstr_standard tap *
  page98_i42
#ISCELL
  mstr_standard tap *
  page98_i43
#ISCELL
  mstr_standard tap *
  page98_i44
#ISCELL
  mstr_standard tap *
  page98_i45
#ISCELL
  mstr_standard tap *
  page98_i46
#ISCELL
  mstr_standard tap *
  page98_i47
#ISCELL
  mstr_standard tap *
  page98_i48
#ISCELL
  mstr_standard tap *
  page98_i49
#ISCELL
  mstr_standard tap *
  page98_i50
#ISCELL
  mstr_standard tap *
  page98_i51
#ISCELL
  mstr_standard tap *
  page98_i52
#ISCELL
  mstr_standard tap *
  page98_i53
#ISCELL
  mstr_standard tap *
  page98_i54
#ISCELL
  mstr_standard tap *
  page98_i55
#ISCELL
  mstr_standard tap *
  page98_i56
#ISCELL
  mstr_standard tap *
  page98_i57
#ISCELL
  mstr_standard tap *
  page98_i58
#ISCELL
  mstr_standard tap *
  page98_i59
#ISCELL
  mstr_standard offpage *
  page98_i6
#ISCELL
  mstr_standard tap *
  page98_i60
#ISCELL
  mstr_standard tap *
  page98_i61
#ISCELL
  mstr_standard tap *
  page98_i62
#ISCELL
  mstr_standard tap *
  page98_i63
#ISCELL
  mstr_standard tap *
  page98_i64
#ISCELL
  mstr_standard tap *
  page98_i65
#ISCELL
  mstr_standard tap *
  page98_i66
#ISCELL
  mstr_standard tap *
  page98_i67
#ISCELL
  mstr_standard tap *
  page98_i68
#ISCELL
  mstr_standard tap *
  page98_i69
#ISCELL
  mstr_symbols vcc_core *
  page98_i7
#ISCELL
  mstr_standard tap *
  page98_i70
#ISCELL
  mstr_standard tap *
  page98_i71
#ISCELL
  mstr_standard tap *
  page98_i72
#ISCELL
  mstr_standard offpage *
  page98_i79
#ISCELL
  mstr_standard offpage *
  page98_i8
#ISCELL
  mstr_standard tap *
  page98_i81
#ISCELL
  mstr_standard tap *
  page98_i82
#ISCELL
  mstr_standard tap *
  page98_i83
#ISCELL
  mstr_standard tap *
  page98_i84
#ISCELL
  mstr_standard tap *
  page98_i85
#ISCELL
  mstr_standard tap *
  page98_i86
#ISCELL
  mstr_standard tap *
  page98_i87
#ISCELL
  mstr_standard tap *
  page98_i88
#ISCELL
  mstr_standard tap *
  page98_i89
#ISCELL
  mstr_standard offpage *
  page98_i9
#ISCELL
  mstr_standard tap *
  page98_i90
#ISCELL
  mstr_standard tap *
  page98_i91
#ISCELL
  mstr_standard tap *
  page98_i92
#ISCELL
  mstr_standard tap *
  page98_i93
#ISCELL
  mstr_standard tap *
  page98_i94
#ISCELL
  mstr_standard tap *
  page98_i95
#ISCELL
  mstr_standard tap *
  page98_i96
#ISCELL
  mstr_standard tap *
  page98_i97
#ISCELL
  mstr_standard tap *
  page98_i98
#ISCELL
  mstr_standard tap *
  page98_i99
#ISCELL
  mstr_misc dns *
  *
#ISCELL
  pure_quanta quanta_title_block_c *
  *
#ISCELL
  mstr_standard offpage *
  page99_i1
#ISCELL
  mstr_standard offpage *
  page99_i10
#ISCELL
  mstr_standard tap *
  page99_i100
#ISCELL
  mstr_standard tap *
  page99_i101
#ISCELL
  mstr_standard tap *
  page99_i102
#ISCELL
  mstr_standard tap *
  page99_i103
#ISCELL
  mstr_standard tap *
  page99_i104
#ISCELL
  mstr_standard tap *
  page99_i105
#ISCELL
  mstr_standard tap *
  page99_i106
#ISCELL
  mstr_standard tap *
  page99_i107
#ISCELL
  mstr_standard tap *
  page99_i108
#ISCELL
  mstr_standard tap *
  page99_i109
#ISCELL
  mstr_standard offpage *
  page99_i11
#ISCELL
  mstr_standard tap *
  page99_i110
#ISCELL
  mstr_standard tap *
  page99_i111
#ISCELL
  mstr_standard tap *
  page99_i112
#ISCELL
  mstr_standard tap *
  page99_i113
#ISCELL
  mstr_standard tap *
  page99_i114
#ISCELL
  mstr_standard tap *
  page99_i115
#ISCELL
  mstr_standard tap *
  page99_i116
#ISCELL
  mstr_standard tap *
  page99_i117
#ISCELL
  mstr_standard tap *
  page99_i118
#ISCELL
  mstr_standard tap *
  page99_i119
#ISCELL
  mstr_standard offpage *
  page99_i12
#ISCELL
  mstr_standard tap *
  page99_i120
#ISCELL
  mstr_standard tap *
  page99_i121
#ISCELL
  mstr_standard tap *
  page99_i122
#ISCELL
  mstr_standard tap *
  page99_i123
#ISCELL
  mstr_standard tap *
  page99_i124
#ISCELL
  mstr_standard tap *
  page99_i125
#ISCELL
  mstr_standard tap *
  page99_i126
#ISCELL
  mstr_standard tap *
  page99_i127
#ISCELL
  mstr_standard tap *
  page99_i128
#ISCELL
  mstr_standard offpage *
  page99_i129
#ISCELL
  mstr_standard offpage *
  page99_i13
#ISCELL
  mstr_standard offpage *
  page99_i14
#ISCELL
  mstr_standard offpage *
  page99_i146
#ISCELL
  mstr_symbols gnd *
  page99_i147
#CELL
  pure_quanta q_res *
  page99_i148
#ISCELL
  mstr_standard offpage *
  page99_i15
#ISCELL
  mstr_symbols gnd *
  page99_i154
#CELL
  pure_quanta sconn288_ddr506112002kq *
  page99_i155
#ISCELL
  mstr_symbols gnd *
  page99_i156
#ISCELL
  mstr_standard offpage *
  page99_i16
#ISCELL
  mstr_standard offpage *
  page99_i17
#ISCELL
  mstr_standard offpage *
  page99_i18
#CELL
  pure_quanta q_cap *
  page99_i185
#ISCELL
  mstr_symbols gnd *
  page99_i186
#ISCELL
  mstr_standard offpage *
  page99_i187
#CELL
  pure_quanta q_res *
  page99_i188
#ISCELL
  mstr_symbols vcc_core *
  page99_i189
#ISCELL
  mstr_standard offpage *
  page99_i19
#CELL
  pure_quanta q_res *
  page99_i190
#ISCELL
  mstr_standard tap *
  page99_i191
#ISCELL
  mstr_standard tap *
  page99_i193
#ISCELL
  mstr_standard offpage *
  page99_i194
#ISCELL
  mstr_standard offpage *
  page99_i195
#ISCELL
  mstr_standard tap *
  page99_i196
#ISCELL
  mstr_standard tap *
  page99_i197
#ISCELL
  mstr_standard tap *
  page99_i198
#ISCELL
  mstr_standard tap *
  page99_i199
#ISCELL
  mstr_standard offpage *
  page99_i2
#ISCELL
  mstr_standard offpage *
  page99_i20
#ISCELL
  mstr_standard tap *
  page99_i200
#ISCELL
  mstr_standard offpage *
  page99_i201
#ISCELL
  mstr_standard offpage *
  page99_i202
#ISCELL
  mstr_standard tap *
  page99_i203
#ISCELL
  mstr_standard tap *
  page99_i204
#ISCELL
  mstr_standard tap *
  page99_i205
#ISCELL
  mstr_standard tap *
  page99_i206
#ISCELL
  mstr_standard tap *
  page99_i207
#ISCELL
  mstr_standard tap *
  page99_i208
#ISCELL
  mstr_standard tap *
  page99_i209
#ISCELL
  mstr_standard offpage *
  page99_i21
#ISCELL
  mstr_standard tap *
  page99_i210
#ISCELL
  mstr_standard tap *
  page99_i211
#ISCELL
  mstr_standard tap *
  page99_i212
#ISCELL
  mstr_standard tap *
  page99_i213
#ISCELL
  mstr_standard tap *
  page99_i214
#ISCELL
  mstr_standard tap *
  page99_i215
#ISCELL
  mstr_standard tap *
  page99_i216
#ISCELL
  mstr_standard tap *
  page99_i217
#ISCELL
  mstr_standard tap *
  page99_i218
#ISCELL
  mstr_standard tap *
  page99_i219
#CELL
  pure_quanta sconn288_ddr506112002kq *
  page99_i22
#ISCELL
  mstr_standard tap *
  page99_i220
#ISCELL
  mstr_standard tap *
  page99_i221
#ISCELL
  mstr_standard tap *
  page99_i222
#ISCELL
  mstr_standard tap *
  page99_i223
#ISCELL
  mstr_standard tap *
  page99_i224
#ISCELL
  mstr_standard tap *
  page99_i225
#ISCELL
  mstr_standard tap *
  page99_i226
#ISCELL
  mstr_standard tap *
  page99_i227
#ISCELL
  mstr_standard tap *
  page99_i228
#ISCELL
  mstr_standard tap *
  page99_i229
#ISCELL
  mstr_standard tap *
  page99_i23
#ISCELL
  mstr_standard tap *
  page99_i230
#ISCELL
  mstr_standard tap *
  page99_i231
#ISCELL
  mstr_standard tap *
  page99_i232
#ISCELL
  mstr_standard tap *
  page99_i233
#ISCELL
  mstr_standard tap *
  page99_i234
#ISCELL
  mstr_standard tap *
  page99_i235
#CELL
  pure_quanta sconn288_ddr506112002kq *
  page99_i236
#ISCELL
  pure_quanta_power gnd *
  page99_i237
#CELL
  pure_quanta q_cap *
  page99_i238
#CELL
  pure_quanta q_cap *
  page99_i239
#ISCELL
  mstr_standard tap *
  page99_i24
#ISCELL
  pure_quanta_power universal_power *
  page99_i240
#ISCELL
  mstr_standard offpage *
  page99_i241
#CELL
  pure_quanta q_res *
  page99_i242
#CELL
  pure_quanta q_res *
  page99_i243
#ISCELL
  mstr_standard offpage *
  page99_i244
#ISCELL
  mstr_standard tap *
  page99_i25
#ISCELL
  mstr_standard tap *
  page99_i26
#ISCELL
  mstr_standard tap *
  page99_i27
#ISCELL
  mstr_standard tap *
  page99_i28
#ISCELL
  mstr_standard tap *
  page99_i29
#ISCELL
  mstr_standard tap *
  page99_i30
#ISCELL
  mstr_standard tap *
  page99_i31
#ISCELL
  mstr_standard tap *
  page99_i32
#ISCELL
  mstr_standard tap *
  page99_i33
#ISCELL
  mstr_standard tap *
  page99_i34
#ISCELL
  mstr_standard tap *
  page99_i35
#ISCELL
  mstr_standard tap *
  page99_i36
#ISCELL
  mstr_standard tap *
  page99_i37
#ISCELL
  mstr_standard tap *
  page99_i38
#ISCELL
  mstr_standard tap *
  page99_i39
#ISCELL
  mstr_standard tap *
  page99_i40
#ISCELL
  mstr_standard tap *
  page99_i41
#ISCELL
  mstr_standard tap *
  page99_i42
#ISCELL
  mstr_standard tap *
  page99_i43
#ISCELL
  mstr_standard tap *
  page99_i44
#ISCELL
  mstr_standard tap *
  page99_i45
#ISCELL
  mstr_standard tap *
  page99_i46
#ISCELL
  mstr_standard tap *
  page99_i47
#ISCELL
  mstr_standard tap *
  page99_i48
#ISCELL
  mstr_standard tap *
  page99_i49
#ISCELL
  mstr_standard tap *
  page99_i50
#ISCELL
  mstr_standard tap *
  page99_i51
#ISCELL
  mstr_standard tap *
  page99_i52
#ISCELL
  mstr_standard tap *
  page99_i53
#ISCELL
  mstr_standard tap *
  page99_i54
#ISCELL
  mstr_standard tap *
  page99_i55
#ISCELL
  mstr_standard tap *
  page99_i56
#ISCELL
  mstr_standard tap *
  page99_i57
#ISCELL
  mstr_standard tap *
  page99_i58
#ISCELL
  mstr_standard tap *
  page99_i59
#ISCELL
  mstr_symbols vcc_core *
  page99_i6
#ISCELL
  mstr_standard tap *
  page99_i60
#ISCELL
  mstr_standard tap *
  page99_i61
#ISCELL
  mstr_standard tap *
  page99_i62
#ISCELL
  mstr_standard tap *
  page99_i63
#ISCELL
  mstr_standard tap *
  page99_i64
#ISCELL
  mstr_standard tap *
  page99_i65
#ISCELL
  mstr_standard tap *
  page99_i66
#ISCELL
  mstr_standard offpage *
  page99_i7
#ISCELL
  mstr_standard offpage *
  page99_i74
#ISCELL
  mstr_standard tap *
  page99_i79
#ISCELL
  mstr_standard offpage *
  page99_i8
#ISCELL
  mstr_standard tap *
  page99_i80
#ISCELL
  mstr_standard tap *
  page99_i81
#ISCELL
  mstr_standard tap *
  page99_i82
#ISCELL
  mstr_standard tap *
  page99_i83
#ISCELL
  mstr_standard tap *
  page99_i84
#ISCELL
  mstr_standard tap *
  page99_i85
#ISCELL
  mstr_standard tap *
  page99_i86
#ISCELL
  mstr_standard tap *
  page99_i87
#ISCELL
  mstr_standard tap *
  page99_i88
#ISCELL
  mstr_standard tap *
  page99_i89
#ISCELL
  mstr_standard offpage *
  page99_i9
#ISCELL
  mstr_standard tap *
  page99_i90
#ISCELL
  mstr_standard tap *
  page99_i91
#ISCELL
  mstr_standard tap *
  page99_i92
#ISCELL
  mstr_standard tap *
  page99_i93
#ISCELL
  mstr_standard tap *
  page99_i94
#ISCELL
  mstr_standard tap *
  page99_i95
#ISCELL
  mstr_standard tap *
  page99_i96
#ISCELL
  mstr_standard tap *
  page99_i97
#ISCELL
  mstr_standard tap *
  page99_i98
#ISCELL
  mstr_standard tap *
  page99_i99
#ISCELL
  mstr_misc dns *
  *
#ISCELL
  pure_quanta quanta_title_block_c *
  *
#ISCELL
  mstr_standard offpage *
  page100_i1
#ISCELL
  mstr_standard offpage *
  page100_i10
#ISCELL
  mstr_standard tap *
  page100_i107
#ISCELL
  mstr_standard tap *
  page100_i108
#ISCELL
  mstr_standard tap *
  page100_i109
#ISCELL
  mstr_standard offpage *
  page100_i11
#ISCELL
  mstr_standard tap *
  page100_i110
#ISCELL
  mstr_standard tap *
  page100_i111
#ISCELL
  mstr_standard tap *
  page100_i112
#ISCELL
  mstr_standard tap *
  page100_i113
#ISCELL
  mstr_standard tap *
  page100_i114
#ISCELL
  mstr_standard tap *
  page100_i115
#ISCELL
  mstr_standard tap *
  page100_i116
#ISCELL
  mstr_standard tap *
  page100_i117
#ISCELL
  mstr_standard tap *
  page100_i118
#ISCELL
  mstr_standard tap *
  page100_i119
#ISCELL
  mstr_standard tap *
  page100_i12
#ISCELL
  mstr_standard tap *
  page100_i120
#ISCELL
  mstr_standard tap *
  page100_i121
#ISCELL
  mstr_standard tap *
  page100_i122
#ISCELL
  mstr_standard tap *
  page100_i123
#ISCELL
  mstr_standard tap *
  page100_i124
#ISCELL
  mstr_standard tap *
  page100_i125
#ISCELL
  mstr_standard tap *
  page100_i126
#ISCELL
  mstr_standard tap *
  page100_i127
#ISCELL
  mstr_standard tap *
  page100_i128
#ISCELL
  mstr_standard tap *
  page100_i129
#ISCELL
  mstr_standard tap *
  page100_i13
#ISCELL
  mstr_standard tap *
  page100_i130
#ISCELL
  mstr_standard tap *
  page100_i131
#ISCELL
  mstr_standard tap *
  page100_i132
#ISCELL
  mstr_standard tap *
  page100_i133
#ISCELL
  mstr_standard tap *
  page100_i134
#ISCELL
  mstr_standard offpage *
  page100_i135
#ISCELL
  mstr_standard tap *
  page100_i14
#ISCELL
  mstr_symbols gnd *
  page100_i145
#CELL
  pure_quanta q_res *
  page100_i146
#ISCELL
  mstr_symbols gnd *
  page100_i147
#ISCELL
  mstr_standard tap *
  page100_i15
#ISCELL
  mstr_standard tap *
  page100_i16
#CELL
  pure_quanta sconn288_ddr506112002kq *
  page100_i161
#ISCELL
  mstr_symbols gnd *
  page100_i162
#ISCELL
  mstr_standard tap *
  page100_i17
#ISCELL
  mstr_standard tap *
  page100_i18
#CELL
  pure_quanta q_cap *
  page100_i185
#ISCELL
  mstr_symbols gnd *
  page100_i186
#ISCELL
  mstr_standard offpage *
  page100_i187
#CELL
  pure_quanta q_res *
  page100_i188
#ISCELL
  mstr_symbols vcc_core *
  page100_i189
#ISCELL
  mstr_standard tap *
  page100_i19
#CELL
  pure_quanta q_res *
  page100_i190
#ISCELL
  mstr_standard tap *
  page100_i191
#ISCELL
  mstr_standard tap *
  page100_i192
#ISCELL
  mstr_standard tap *
  page100_i193
#ISCELL
  mstr_standard tap *
  page100_i194
#ISCELL
  mstr_standard offpage *
  page100_i196
#ISCELL
  mstr_standard offpage *
  page100_i197
#ISCELL
  mstr_standard tap *
  page100_i198
#ISCELL
  mstr_standard tap *
  page100_i199
#ISCELL
  mstr_standard offpage *
  page100_i2
#ISCELL
  mstr_standard tap *
  page100_i20
#ISCELL
  mstr_standard tap *
  page100_i200
#ISCELL
  mstr_standard tap *
  page100_i201
#ISCELL
  mstr_standard tap *
  page100_i202
#ISCELL
  mstr_standard tap *
  page100_i203
#ISCELL
  mstr_standard tap *
  page100_i204
#ISCELL
  mstr_standard tap *
  page100_i205
#ISCELL
  mstr_standard tap *
  page100_i206
#ISCELL
  mstr_standard tap *
  page100_i207
#ISCELL
  mstr_standard tap *
  page100_i208
#ISCELL
  mstr_standard tap *
  page100_i209
#ISCELL
  mstr_standard tap *
  page100_i21
#ISCELL
  mstr_standard tap *
  page100_i210
#ISCELL
  mstr_standard tap *
  page100_i211
#ISCELL
  mstr_standard tap *
  page100_i212
#ISCELL
  mstr_standard offpage *
  page100_i213
#ISCELL
  mstr_standard offpage *
  page100_i214
#ISCELL
  mstr_standard tap *
  page100_i215
#ISCELL
  mstr_standard tap *
  page100_i216
#ISCELL
  mstr_standard tap *
  page100_i217
#ISCELL
  mstr_standard tap *
  page100_i218
#ISCELL
  mstr_standard tap *
  page100_i219
#ISCELL
  mstr_standard tap *
  page100_i22
#ISCELL
  mstr_standard tap *
  page100_i220
#ISCELL
  mstr_standard tap *
  page100_i221
#ISCELL
  mstr_standard tap *
  page100_i222
#ISCELL
  mstr_standard tap *
  page100_i223
#ISCELL
  mstr_standard tap *
  page100_i224
#ISCELL
  mstr_standard tap *
  page100_i225
#ISCELL
  mstr_standard tap *
  page100_i226
#ISCELL
  mstr_standard tap *
  page100_i227
#ISCELL
  mstr_standard tap *
  page100_i228
#ISCELL
  mstr_standard tap *
  page100_i229
#ISCELL
  mstr_standard tap *
  page100_i23
#ISCELL
  mstr_standard tap *
  page100_i230
#ISCELL
  mstr_standard tap *
  page100_i231
#ISCELL
  mstr_standard tap *
  page100_i232
#ISCELL
  mstr_standard tap *
  page100_i233
#ISCELL
  mstr_standard tap *
  page100_i234
#ISCELL
  mstr_standard tap *
  page100_i235
#CELL
  pure_quanta sconn288_ddr506112002kq *
  page100_i236
#ISCELL
  pure_quanta_power gnd *
  page100_i237
#CELL
  pure_quanta q_cap *
  page100_i238
#CELL
  pure_quanta q_cap *
  page100_i239
#ISCELL
  mstr_standard tap *
  page100_i24
#ISCELL
  pure_quanta_power universal_power *
  page100_i240
#ISCELL
  mstr_standard offpage *
  page100_i241
#CELL
  pure_quanta q_res *
  page100_i242
#CELL
  pure_quanta q_res *
  page100_i243
#ISCELL
  mstr_standard offpage *
  page100_i244
#ISCELL
  mstr_standard tap *
  page100_i25
#ISCELL
  mstr_standard tap *
  page100_i26
#ISCELL
  mstr_standard tap *
  page100_i27
#ISCELL
  mstr_standard offpage *
  page100_i28
#ISCELL
  mstr_standard offpage *
  page100_i29
#ISCELL
  mstr_standard offpage *
  page100_i30
#ISCELL
  mstr_standard offpage *
  page100_i31
#ISCELL
  mstr_standard offpage *
  page100_i32
#ISCELL
  mstr_standard offpage *
  page100_i33
#ISCELL
  mstr_standard offpage *
  page100_i34
#ISCELL
  mstr_standard offpage *
  page100_i35
#ISCELL
  mstr_standard offpage *
  page100_i36
#ISCELL
  mstr_standard tap *
  page100_i37
#ISCELL
  mstr_standard tap *
  page100_i38
#ISCELL
  mstr_standard tap *
  page100_i39
#ISCELL
  mstr_standard offpage *
  page100_i4
#ISCELL
  mstr_standard tap *
  page100_i40
#ISCELL
  mstr_standard tap *
  page100_i41
#ISCELL
  mstr_standard tap *
  page100_i42
#ISCELL
  mstr_standard tap *
  page100_i43
#ISCELL
  mstr_standard offpage *
  page100_i44
#ISCELL
  mstr_standard tap *
  page100_i45
#ISCELL
  mstr_standard tap *
  page100_i46
#ISCELL
  mstr_standard tap *
  page100_i47
#ISCELL
  mstr_standard tap *
  page100_i48
#ISCELL
  mstr_standard tap *
  page100_i49
#ISCELL
  mstr_standard tap *
  page100_i50
#ISCELL
  mstr_standard tap *
  page100_i51
#CELL
  pure_quanta sconn288_ddr506112002kq *
  page100_i52
#ISCELL
  mstr_standard tap *
  page100_i53
#ISCELL
  mstr_standard tap *
  page100_i54
#ISCELL
  mstr_standard tap *
  page100_i55
#ISCELL
  mstr_standard tap *
  page100_i56
#ISCELL
  mstr_standard tap *
  page100_i57
#ISCELL
  mstr_standard tap *
  page100_i58
#ISCELL
  mstr_standard tap *
  page100_i59
#ISCELL
  mstr_standard tap *
  page100_i60
#ISCELL
  mstr_standard tap *
  page100_i61
#ISCELL
  mstr_standard tap *
  page100_i62
#ISCELL
  mstr_standard tap *
  page100_i63
#ISCELL
  mstr_standard tap *
  page100_i64
#ISCELL
  mstr_standard tap *
  page100_i65
#ISCELL
  mstr_standard tap *
  page100_i66
#ISCELL
  mstr_standard tap *
  page100_i67
#ISCELL
  mstr_standard tap *
  page100_i68
#ISCELL
  mstr_standard tap *
  page100_i69
#ISCELL
  mstr_symbols vcc_core *
  page100_i7
#ISCELL
  mstr_standard tap *
  page100_i70
#ISCELL
  mstr_standard tap *
  page100_i71
#ISCELL
  mstr_standard tap *
  page100_i72
#ISCELL
  mstr_standard tap *
  page100_i73
#ISCELL
  mstr_standard tap *
  page100_i74
#ISCELL
  mstr_standard tap *
  page100_i75
#ISCELL
  mstr_standard tap *
  page100_i76
#ISCELL
  mstr_standard tap *
  page100_i77
#ISCELL
  mstr_standard tap *
  page100_i78
#ISCELL
  mstr_standard tap *
  page100_i79
#ISCELL
  mstr_standard offpage *
  page100_i8
#ISCELL
  mstr_standard tap *
  page100_i80
#ISCELL
  mstr_standard tap *
  page100_i81
#ISCELL
  mstr_standard tap *
  page100_i82
#ISCELL
  mstr_standard tap *
  page100_i83
#ISCELL
  mstr_standard tap *
  page100_i84
#ISCELL
  mstr_standard tap *
  page100_i85
#ISCELL
  mstr_standard tap *
  page100_i86
#ISCELL
  mstr_standard tap *
  page100_i87
#ISCELL
  mstr_standard tap *
  page100_i88
#ISCELL
  mstr_standard offpage *
  page100_i9
#ISCELL
  mstr_standard offpage *
  page100_i96
#ISCELL
  mstr_standard offpage *
  page100_i97
#ISCELL
  mstr_misc dns *
  *
#ISCELL
  pure_quanta quanta_title_block_c *
  *
#ISCELL
  mstr_symbols vcc_core *
  page101_i1
#ISCELL
  mstr_standard offpage *
  page101_i10
#ISCELL
  mstr_standard tap *
  page101_i100
#ISCELL
  mstr_standard tap *
  page101_i101
#ISCELL
  mstr_standard tap *
  page101_i102
#ISCELL
  mstr_standard tap *
  page101_i103
#ISCELL
  mstr_standard tap *
  page101_i104
#ISCELL
  mstr_standard tap *
  page101_i105
#ISCELL
  mstr_standard tap *
  page101_i106
#ISCELL
  mstr_standard tap *
  page101_i107
#ISCELL
  mstr_standard tap *
  page101_i108
#ISCELL
  mstr_standard tap *
  page101_i109
#ISCELL
  mstr_standard tap *
  page101_i11
#ISCELL
  mstr_standard tap *
  page101_i110
#ISCELL
  mstr_standard tap *
  page101_i111
#ISCELL
  mstr_standard tap *
  page101_i112
#ISCELL
  mstr_standard tap *
  page101_i113
#ISCELL
  mstr_standard tap *
  page101_i114
#ISCELL
  mstr_standard tap *
  page101_i115
#ISCELL
  mstr_standard tap *
  page101_i116
#ISCELL
  mstr_standard tap *
  page101_i117
#ISCELL
  mstr_standard tap *
  page101_i118
#ISCELL
  mstr_standard tap *
  page101_i119
#ISCELL
  mstr_standard tap *
  page101_i12
#ISCELL
  mstr_standard tap *
  page101_i120
#ISCELL
  mstr_standard tap *
  page101_i121
#ISCELL
  mstr_standard tap *
  page101_i122
#ISCELL
  mstr_standard tap *
  page101_i123
#ISCELL
  mstr_standard tap *
  page101_i124
#ISCELL
  mstr_standard offpage *
  page101_i125
#ISCELL
  mstr_symbols gnd *
  page101_i126
#CELL
  pure_quanta q_res *
  page101_i127
#ISCELL
  mstr_standard offpage *
  page101_i128
#ISCELL
  mstr_standard tap *
  page101_i13
#ISCELL
  mstr_standard tap *
  page101_i14
#ISCELL
  mstr_symbols gnd *
  page101_i140
#ISCELL
  mstr_symbols gnd *
  page101_i141
#ISCELL
  mstr_standard tap *
  page101_i15
#ISCELL
  mstr_standard tap *
  page101_i16
#ISCELL
  mstr_standard tap *
  page101_i17
#CELL
  pure_quanta sconn288_ddr506112002kq *
  page101_i175
#ISCELL
  mstr_standard tap *
  page101_i18
#CELL
  pure_quanta q_cap *
  page101_i185
#ISCELL
  mstr_symbols gnd *
  page101_i186
#ISCELL
  mstr_standard offpage *
  page101_i187
#CELL
  pure_quanta q_res *
  page101_i188
#ISCELL
  mstr_symbols vcc_core *
  page101_i189
#ISCELL
  mstr_standard tap *
  page101_i19
#CELL
  pure_quanta q_res *
  page101_i190
#ISCELL
  mstr_standard tap *
  page101_i192
#ISCELL
  mstr_standard tap *
  page101_i193
#ISCELL
  mstr_standard offpage *
  page101_i194
#ISCELL
  mstr_standard offpage *
  page101_i195
#ISCELL
  mstr_standard offpage *
  page101_i196
#ISCELL
  mstr_standard offpage *
  page101_i197
#ISCELL
  mstr_standard tap *
  page101_i198
#ISCELL
  mstr_standard tap *
  page101_i199
#ISCELL
  mstr_standard offpage *
  page101_i2
#ISCELL
  mstr_standard tap *
  page101_i20
#ISCELL
  mstr_standard tap *
  page101_i200
#ISCELL
  mstr_standard tap *
  page101_i201
#ISCELL
  mstr_standard tap *
  page101_i202
#ISCELL
  mstr_standard tap *
  page101_i203
#ISCELL
  mstr_standard tap *
  page101_i204
#ISCELL
  mstr_standard tap *
  page101_i205
#ISCELL
  mstr_standard tap *
  page101_i206
#ISCELL
  mstr_standard tap *
  page101_i207
#ISCELL
  mstr_standard tap *
  page101_i208
#ISCELL
  mstr_standard tap *
  page101_i209
#ISCELL
  mstr_standard tap *
  page101_i21
#ISCELL
  mstr_standard tap *
  page101_i210
#ISCELL
  mstr_standard tap *
  page101_i211
#ISCELL
  mstr_standard tap *
  page101_i212
#ISCELL
  mstr_standard tap *
  page101_i213
#ISCELL
  mstr_standard tap *
  page101_i214
#ISCELL
  mstr_standard tap *
  page101_i215
#ISCELL
  mstr_standard tap *
  page101_i216
#ISCELL
  mstr_standard tap *
  page101_i217
#ISCELL
  mstr_standard tap *
  page101_i218
#ISCELL
  mstr_standard tap *
  page101_i219
#ISCELL
  mstr_standard tap *
  page101_i22
#ISCELL
  mstr_standard tap *
  page101_i220
#ISCELL
  mstr_standard tap *
  page101_i221
#ISCELL
  mstr_standard tap *
  page101_i222
#ISCELL
  mstr_standard tap *
  page101_i223
#ISCELL
  mstr_standard tap *
  page101_i224
#ISCELL
  mstr_standard tap *
  page101_i225
#ISCELL
  mstr_standard tap *
  page101_i226
#ISCELL
  mstr_standard tap *
  page101_i227
#ISCELL
  mstr_standard tap *
  page101_i228
#ISCELL
  mstr_standard tap *
  page101_i229
#ISCELL
  mstr_standard tap *
  page101_i23
#ISCELL
  mstr_standard tap *
  page101_i230
#ISCELL
  mstr_standard tap *
  page101_i231
#ISCELL
  mstr_standard tap *
  page101_i232
#ISCELL
  mstr_standard tap *
  page101_i233
#ISCELL
  mstr_standard tap *
  page101_i234
#ISCELL
  mstr_standard tap *
  page101_i235
#CELL
  pure_quanta sconn288_ddr506112002kq *
  page101_i236
#ISCELL
  pure_quanta_power gnd *
  page101_i237
#CELL
  pure_quanta q_cap *
  page101_i238
#CELL
  pure_quanta q_cap *
  page101_i239
#ISCELL
  mstr_standard tap *
  page101_i24
#ISCELL
  pure_quanta_power universal_power *
  page101_i240
#ISCELL
  mstr_standard offpage *
  page101_i241
#CELL
  pure_quanta q_res *
  page101_i242
#CELL
  pure_quanta q_res *
  page101_i243
#ISCELL
  mstr_standard offpage *
  page101_i244
#ISCELL
  mstr_standard offpage *
  page101_i25
#ISCELL
  mstr_standard offpage *
  page101_i26
#ISCELL
  mstr_standard offpage *
  page101_i27
#ISCELL
  mstr_standard offpage *
  page101_i28
#ISCELL
  mstr_standard offpage *
  page101_i29
#ISCELL
  mstr_standard offpage *
  page101_i3
#ISCELL
  mstr_standard offpage *
  page101_i30
#ISCELL
  mstr_standard offpage *
  page101_i31
#ISCELL
  mstr_standard offpage *
  page101_i32
#ISCELL
  mstr_standard offpage *
  page101_i33
#ISCELL
  mstr_standard tap *
  page101_i34
#ISCELL
  mstr_standard tap *
  page101_i35
#ISCELL
  mstr_standard tap *
  page101_i36
#ISCELL
  mstr_standard tap *
  page101_i37
#ISCELL
  mstr_standard tap *
  page101_i38
#ISCELL
  mstr_standard tap *
  page101_i39
#ISCELL
  mstr_standard tap *
  page101_i40
#ISCELL
  mstr_standard offpage *
  page101_i41
#ISCELL
  mstr_standard offpage *
  page101_i42
#ISCELL
  mstr_standard tap *
  page101_i43
#ISCELL
  mstr_standard tap *
  page101_i44
#ISCELL
  mstr_standard tap *
  page101_i45
#ISCELL
  mstr_standard tap *
  page101_i46
#ISCELL
  mstr_standard tap *
  page101_i47
#ISCELL
  mstr_standard tap *
  page101_i48
#ISCELL
  mstr_standard tap *
  page101_i49
#ISCELL
  mstr_standard tap *
  page101_i50
#ISCELL
  mstr_standard tap *
  page101_i51
#CELL
  pure_quanta sconn288_ddr506112002kq *
  page101_i52
#ISCELL
  mstr_standard tap *
  page101_i53
#ISCELL
  mstr_standard tap *
  page101_i54
#ISCELL
  mstr_standard tap *
  page101_i55
#ISCELL
  mstr_standard tap *
  page101_i56
#ISCELL
  mstr_standard tap *
  page101_i57
#ISCELL
  mstr_standard tap *
  page101_i58
#ISCELL
  mstr_standard tap *
  page101_i59
#ISCELL
  mstr_standard tap *
  page101_i60
#ISCELL
  mstr_standard tap *
  page101_i61
#ISCELL
  mstr_standard tap *
  page101_i62
#ISCELL
  mstr_standard tap *
  page101_i63
#ISCELL
  mstr_standard tap *
  page101_i64
#ISCELL
  mstr_standard tap *
  page101_i65
#ISCELL
  mstr_standard tap *
  page101_i66
#ISCELL
  mstr_standard tap *
  page101_i67
#ISCELL
  mstr_standard tap *
  page101_i68
#ISCELL
  mstr_standard tap *
  page101_i69
#ISCELL
  mstr_standard offpage *
  page101_i7
#ISCELL
  mstr_standard tap *
  page101_i70
#ISCELL
  mstr_standard tap *
  page101_i71
#ISCELL
  mstr_standard tap *
  page101_i72
#ISCELL
  mstr_standard tap *
  page101_i73
#ISCELL
  mstr_standard tap *
  page101_i74
#ISCELL
  mstr_standard tap *
  page101_i75
#ISCELL
  mstr_standard tap *
  page101_i76
#ISCELL
  mstr_standard tap *
  page101_i77
#ISCELL
  mstr_standard tap *
  page101_i78
#ISCELL
  mstr_standard tap *
  page101_i79
#ISCELL
  mstr_standard offpage *
  page101_i8
#ISCELL
  mstr_standard tap *
  page101_i80
#ISCELL
  mstr_standard tap *
  page101_i81
#ISCELL
  mstr_standard tap *
  page101_i82
#ISCELL
  mstr_standard tap *
  page101_i83
#ISCELL
  mstr_standard tap *
  page101_i84
#ISCELL
  mstr_standard tap *
  page101_i85
#ISCELL
  mstr_standard tap *
  page101_i86
#ISCELL
  mstr_standard offpage *
  page101_i9
#ISCELL
  mstr_standard offpage *
  page101_i93
#ISCELL
  mstr_standard tap *
  page101_i95
#ISCELL
  mstr_standard tap *
  page101_i96
#ISCELL
  mstr_standard tap *
  page101_i97
#ISCELL
  mstr_standard tap *
  page101_i98
#ISCELL
  mstr_standard tap *
  page101_i99
#ISCELL
  mstr_misc dns *
  *
#ISCELL
  pure_quanta quanta_title_block_c *
  *
#ISCELL
  mstr_standard offpage *
  page102_i1
#ISCELL
  mstr_standard offpage *
  page102_i10
#ISCELL
  mstr_standard tap *
  page102_i100
#ISCELL
  mstr_standard tap *
  page102_i101
#ISCELL
  mstr_standard tap *
  page102_i102
#ISCELL
  mstr_standard tap *
  page102_i103
#ISCELL
  mstr_standard tap *
  page102_i104
#ISCELL
  mstr_standard tap *
  page102_i105
#ISCELL
  mstr_standard tap *
  page102_i106
#ISCELL
  mstr_standard tap *
  page102_i107
#ISCELL
  mstr_standard tap *
  page102_i108
#ISCELL
  mstr_standard tap *
  page102_i109
#ISCELL
  mstr_standard offpage *
  page102_i11
#ISCELL
  mstr_standard tap *
  page102_i110
#ISCELL
  mstr_standard tap *
  page102_i111
#ISCELL
  mstr_standard tap *
  page102_i112
#ISCELL
  mstr_standard tap *
  page102_i113
#ISCELL
  mstr_standard tap *
  page102_i114
#ISCELL
  mstr_standard tap *
  page102_i115
#ISCELL
  mstr_standard tap *
  page102_i116
#ISCELL
  mstr_standard tap *
  page102_i117
#ISCELL
  mstr_standard tap *
  page102_i118
#ISCELL
  mstr_standard tap *
  page102_i119
#ISCELL
  mstr_standard offpage *
  page102_i12
#ISCELL
  mstr_standard tap *
  page102_i120
#ISCELL
  mstr_standard tap *
  page102_i121
#ISCELL
  mstr_standard tap *
  page102_i122
#ISCELL
  mstr_standard tap *
  page102_i123
#ISCELL
  mstr_standard tap *
  page102_i124
#ISCELL
  mstr_standard tap *
  page102_i125
#ISCELL
  mstr_standard offpage *
  page102_i126
#ISCELL
  mstr_standard offpage *
  page102_i127
#ISCELL
  mstr_symbols gnd *
  page102_i128
#CELL
  pure_quanta q_res *
  page102_i129
#ISCELL
  mstr_standard offpage *
  page102_i13
#ISCELL
  mstr_standard offpage *
  page102_i14
#ISCELL
  mstr_symbols gnd *
  page102_i140
#ISCELL
  mstr_symbols gnd *
  page102_i141
#CELL
  pure_quanta sconn288_ddr506112002kq *
  page102_i142
#ISCELL
  mstr_standard offpage *
  page102_i15
#ISCELL
  mstr_standard offpage *
  page102_i16
#ISCELL
  mstr_standard offpage *
  page102_i17
#ISCELL
  mstr_standard offpage *
  page102_i18
#CELL
  pure_quanta q_cap *
  page102_i185
#ISCELL
  mstr_symbols gnd *
  page102_i186
#ISCELL
  mstr_standard offpage *
  page102_i187
#CELL
  pure_quanta q_res *
  page102_i188
#ISCELL
  mstr_symbols vcc_core *
  page102_i189
#ISCELL
  mstr_standard offpage *
  page102_i19
#CELL
  pure_quanta q_res *
  page102_i190
#ISCELL
  mstr_standard tap *
  page102_i191
#ISCELL
  mstr_standard tap *
  page102_i193
#ISCELL
  mstr_standard offpage *
  page102_i194
#ISCELL
  mstr_standard offpage *
  page102_i195
#ISCELL
  mstr_standard offpage *
  page102_i196
#ISCELL
  mstr_standard offpage *
  page102_i197
#ISCELL
  mstr_standard tap *
  page102_i198
#ISCELL
  mstr_standard tap *
  page102_i199
#ISCELL
  mstr_standard offpage *
  page102_i2
#ISCELL
  mstr_standard offpage *
  page102_i20
#ISCELL
  mstr_standard tap *
  page102_i200
#ISCELL
  mstr_standard tap *
  page102_i201
#ISCELL
  mstr_standard tap *
  page102_i202
#ISCELL
  mstr_standard tap *
  page102_i203
#ISCELL
  mstr_standard tap *
  page102_i204
#ISCELL
  mstr_standard tap *
  page102_i205
#ISCELL
  mstr_standard tap *
  page102_i206
#ISCELL
  mstr_standard tap *
  page102_i207
#ISCELL
  mstr_standard tap *
  page102_i208
#ISCELL
  mstr_standard tap *
  page102_i209
#ISCELL
  mstr_standard offpage *
  page102_i21
#ISCELL
  mstr_standard tap *
  page102_i210
#ISCELL
  mstr_standard tap *
  page102_i211
#ISCELL
  mstr_standard tap *
  page102_i212
#ISCELL
  mstr_standard tap *
  page102_i213
#ISCELL
  mstr_standard tap *
  page102_i214
#ISCELL
  mstr_standard tap *
  page102_i215
#ISCELL
  mstr_standard tap *
  page102_i216
#ISCELL
  mstr_standard tap *
  page102_i217
#ISCELL
  mstr_standard tap *
  page102_i218
#ISCELL
  mstr_standard tap *
  page102_i219
#CELL
  pure_quanta sconn288_ddr506112002kq *
  page102_i22
#ISCELL
  mstr_standard tap *
  page102_i220
#ISCELL
  mstr_standard tap *
  page102_i221
#ISCELL
  mstr_standard tap *
  page102_i222
#ISCELL
  mstr_standard tap *
  page102_i223
#ISCELL
  mstr_standard tap *
  page102_i224
#ISCELL
  mstr_standard tap *
  page102_i225
#ISCELL
  mstr_standard tap *
  page102_i226
#ISCELL
  mstr_standard tap *
  page102_i227
#ISCELL
  mstr_standard tap *
  page102_i228
#ISCELL
  mstr_standard tap *
  page102_i229
#ISCELL
  mstr_standard tap *
  page102_i23
#ISCELL
  mstr_standard tap *
  page102_i230
#ISCELL
  mstr_standard tap *
  page102_i231
#ISCELL
  mstr_standard tap *
  page102_i232
#ISCELL
  mstr_standard tap *
  page102_i233
#ISCELL
  mstr_standard tap *
  page102_i234
#ISCELL
  mstr_standard tap *
  page102_i235
#CELL
  pure_quanta sconn288_ddr506112002kq *
  page102_i236
#ISCELL
  pure_quanta_power gnd *
  page102_i237
#CELL
  pure_quanta q_cap *
  page102_i238
#CELL
  pure_quanta q_cap *
  page102_i239
#ISCELL
  mstr_standard tap *
  page102_i24
#ISCELL
  pure_quanta_power universal_power *
  page102_i240
#ISCELL
  mstr_standard offpage *
  page102_i241
#CELL
  pure_quanta q_res *
  page102_i242
#CELL
  pure_quanta q_res *
  page102_i243
#ISCELL
  mstr_standard offpage *
  page102_i244
#ISCELL
  mstr_standard tap *
  page102_i25
#ISCELL
  mstr_standard tap *
  page102_i26
#ISCELL
  mstr_standard tap *
  page102_i27
#ISCELL
  mstr_standard tap *
  page102_i28
#ISCELL
  mstr_standard tap *
  page102_i29
#ISCELL
  mstr_standard tap *
  page102_i30
#ISCELL
  mstr_standard tap *
  page102_i31
#ISCELL
  mstr_standard tap *
  page102_i32
#ISCELL
  mstr_standard tap *
  page102_i33
#ISCELL
  mstr_standard tap *
  page102_i34
#ISCELL
  mstr_standard tap *
  page102_i35
#ISCELL
  mstr_standard tap *
  page102_i36
#ISCELL
  mstr_standard tap *
  page102_i37
#ISCELL
  mstr_standard tap *
  page102_i38
#ISCELL
  mstr_standard tap *
  page102_i39
#ISCELL
  mstr_standard tap *
  page102_i40
#ISCELL
  mstr_standard tap *
  page102_i41
#ISCELL
  mstr_standard tap *
  page102_i42
#ISCELL
  mstr_standard tap *
  page102_i43
#ISCELL
  mstr_standard tap *
  page102_i44
#ISCELL
  mstr_standard tap *
  page102_i45
#ISCELL
  mstr_standard tap *
  page102_i46
#ISCELL
  mstr_standard tap *
  page102_i47
#ISCELL
  mstr_standard tap *
  page102_i48
#ISCELL
  mstr_standard tap *
  page102_i49
#ISCELL
  mstr_symbols vcc_core *
  page102_i5
#ISCELL
  mstr_standard tap *
  page102_i50
#ISCELL
  mstr_standard tap *
  page102_i51
#ISCELL
  mstr_standard tap *
  page102_i52
#ISCELL
  mstr_standard tap *
  page102_i53
#ISCELL
  mstr_standard tap *
  page102_i54
#ISCELL
  mstr_standard tap *
  page102_i55
#ISCELL
  mstr_standard tap *
  page102_i56
#ISCELL
  mstr_standard tap *
  page102_i57
#ISCELL
  mstr_standard tap *
  page102_i58
#ISCELL
  mstr_standard tap *
  page102_i59
#ISCELL
  mstr_standard offpage *
  page102_i6
#ISCELL
  mstr_standard tap *
  page102_i60
#ISCELL
  mstr_standard tap *
  page102_i61
#ISCELL
  mstr_standard tap *
  page102_i62
#ISCELL
  mstr_standard tap *
  page102_i63
#ISCELL
  mstr_standard tap *
  page102_i64
#ISCELL
  mstr_standard tap *
  page102_i65
#ISCELL
  mstr_standard tap *
  page102_i66
#ISCELL
  mstr_standard offpage *
  page102_i73
#ISCELL
  mstr_standard tap *
  page102_i76
#ISCELL
  mstr_standard tap *
  page102_i77
#ISCELL
  mstr_standard tap *
  page102_i78
#ISCELL
  mstr_standard tap *
  page102_i79
#ISCELL
  mstr_standard offpage *
  page102_i8
#ISCELL
  mstr_standard tap *
  page102_i80
#ISCELL
  mstr_standard tap *
  page102_i81
#ISCELL
  mstr_standard tap *
  page102_i82
#ISCELL
  mstr_standard tap *
  page102_i83
#ISCELL
  mstr_standard tap *
  page102_i84
#ISCELL
  mstr_standard tap *
  page102_i85
#ISCELL
  mstr_standard tap *
  page102_i86
#ISCELL
  mstr_standard tap *
  page102_i87
#ISCELL
  mstr_standard tap *
  page102_i88
#ISCELL
  mstr_standard tap *
  page102_i89
#ISCELL
  mstr_standard offpage *
  page102_i9
#ISCELL
  mstr_standard tap *
  page102_i90
#ISCELL
  mstr_standard tap *
  page102_i91
#ISCELL
  mstr_standard tap *
  page102_i92
#ISCELL
  mstr_standard tap *
  page102_i93
#ISCELL
  mstr_standard tap *
  page102_i94
#ISCELL
  mstr_standard tap *
  page102_i95
#ISCELL
  mstr_standard tap *
  page102_i96
#ISCELL
  mstr_standard tap *
  page102_i97
#ISCELL
  mstr_standard tap *
  page102_i98
#ISCELL
  mstr_standard tap *
  page102_i99
#ISCELL
  mstr_misc dns *
  *
#ISCELL
  pure_quanta quanta_title_block_c *
  *
#ISCELL
  mstr_standard offpage *
  page103_i1
#ISCELL
  mstr_standard offpage *
  page103_i10
#ISCELL
  mstr_standard tap *
  page103_i100
#ISCELL
  mstr_standard tap *
  page103_i101
#ISCELL
  mstr_standard tap *
  page103_i102
#ISCELL
  mstr_standard tap *
  page103_i103
#ISCELL
  mstr_standard tap *
  page103_i104
#ISCELL
  mstr_standard tap *
  page103_i105
#ISCELL
  mstr_standard tap *
  page103_i106
#ISCELL
  mstr_standard tap *
  page103_i107
#ISCELL
  mstr_standard tap *
  page103_i108
#ISCELL
  mstr_standard tap *
  page103_i109
#ISCELL
  mstr_standard offpage *
  page103_i11
#ISCELL
  mstr_standard tap *
  page103_i110
#ISCELL
  mstr_standard tap *
  page103_i111
#ISCELL
  mstr_standard tap *
  page103_i112
#ISCELL
  mstr_standard tap *
  page103_i113
#ISCELL
  mstr_standard tap *
  page103_i114
#ISCELL
  mstr_standard tap *
  page103_i115
#ISCELL
  mstr_standard tap *
  page103_i116
#ISCELL
  mstr_standard tap *
  page103_i117
#ISCELL
  mstr_standard tap *
  page103_i118
#ISCELL
  mstr_standard tap *
  page103_i119
#ISCELL
  mstr_standard offpage *
  page103_i12
#ISCELL
  mstr_standard tap *
  page103_i120
#ISCELL
  mstr_standard tap *
  page103_i121
#ISCELL
  mstr_standard tap *
  page103_i122
#ISCELL
  mstr_standard tap *
  page103_i123
#ISCELL
  mstr_standard tap *
  page103_i124
#ISCELL
  mstr_standard tap *
  page103_i125
#ISCELL
  mstr_standard offpage *
  page103_i126
#ISCELL
  mstr_standard offpage *
  page103_i127
#ISCELL
  mstr_symbols gnd *
  page103_i128
#CELL
  pure_quanta q_res *
  page103_i129
#ISCELL
  mstr_standard offpage *
  page103_i13
#ISCELL
  mstr_standard offpage *
  page103_i14
#ISCELL
  mstr_symbols gnd *
  page103_i140
#ISCELL
  mstr_symbols gnd *
  page103_i141
#CELL
  pure_quanta sconn288_ddr506112002kq *
  page103_i142
#ISCELL
  mstr_standard offpage *
  page103_i15
#ISCELL
  mstr_standard offpage *
  page103_i16
#ISCELL
  mstr_standard offpage *
  page103_i17
#ISCELL
  mstr_standard offpage *
  page103_i18
#CELL
  pure_quanta q_cap *
  page103_i185
#ISCELL
  mstr_symbols gnd *
  page103_i186
#ISCELL
  mstr_standard offpage *
  page103_i187
#CELL
  pure_quanta q_res *
  page103_i188
#CELL
  pure_quanta q_res *
  page103_i189
#ISCELL
  mstr_standard offpage *
  page103_i19
#ISCELL
  mstr_symbols vcc_core *
  page103_i190
#ISCELL
  mstr_symbols vcc_core *
  page103_i191
#CELL
  pure_quanta q_res *
  page103_i192
#ISCELL
  mstr_standard offpage *
  page103_i194
#ISCELL
  mstr_standard offpage *
  page103_i195
#ISCELL
  mstr_standard offpage *
  page103_i196
#ISCELL
  mstr_standard offpage *
  page103_i197
#ISCELL
  mstr_standard tap *
  page103_i198
#ISCELL
  mstr_standard tap *
  page103_i199
#ISCELL
  mstr_standard offpage *
  page103_i2
#ISCELL
  mstr_standard offpage *
  page103_i20
#ISCELL
  mstr_standard tap *
  page103_i200
#ISCELL
  mstr_standard tap *
  page103_i201
#ISCELL
  mstr_standard tap *
  page103_i202
#ISCELL
  mstr_standard tap *
  page103_i203
#ISCELL
  mstr_standard tap *
  page103_i204
#ISCELL
  mstr_standard tap *
  page103_i205
#ISCELL
  mstr_standard tap *
  page103_i206
#ISCELL
  mstr_standard tap *
  page103_i207
#ISCELL
  mstr_standard tap *
  page103_i208
#ISCELL
  mstr_standard tap *
  page103_i209
#ISCELL
  mstr_standard offpage *
  page103_i21
#ISCELL
  mstr_standard tap *
  page103_i210
#ISCELL
  mstr_standard tap *
  page103_i211
#ISCELL
  mstr_standard tap *
  page103_i212
#ISCELL
  mstr_standard tap *
  page103_i213
#ISCELL
  mstr_standard tap *
  page103_i214
#ISCELL
  mstr_standard tap *
  page103_i215
#ISCELL
  mstr_standard tap *
  page103_i216
#ISCELL
  mstr_standard tap *
  page103_i217
#ISCELL
  mstr_standard tap *
  page103_i218
#ISCELL
  mstr_standard tap *
  page103_i219
#CELL
  pure_quanta sconn288_ddr506112002kq *
  page103_i22
#ISCELL
  mstr_standard tap *
  page103_i220
#ISCELL
  mstr_standard tap *
  page103_i221
#ISCELL
  mstr_standard tap *
  page103_i222
#ISCELL
  mstr_standard tap *
  page103_i223
#ISCELL
  mstr_standard tap *
  page103_i224
#ISCELL
  mstr_standard tap *
  page103_i225
#ISCELL
  mstr_standard tap *
  page103_i226
#ISCELL
  mstr_standard tap *
  page103_i227
#ISCELL
  mstr_standard tap *
  page103_i228
#ISCELL
  mstr_standard tap *
  page103_i229
#ISCELL
  mstr_standard tap *
  page103_i23
#ISCELL
  mstr_standard tap *
  page103_i230
#ISCELL
  mstr_standard tap *
  page103_i231
#ISCELL
  mstr_standard tap *
  page103_i232
#ISCELL
  mstr_standard tap *
  page103_i233
#ISCELL
  mstr_standard tap *
  page103_i234
#ISCELL
  mstr_standard tap *
  page103_i235
#ISCELL
  mstr_standard tap *
  page103_i236
#ISCELL
  mstr_standard tap *
  page103_i237
#CELL
  pure_quanta sconn288_ddr506112002kq *
  page103_i238
#ISCELL
  pure_quanta_power gnd *
  page103_i239
#ISCELL
  mstr_standard tap *
  page103_i24
#CELL
  pure_quanta q_cap *
  page103_i240
#CELL
  pure_quanta q_cap *
  page103_i241
#ISCELL
  pure_quanta_power universal_power *
  page103_i242
#ISCELL
  mstr_standard offpage *
  page103_i243
#CELL
  pure_quanta q_res *
  page103_i244
#CELL
  pure_quanta q_res *
  page103_i245
#ISCELL
  pure_quanta_power vcc_core *
  page103_i246
#ISCELL
  standard offpage *
  page103_i247
#ISCELL
  standard offpage *
  page103_i248
#CELL
  pure_quanta q_res *
  page103_i249
#ISCELL
  mstr_standard tap *
  page103_i25
#ISCELL
  pure_quanta_power vcc_core *
  page103_i250
#CELL
  pure_quanta q_res *
  page103_i251
#CELL
  pure_quanta q_res *
  page103_i252
#CELL
  pure_quanta schottky_12 *
  page103_i253
#ISCELL
  standard offpage *
  page103_i254
#ISCELL
  pure_quanta_power vcc_core *
  page103_i255
#CELL
  pure_quanta q_res *
  page103_i256
#ISCELL
  mstr_standard offpage *
  page103_i257
#ISCELL
  mstr_standard tap *
  page103_i26
#ISCELL
  mstr_standard tap *
  page103_i27
#ISCELL
  mstr_standard tap *
  page103_i28
#ISCELL
  mstr_standard tap *
  page103_i29
#ISCELL
  mstr_standard tap *
  page103_i30
#ISCELL
  mstr_standard tap *
  page103_i31
#ISCELL
  mstr_standard tap *
  page103_i32
#ISCELL
  mstr_standard tap *
  page103_i33
#ISCELL
  mstr_standard tap *
  page103_i34
#ISCELL
  mstr_standard tap *
  page103_i42
#ISCELL
  mstr_standard tap *
  page103_i43
#ISCELL
  mstr_standard tap *
  page103_i44
#ISCELL
  mstr_standard tap *
  page103_i45
#ISCELL
  mstr_standard tap *
  page103_i46
#ISCELL
  mstr_standard tap *
  page103_i47
#ISCELL
  mstr_standard tap *
  page103_i48
#ISCELL
  mstr_standard tap *
  page103_i49
#ISCELL
  mstr_symbols vcc_core *
  page103_i5
#ISCELL
  mstr_standard tap *
  page103_i50
#ISCELL
  mstr_standard tap *
  page103_i51
#ISCELL
  mstr_standard tap *
  page103_i52
#ISCELL
  mstr_standard tap *
  page103_i53
#ISCELL
  mstr_standard tap *
  page103_i54
#ISCELL
  mstr_standard tap *
  page103_i55
#ISCELL
  mstr_standard tap *
  page103_i56
#ISCELL
  mstr_standard tap *
  page103_i57
#ISCELL
  mstr_standard tap *
  page103_i58
#ISCELL
  mstr_standard tap *
  page103_i59
#ISCELL
  mstr_standard tap *
  page103_i60
#ISCELL
  mstr_standard tap *
  page103_i61
#ISCELL
  mstr_standard tap *
  page103_i62
#ISCELL
  mstr_standard tap *
  page103_i63
#ISCELL
  mstr_standard tap *
  page103_i64
#ISCELL
  mstr_standard tap *
  page103_i65
#ISCELL
  mstr_standard tap *
  page103_i66
#ISCELL
  mstr_standard tap *
  page103_i67
#ISCELL
  mstr_standard tap *
  page103_i68
#ISCELL
  mstr_standard tap *
  page103_i69
#ISCELL
  mstr_standard offpage *
  page103_i7
#ISCELL
  mstr_standard tap *
  page103_i70
#ISCELL
  mstr_standard tap *
  page103_i71
#ISCELL
  mstr_standard tap *
  page103_i72
#ISCELL
  mstr_standard tap *
  page103_i73
#ISCELL
  mstr_standard offpage *
  page103_i74
#ISCELL
  mstr_standard tap *
  page103_i76
#ISCELL
  mstr_standard tap *
  page103_i77
#ISCELL
  mstr_standard tap *
  page103_i78
#ISCELL
  mstr_standard tap *
  page103_i79
#ISCELL
  mstr_standard offpage *
  page103_i8
#ISCELL
  mstr_standard tap *
  page103_i80
#ISCELL
  mstr_standard tap *
  page103_i81
#ISCELL
  mstr_standard tap *
  page103_i82
#ISCELL
  mstr_standard tap *
  page103_i83
#ISCELL
  mstr_standard tap *
  page103_i84
#ISCELL
  mstr_standard tap *
  page103_i85
#ISCELL
  mstr_standard tap *
  page103_i86
#ISCELL
  mstr_standard tap *
  page103_i87
#ISCELL
  mstr_standard tap *
  page103_i88
#ISCELL
  mstr_standard tap *
  page103_i89
#ISCELL
  mstr_standard offpage *
  page103_i9
#ISCELL
  mstr_standard tap *
  page103_i90
#ISCELL
  mstr_standard tap *
  page103_i91
#ISCELL
  mstr_standard tap *
  page103_i92
#ISCELL
  mstr_standard tap *
  page103_i93
#ISCELL
  mstr_standard tap *
  page103_i94
#ISCELL
  mstr_standard tap *
  page103_i95
#ISCELL
  mstr_standard tap *
  page103_i96
#ISCELL
  mstr_standard tap *
  page103_i97
#ISCELL
  mstr_standard tap *
  page103_i98
#ISCELL
  mstr_standard tap *
  page103_i99
#ISCELL
  mstr_misc dns *
  *
#ISCELL
  pure_quanta quanta_title_block_c *
  *
#ISCELL
  mstr_standard offpage *
  page104_i1
#ISCELL
  mstr_standard offpage *
  page104_i10
#ISCELL
  mstr_standard tap *
  page104_i100
#ISCELL
  mstr_standard tap *
  page104_i101
#ISCELL
  mstr_standard tap *
  page104_i102
#ISCELL
  mstr_standard tap *
  page104_i103
#ISCELL
  mstr_standard tap *
  page104_i104
#ISCELL
  mstr_standard tap *
  page104_i105
#ISCELL
  mstr_standard tap *
  page104_i106
#ISCELL
  mstr_standard tap *
  page104_i107
#ISCELL
  mstr_standard tap *
  page104_i108
#ISCELL
  mstr_standard tap *
  page104_i109
#ISCELL
  mstr_standard offpage *
  page104_i11
#ISCELL
  mstr_standard tap *
  page104_i110
#ISCELL
  mstr_standard tap *
  page104_i111
#ISCELL
  mstr_standard tap *
  page104_i112
#ISCELL
  mstr_standard tap *
  page104_i113
#ISCELL
  mstr_standard tap *
  page104_i114
#ISCELL
  mstr_standard tap *
  page104_i115
#ISCELL
  mstr_standard tap *
  page104_i116
#ISCELL
  mstr_standard tap *
  page104_i117
#ISCELL
  mstr_standard tap *
  page104_i118
#ISCELL
  mstr_standard tap *
  page104_i119
#ISCELL
  mstr_standard offpage *
  page104_i12
#ISCELL
  mstr_standard tap *
  page104_i120
#ISCELL
  mstr_standard tap *
  page104_i121
#ISCELL
  mstr_standard tap *
  page104_i122
#ISCELL
  mstr_standard tap *
  page104_i123
#ISCELL
  mstr_standard tap *
  page104_i124
#ISCELL
  mstr_standard offpage *
  page104_i125
#ISCELL
  mstr_standard offpage *
  page104_i126
#ISCELL
  mstr_symbols gnd *
  page104_i127
#CELL
  pure_quanta q_res *
  page104_i128
#ISCELL
  mstr_standard offpage *
  page104_i13
#ISCELL
  mstr_standard offpage *
  page104_i14
#ISCELL
  mstr_symbols gnd *
  page104_i140
#ISCELL
  mstr_symbols gnd *
  page104_i141
#ISCELL
  mstr_standard offpage *
  page104_i15
#ISCELL
  mstr_standard offpage *
  page104_i16
#ISCELL
  mstr_standard offpage *
  page104_i17
#CELL
  pure_quanta sconn288_ddr506112002kq *
  page104_i174
#ISCELL
  mstr_standard offpage *
  page104_i18
#CELL
  pure_quanta q_cap *
  page104_i185
#ISCELL
  mstr_symbols gnd *
  page104_i186
#ISCELL
  mstr_standard offpage *
  page104_i187
#CELL
  pure_quanta q_res *
  page104_i189
#ISCELL
  mstr_standard offpage *
  page104_i19
#CELL
  pure_quanta q_res *
  page104_i190
#ISCELL
  mstr_symbols vcc_core *
  page104_i192
#ISCELL
  mstr_standard tap *
  page104_i193
#ISCELL
  mstr_standard tap *
  page104_i194
#ISCELL
  mstr_standard tap *
  page104_i195
#ISCELL
  mstr_standard tap *
  page104_i196
#ISCELL
  mstr_standard offpage *
  page104_i198
#ISCELL
  mstr_standard offpage *
  page104_i199
#ISCELL
  mstr_standard offpage *
  page104_i2
#ISCELL
  mstr_standard offpage *
  page104_i20
#ISCELL
  mstr_standard offpage *
  page104_i200
#ISCELL
  mstr_standard offpage *
  page104_i201
#ISCELL
  mstr_standard tap *
  page104_i202
#ISCELL
  mstr_standard tap *
  page104_i203
#ISCELL
  mstr_standard tap *
  page104_i204
#ISCELL
  mstr_standard tap *
  page104_i205
#ISCELL
  mstr_standard tap *
  page104_i206
#ISCELL
  mstr_standard tap *
  page104_i207
#ISCELL
  mstr_standard tap *
  page104_i208
#ISCELL
  mstr_standard tap *
  page104_i209
#ISCELL
  mstr_standard offpage *
  page104_i21
#ISCELL
  mstr_standard tap *
  page104_i210
#ISCELL
  mstr_standard tap *
  page104_i211
#ISCELL
  mstr_standard tap *
  page104_i212
#ISCELL
  mstr_standard tap *
  page104_i213
#ISCELL
  mstr_standard tap *
  page104_i214
#ISCELL
  mstr_standard tap *
  page104_i215
#ISCELL
  mstr_standard tap *
  page104_i216
#ISCELL
  mstr_standard tap *
  page104_i217
#ISCELL
  mstr_standard tap *
  page104_i218
#ISCELL
  mstr_standard tap *
  page104_i219
#CELL
  pure_quanta sconn288_ddr506112002kq *
  page104_i22
#ISCELL
  mstr_standard tap *
  page104_i220
#ISCELL
  mstr_standard tap *
  page104_i221
#ISCELL
  mstr_standard tap *
  page104_i222
#ISCELL
  mstr_standard tap *
  page104_i223
#ISCELL
  mstr_standard tap *
  page104_i224
#ISCELL
  mstr_standard tap *
  page104_i225
#ISCELL
  mstr_standard tap *
  page104_i226
#ISCELL
  mstr_standard tap *
  page104_i227
#ISCELL
  mstr_standard tap *
  page104_i228
#ISCELL
  mstr_standard tap *
  page104_i229
#ISCELL
  mstr_standard tap *
  page104_i23
#ISCELL
  mstr_standard tap *
  page104_i230
#ISCELL
  mstr_standard tap *
  page104_i231
#ISCELL
  mstr_standard tap *
  page104_i232
#ISCELL
  mstr_standard tap *
  page104_i233
#ISCELL
  mstr_standard tap *
  page104_i234
#ISCELL
  mstr_standard tap *
  page104_i235
#ISCELL
  mstr_standard tap *
  page104_i236
#ISCELL
  mstr_standard tap *
  page104_i237
#CELL
  pure_quanta sconn288_ddr506112002kq *
  page104_i238
#ISCELL
  pure_quanta_power gnd *
  page104_i239
#ISCELL
  mstr_standard tap *
  page104_i24
#CELL
  pure_quanta q_cap *
  page104_i240
#CELL
  pure_quanta q_cap *
  page104_i241
#ISCELL
  pure_quanta_power universal_power *
  page104_i242
#ISCELL
  mstr_standard offpage *
  page104_i243
#CELL
  pure_quanta q_res *
  page104_i244
#CELL
  pure_quanta q_res *
  page104_i245
#ISCELL
  mstr_standard offpage *
  page104_i246
#ISCELL
  mstr_standard tap *
  page104_i25
#ISCELL
  mstr_standard tap *
  page104_i26
#ISCELL
  mstr_standard tap *
  page104_i27
#ISCELL
  mstr_standard tap *
  page104_i28
#ISCELL
  mstr_standard tap *
  page104_i29
#ISCELL
  mstr_standard tap *
  page104_i30
#ISCELL
  mstr_standard tap *
  page104_i31
#ISCELL
  mstr_standard tap *
  page104_i32
#ISCELL
  mstr_standard tap *
  page104_i33
#ISCELL
  mstr_standard tap *
  page104_i34
#ISCELL
  mstr_standard tap *
  page104_i35
#ISCELL
  mstr_standard tap *
  page104_i36
#ISCELL
  mstr_standard tap *
  page104_i37
#ISCELL
  mstr_standard tap *
  page104_i38
#ISCELL
  mstr_standard tap *
  page104_i39
#ISCELL
  mstr_standard tap *
  page104_i40
#ISCELL
  mstr_standard tap *
  page104_i41
#ISCELL
  mstr_standard tap *
  page104_i42
#ISCELL
  mstr_standard tap *
  page104_i43
#ISCELL
  mstr_standard tap *
  page104_i44
#ISCELL
  mstr_standard tap *
  page104_i45
#ISCELL
  mstr_standard tap *
  page104_i46
#ISCELL
  mstr_standard tap *
  page104_i47
#ISCELL
  mstr_standard tap *
  page104_i48
#ISCELL
  mstr_standard tap *
  page104_i49
#ISCELL
  mstr_standard tap *
  page104_i50
#ISCELL
  mstr_standard tap *
  page104_i51
#ISCELL
  mstr_standard tap *
  page104_i52
#ISCELL
  mstr_standard tap *
  page104_i53
#ISCELL
  mstr_standard tap *
  page104_i54
#ISCELL
  mstr_standard tap *
  page104_i55
#ISCELL
  mstr_standard tap *
  page104_i56
#ISCELL
  mstr_standard tap *
  page104_i57
#ISCELL
  mstr_standard tap *
  page104_i58
#ISCELL
  mstr_standard tap *
  page104_i59
#ISCELL
  mstr_standard offpage *
  page104_i6
#ISCELL
  mstr_standard tap *
  page104_i60
#ISCELL
  mstr_standard tap *
  page104_i61
#ISCELL
  mstr_standard tap *
  page104_i62
#ISCELL
  mstr_standard tap *
  page104_i63
#ISCELL
  mstr_standard tap *
  page104_i64
#ISCELL
  mstr_standard tap *
  page104_i65
#ISCELL
  mstr_standard tap *
  page104_i66
#ISCELL
  mstr_standard tap *
  page104_i67
#ISCELL
  mstr_standard tap *
  page104_i68
#ISCELL
  mstr_standard offpage *
  page104_i7
#ISCELL
  mstr_standard offpage *
  page104_i76
#ISCELL
  mstr_standard tap *
  page104_i77
#ISCELL
  mstr_standard tap *
  page104_i78
#ISCELL
  mstr_standard tap *
  page104_i79
#ISCELL
  mstr_standard offpage *
  page104_i8
#ISCELL
  mstr_standard tap *
  page104_i80
#ISCELL
  mstr_standard tap *
  page104_i81
#ISCELL
  mstr_standard tap *
  page104_i82
#ISCELL
  mstr_standard tap *
  page104_i83
#ISCELL
  mstr_standard tap *
  page104_i84
#ISCELL
  mstr_standard tap *
  page104_i85
#ISCELL
  mstr_standard tap *
  page104_i86
#ISCELL
  mstr_standard tap *
  page104_i87
#ISCELL
  mstr_standard tap *
  page104_i88
#ISCELL
  mstr_standard tap *
  page104_i89
#ISCELL
  mstr_symbols vcc_core *
  page104_i9
#ISCELL
  mstr_standard tap *
  page104_i90
#ISCELL
  mstr_standard tap *
  page104_i91
#ISCELL
  mstr_standard tap *
  page104_i92
#ISCELL
  mstr_standard tap *
  page104_i93
#ISCELL
  mstr_standard tap *
  page104_i94
#ISCELL
  mstr_standard tap *
  page104_i95
#ISCELL
  mstr_standard tap *
  page104_i96
#ISCELL
  mstr_standard tap *
  page104_i97
#ISCELL
  mstr_standard tap *
  page104_i98
#ISCELL
  mstr_standard tap *
  page104_i99
#ISCELL
  mstr_misc dns *
  *
#ISCELL
  pure_quanta quanta_title_block_c *
  *
#ISCELL
  mstr_standard offpage *
  page105_i1
#ISCELL
  mstr_standard offpage *
  page105_i10
#ISCELL
  mstr_standard tap *
  page105_i100
#ISCELL
  mstr_standard tap *
  page105_i101
#ISCELL
  mstr_standard tap *
  page105_i102
#ISCELL
  mstr_standard tap *
  page105_i103
#ISCELL
  mstr_standard tap *
  page105_i104
#ISCELL
  mstr_standard tap *
  page105_i105
#ISCELL
  mstr_standard tap *
  page105_i106
#ISCELL
  mstr_standard tap *
  page105_i107
#ISCELL
  mstr_standard tap *
  page105_i108
#ISCELL
  mstr_standard tap *
  page105_i109
#ISCELL
  mstr_standard offpage *
  page105_i11
#ISCELL
  mstr_standard tap *
  page105_i110
#ISCELL
  mstr_standard tap *
  page105_i111
#ISCELL
  mstr_standard tap *
  page105_i112
#ISCELL
  mstr_standard tap *
  page105_i113
#ISCELL
  mstr_standard tap *
  page105_i114
#ISCELL
  mstr_standard tap *
  page105_i115
#ISCELL
  mstr_standard tap *
  page105_i116
#ISCELL
  mstr_standard tap *
  page105_i117
#ISCELL
  mstr_standard tap *
  page105_i118
#ISCELL
  mstr_standard tap *
  page105_i119
#ISCELL
  mstr_standard offpage *
  page105_i12
#ISCELL
  mstr_standard tap *
  page105_i120
#ISCELL
  mstr_standard tap *
  page105_i121
#ISCELL
  mstr_standard tap *
  page105_i122
#ISCELL
  mstr_standard tap *
  page105_i123
#ISCELL
  mstr_standard tap *
  page105_i124
#ISCELL
  mstr_standard offpage *
  page105_i125
#ISCELL
  mstr_standard offpage *
  page105_i126
#ISCELL
  mstr_symbols gnd *
  page105_i127
#CELL
  pure_quanta q_res *
  page105_i128
#ISCELL
  mstr_standard offpage *
  page105_i13
#ISCELL
  mstr_standard offpage *
  page105_i14
#ISCELL
  mstr_symbols gnd *
  page105_i140
#ISCELL
  mstr_symbols gnd *
  page105_i141
#ISCELL
  mstr_standard offpage *
  page105_i15
#ISCELL
  mstr_standard offpage *
  page105_i16
#ISCELL
  mstr_standard offpage *
  page105_i17
#CELL
  pure_quanta sconn288_ddr506112002kq *
  page105_i176
#ISCELL
  mstr_standard offpage *
  page105_i18
#CELL
  pure_quanta q_cap *
  page105_i185
#ISCELL
  mstr_symbols gnd *
  page105_i186
#ISCELL
  mstr_standard offpage *
  page105_i187
#CELL
  pure_quanta q_res *
  page105_i188
#ISCELL
  mstr_symbols vcc_core *
  page105_i189
#ISCELL
  mstr_standard offpage *
  page105_i19
#CELL
  pure_quanta q_res *
  page105_i190
#ISCELL
  mstr_standard tap *
  page105_i191
#ISCELL
  mstr_standard tap *
  page105_i192
#ISCELL
  mstr_standard tap *
  page105_i193
#ISCELL
  mstr_standard tap *
  page105_i194
#ISCELL
  mstr_standard tap *
  page105_i195
#ISCELL
  mstr_standard offpage *
  page105_i197
#ISCELL
  mstr_standard offpage *
  page105_i198
#ISCELL
  mstr_standard offpage *
  page105_i199
#ISCELL
  mstr_standard offpage *
  page105_i2
#ISCELL
  mstr_standard offpage *
  page105_i20
#ISCELL
  mstr_standard offpage *
  page105_i200
#ISCELL
  mstr_standard tap *
  page105_i201
#ISCELL
  mstr_standard tap *
  page105_i202
#ISCELL
  mstr_standard tap *
  page105_i203
#ISCELL
  mstr_standard tap *
  page105_i204
#ISCELL
  mstr_standard tap *
  page105_i205
#ISCELL
  mstr_standard tap *
  page105_i206
#ISCELL
  mstr_standard tap *
  page105_i207
#ISCELL
  mstr_standard tap *
  page105_i208
#ISCELL
  mstr_standard tap *
  page105_i209
#ISCELL
  mstr_standard offpage *
  page105_i21
#ISCELL
  mstr_standard tap *
  page105_i210
#ISCELL
  mstr_standard tap *
  page105_i211
#ISCELL
  mstr_standard tap *
  page105_i212
#ISCELL
  mstr_standard tap *
  page105_i213
#ISCELL
  mstr_standard tap *
  page105_i214
#ISCELL
  mstr_standard tap *
  page105_i215
#ISCELL
  mstr_standard tap *
  page105_i216
#ISCELL
  mstr_standard tap *
  page105_i217
#ISCELL
  mstr_standard tap *
  page105_i218
#ISCELL
  mstr_standard tap *
  page105_i219
#CELL
  pure_quanta sconn288_ddr506112002kq *
  page105_i22
#ISCELL
  mstr_standard tap *
  page105_i220
#ISCELL
  mstr_standard tap *
  page105_i221
#ISCELL
  mstr_standard tap *
  page105_i222
#ISCELL
  mstr_standard tap *
  page105_i223
#ISCELL
  mstr_standard tap *
  page105_i224
#ISCELL
  mstr_standard tap *
  page105_i225
#ISCELL
  mstr_standard tap *
  page105_i226
#ISCELL
  mstr_standard tap *
  page105_i227
#ISCELL
  mstr_standard tap *
  page105_i228
#ISCELL
  mstr_standard tap *
  page105_i229
#ISCELL
  mstr_standard tap *
  page105_i23
#ISCELL
  mstr_standard tap *
  page105_i230
#ISCELL
  mstr_standard tap *
  page105_i231
#ISCELL
  mstr_standard tap *
  page105_i232
#ISCELL
  mstr_standard tap *
  page105_i233
#ISCELL
  mstr_standard tap *
  page105_i234
#ISCELL
  mstr_standard tap *
  page105_i235
#CELL
  pure_quanta sconn288_ddr506112002kq *
  page105_i236
#ISCELL
  pure_quanta_power gnd *
  page105_i237
#CELL
  pure_quanta q_cap *
  page105_i238
#CELL
  pure_quanta q_cap *
  page105_i239
#ISCELL
  mstr_standard tap *
  page105_i24
#ISCELL
  pure_quanta_power universal_power *
  page105_i240
#ISCELL
  mstr_standard offpage *
  page105_i241
#CELL
  pure_quanta q_res *
  page105_i242
#CELL
  pure_quanta q_res *
  page105_i243
#ISCELL
  mstr_standard offpage *
  page105_i244
#ISCELL
  mstr_standard tap *
  page105_i25
#ISCELL
  mstr_standard tap *
  page105_i26
#ISCELL
  mstr_standard tap *
  page105_i27
#ISCELL
  mstr_standard tap *
  page105_i28
#ISCELL
  mstr_standard tap *
  page105_i29
#ISCELL
  mstr_standard tap *
  page105_i30
#ISCELL
  mstr_standard tap *
  page105_i31
#ISCELL
  mstr_standard tap *
  page105_i32
#ISCELL
  mstr_standard tap *
  page105_i33
#ISCELL
  mstr_standard tap *
  page105_i34
#ISCELL
  mstr_standard tap *
  page105_i35
#ISCELL
  mstr_standard tap *
  page105_i36
#ISCELL
  mstr_standard tap *
  page105_i37
#ISCELL
  mstr_standard tap *
  page105_i38
#ISCELL
  mstr_standard tap *
  page105_i39
#ISCELL
  mstr_standard tap *
  page105_i40
#ISCELL
  mstr_standard tap *
  page105_i41
#ISCELL
  mstr_standard tap *
  page105_i42
#ISCELL
  mstr_standard tap *
  page105_i43
#ISCELL
  mstr_standard tap *
  page105_i44
#ISCELL
  mstr_standard tap *
  page105_i45
#ISCELL
  mstr_standard tap *
  page105_i46
#ISCELL
  mstr_standard tap *
  page105_i47
#ISCELL
  mstr_standard tap *
  page105_i48
#ISCELL
  mstr_standard tap *
  page105_i49
#ISCELL
  mstr_standard tap *
  page105_i50
#ISCELL
  mstr_standard tap *
  page105_i51
#ISCELL
  mstr_standard tap *
  page105_i52
#ISCELL
  mstr_standard tap *
  page105_i53
#ISCELL
  mstr_standard tap *
  page105_i54
#ISCELL
  mstr_standard tap *
  page105_i55
#ISCELL
  mstr_standard tap *
  page105_i56
#ISCELL
  mstr_standard tap *
  page105_i57
#ISCELL
  mstr_standard tap *
  page105_i58
#ISCELL
  mstr_standard tap *
  page105_i59
#ISCELL
  mstr_standard offpage *
  page105_i6
#ISCELL
  mstr_standard tap *
  page105_i60
#ISCELL
  mstr_standard tap *
  page105_i61
#ISCELL
  mstr_standard tap *
  page105_i62
#ISCELL
  mstr_standard tap *
  page105_i63
#ISCELL
  mstr_standard tap *
  page105_i64
#ISCELL
  mstr_standard tap *
  page105_i65
#ISCELL
  mstr_standard tap *
  page105_i66
#ISCELL
  mstr_standard offpage *
  page105_i7
#ISCELL
  mstr_standard offpage *
  page105_i74
#ISCELL
  mstr_standard tap *
  page105_i75
#ISCELL
  mstr_standard tap *
  page105_i76
#ISCELL
  mstr_standard tap *
  page105_i77
#ISCELL
  mstr_standard tap *
  page105_i78
#ISCELL
  mstr_standard tap *
  page105_i79
#ISCELL
  mstr_standard offpage *
  page105_i8
#ISCELL
  mstr_standard tap *
  page105_i80
#ISCELL
  mstr_standard tap *
  page105_i81
#ISCELL
  mstr_standard tap *
  page105_i82
#ISCELL
  mstr_standard tap *
  page105_i83
#ISCELL
  mstr_standard tap *
  page105_i84
#ISCELL
  mstr_standard tap *
  page105_i85
#ISCELL
  mstr_standard tap *
  page105_i86
#ISCELL
  mstr_standard tap *
  page105_i87
#ISCELL
  mstr_standard tap *
  page105_i88
#ISCELL
  mstr_standard tap *
  page105_i89
#ISCELL
  mstr_symbols vcc_core *
  page105_i9
#ISCELL
  mstr_standard tap *
  page105_i90
#ISCELL
  mstr_standard tap *
  page105_i91
#ISCELL
  mstr_standard tap *
  page105_i92
#ISCELL
  mstr_standard tap *
  page105_i93
#ISCELL
  mstr_standard tap *
  page105_i94
#ISCELL
  mstr_standard tap *
  page105_i95
#ISCELL
  mstr_standard tap *
  page105_i96
#ISCELL
  mstr_standard tap *
  page105_i97
#ISCELL
  mstr_standard tap *
  page105_i98
#ISCELL
  mstr_standard tap *
  page105_i99
#ISCELL
  mstr_misc dns *
  *
#ISCELL
  pure_quanta quanta_title_block_c *
  *
#ISCELL
  mstr_standard offpage *
  page106_i10
#ISCELL
  mstr_standard tap *
  page106_i100
#ISCELL
  mstr_standard tap *
  page106_i101
#ISCELL
  mstr_standard tap *
  page106_i102
#ISCELL
  mstr_standard tap *
  page106_i103
#ISCELL
  mstr_standard tap *
  page106_i104
#ISCELL
  mstr_standard tap *
  page106_i105
#ISCELL
  mstr_standard tap *
  page106_i106
#ISCELL
  mstr_standard tap *
  page106_i107
#ISCELL
  mstr_standard tap *
  page106_i108
#ISCELL
  mstr_standard tap *
  page106_i109
#ISCELL
  mstr_standard offpage *
  page106_i11
#ISCELL
  mstr_standard tap *
  page106_i110
#ISCELL
  mstr_standard tap *
  page106_i111
#ISCELL
  mstr_standard tap *
  page106_i112
#ISCELL
  mstr_standard tap *
  page106_i113
#ISCELL
  mstr_standard tap *
  page106_i114
#ISCELL
  mstr_standard tap *
  page106_i115
#ISCELL
  mstr_standard tap *
  page106_i116
#ISCELL
  mstr_standard tap *
  page106_i117
#ISCELL
  mstr_standard tap *
  page106_i118
#ISCELL
  mstr_standard tap *
  page106_i119
#ISCELL
  mstr_standard offpage *
  page106_i12
#ISCELL
  mstr_standard tap *
  page106_i120
#ISCELL
  mstr_standard tap *
  page106_i121
#ISCELL
  mstr_standard tap *
  page106_i122
#ISCELL
  mstr_standard tap *
  page106_i123
#ISCELL
  mstr_standard tap *
  page106_i124
#ISCELL
  mstr_standard offpage *
  page106_i125
#ISCELL
  mstr_symbols gnd *
  page106_i126
#CELL
  pure_quanta q_res *
  page106_i127
#ISCELL
  mstr_symbols gnd *
  page106_i128
#ISCELL
  mstr_standard offpage *
  page106_i129
#ISCELL
  mstr_standard offpage *
  page106_i13
#ISCELL
  mstr_standard offpage *
  page106_i14
#ISCELL
  mstr_symbols gnd *
  page106_i142
#CELL
  pure_quanta sconn288_ddr506112002kq *
  page106_i143
#ISCELL
  mstr_standard offpage *
  page106_i15
#ISCELL
  mstr_standard offpage *
  page106_i16
#ISCELL
  mstr_standard offpage *
  page106_i17
#ISCELL
  mstr_standard offpage *
  page106_i18
#CELL
  pure_quanta q_cap *
  page106_i185
#ISCELL
  mstr_symbols gnd *
  page106_i186
#ISCELL
  mstr_standard offpage *
  page106_i187
#CELL
  pure_quanta q_res *
  page106_i188
#ISCELL
  mstr_symbols vcc_core *
  page106_i189
#ISCELL
  mstr_standard offpage *
  page106_i19
#CELL
  pure_quanta q_res *
  page106_i190
#ISCELL
  mstr_standard offpage *
  page106_i192
#ISCELL
  mstr_standard offpage *
  page106_i193
#ISCELL
  mstr_standard offpage *
  page106_i194
#ISCELL
  mstr_standard offpage *
  page106_i195
#ISCELL
  mstr_standard tap *
  page106_i196
#ISCELL
  mstr_standard tap *
  page106_i197
#ISCELL
  mstr_standard tap *
  page106_i198
#ISCELL
  mstr_standard tap *
  page106_i199
#ISCELL
  mstr_standard offpage *
  page106_i20
#ISCELL
  mstr_standard tap *
  page106_i200
#ISCELL
  mstr_standard tap *
  page106_i201
#ISCELL
  mstr_standard tap *
  page106_i202
#ISCELL
  mstr_standard tap *
  page106_i203
#ISCELL
  mstr_standard tap *
  page106_i204
#ISCELL
  mstr_standard tap *
  page106_i205
#ISCELL
  mstr_standard tap *
  page106_i206
#ISCELL
  mstr_standard tap *
  page106_i207
#ISCELL
  mstr_standard tap *
  page106_i208
#ISCELL
  mstr_standard tap *
  page106_i209
#ISCELL
  mstr_standard offpage *
  page106_i21
#ISCELL
  mstr_standard tap *
  page106_i210
#ISCELL
  mstr_standard tap *
  page106_i211
#ISCELL
  mstr_standard tap *
  page106_i212
#ISCELL
  mstr_standard tap *
  page106_i213
#ISCELL
  mstr_standard tap *
  page106_i214
#ISCELL
  mstr_standard tap *
  page106_i215
#ISCELL
  mstr_standard tap *
  page106_i216
#ISCELL
  mstr_standard tap *
  page106_i217
#ISCELL
  mstr_standard tap *
  page106_i218
#ISCELL
  mstr_standard tap *
  page106_i219
#CELL
  pure_quanta sconn288_ddr506112002kq *
  page106_i22
#ISCELL
  mstr_standard tap *
  page106_i220
#ISCELL
  mstr_standard tap *
  page106_i221
#ISCELL
  mstr_standard tap *
  page106_i222
#ISCELL
  mstr_standard tap *
  page106_i223
#ISCELL
  mstr_standard tap *
  page106_i224
#ISCELL
  mstr_standard tap *
  page106_i225
#ISCELL
  mstr_standard tap *
  page106_i226
#ISCELL
  mstr_standard tap *
  page106_i227
#ISCELL
  mstr_standard tap *
  page106_i228
#ISCELL
  mstr_standard tap *
  page106_i229
#ISCELL
  mstr_standard tap *
  page106_i23
#ISCELL
  mstr_standard tap *
  page106_i230
#ISCELL
  mstr_standard tap *
  page106_i231
#ISCELL
  mstr_standard tap *
  page106_i232
#ISCELL
  mstr_standard tap *
  page106_i233
#ISCELL
  mstr_standard tap *
  page106_i234
#ISCELL
  mstr_standard tap *
  page106_i235
#CELL
  pure_quanta sconn288_ddr506112002kq *
  page106_i236
#ISCELL
  pure_quanta_power gnd *
  page106_i237
#CELL
  pure_quanta q_cap *
  page106_i238
#CELL
  pure_quanta q_cap *
  page106_i239
#ISCELL
  mstr_standard tap *
  page106_i24
#ISCELL
  pure_quanta_power universal_power *
  page106_i240
#ISCELL
  mstr_standard offpage *
  page106_i241
#CELL
  pure_quanta q_res *
  page106_i242
#CELL
  pure_quanta q_res *
  page106_i243
#ISCELL
  mstr_standard offpage *
  page106_i244
#ISCELL
  mstr_standard tap *
  page106_i25
#ISCELL
  mstr_standard tap *
  page106_i26
#ISCELL
  mstr_standard tap *
  page106_i27
#ISCELL
  mstr_standard tap *
  page106_i28
#ISCELL
  mstr_standard tap *
  page106_i29
#ISCELL
  mstr_standard tap *
  page106_i30
#ISCELL
  mstr_standard tap *
  page106_i31
#ISCELL
  mstr_standard tap *
  page106_i32
#ISCELL
  mstr_standard tap *
  page106_i33
#ISCELL
  mstr_standard tap *
  page106_i34
#ISCELL
  mstr_standard tap *
  page106_i35
#ISCELL
  mstr_standard tap *
  page106_i36
#ISCELL
  mstr_standard tap *
  page106_i37
#ISCELL
  mstr_standard tap *
  page106_i38
#ISCELL
  mstr_standard tap *
  page106_i39
#ISCELL
  mstr_standard offpage *
  page106_i4
#ISCELL
  mstr_standard tap *
  page106_i40
#ISCELL
  mstr_standard tap *
  page106_i41
#ISCELL
  mstr_standard tap *
  page106_i42
#ISCELL
  mstr_standard tap *
  page106_i43
#ISCELL
  mstr_standard tap *
  page106_i44
#ISCELL
  mstr_standard tap *
  page106_i45
#ISCELL
  mstr_standard tap *
  page106_i46
#ISCELL
  mstr_standard tap *
  page106_i47
#ISCELL
  mstr_standard tap *
  page106_i48
#ISCELL
  mstr_standard tap *
  page106_i49
#ISCELL
  mstr_standard offpage *
  page106_i5
#ISCELL
  mstr_standard tap *
  page106_i50
#ISCELL
  mstr_standard tap *
  page106_i51
#ISCELL
  mstr_standard tap *
  page106_i52
#ISCELL
  mstr_standard tap *
  page106_i53
#ISCELL
  mstr_standard tap *
  page106_i54
#ISCELL
  mstr_standard tap *
  page106_i55
#ISCELL
  mstr_standard tap *
  page106_i56
#ISCELL
  mstr_standard tap *
  page106_i57
#ISCELL
  mstr_standard tap *
  page106_i58
#ISCELL
  mstr_standard tap *
  page106_i59
#ISCELL
  mstr_standard offpage *
  page106_i6
#ISCELL
  mstr_standard tap *
  page106_i60
#ISCELL
  mstr_standard tap *
  page106_i61
#ISCELL
  mstr_standard tap *
  page106_i62
#ISCELL
  mstr_standard tap *
  page106_i63
#ISCELL
  mstr_standard tap *
  page106_i64
#ISCELL
  mstr_standard tap *
  page106_i65
#ISCELL
  mstr_standard tap *
  page106_i66
#ISCELL
  mstr_standard tap *
  page106_i67
#ISCELL
  mstr_standard tap *
  page106_i68
#ISCELL
  mstr_standard tap *
  page106_i69
#ISCELL
  mstr_symbols vcc_core *
  page106_i7
#ISCELL
  mstr_standard tap *
  page106_i70
#ISCELL
  mstr_standard offpage *
  page106_i78
#ISCELL
  mstr_standard tap *
  page106_i79
#ISCELL
  mstr_standard offpage *
  page106_i8
#ISCELL
  mstr_standard tap *
  page106_i80
#ISCELL
  mstr_standard tap *
  page106_i81
#ISCELL
  mstr_standard tap *
  page106_i82
#ISCELL
  mstr_standard tap *
  page106_i83
#ISCELL
  mstr_standard tap *
  page106_i84
#ISCELL
  mstr_standard tap *
  page106_i85
#ISCELL
  mstr_standard tap *
  page106_i86
#ISCELL
  mstr_standard tap *
  page106_i87
#ISCELL
  mstr_standard tap *
  page106_i88
#ISCELL
  mstr_standard tap *
  page106_i89
#ISCELL
  mstr_standard offpage *
  page106_i9
#ISCELL
  mstr_standard tap *
  page106_i90
#ISCELL
  mstr_standard tap *
  page106_i91
#ISCELL
  mstr_standard tap *
  page106_i92
#ISCELL
  mstr_standard tap *
  page106_i93
#ISCELL
  mstr_standard tap *
  page106_i94
#ISCELL
  mstr_standard tap *
  page106_i95
#ISCELL
  mstr_standard tap *
  page106_i96
#ISCELL
  mstr_standard tap *
  page106_i97
#ISCELL
  mstr_standard tap *
  page106_i98
#ISCELL
  mstr_standard tap *
  page106_i99
#ISCELL
  mstr_misc dns *
  *
#ISCELL
  pure_quanta quanta_title_block_c *
  *
#ISCELL
  mstr_standard offpage *
  page107_i1
#ISCELL
  mstr_standard offpage *
  page107_i10
#ISCELL
  mstr_standard tap *
  page107_i100
#ISCELL
  mstr_standard tap *
  page107_i101
#ISCELL
  mstr_standard tap *
  page107_i102
#ISCELL
  mstr_standard tap *
  page107_i103
#ISCELL
  mstr_standard tap *
  page107_i104
#ISCELL
  mstr_standard tap *
  page107_i105
#ISCELL
  mstr_standard tap *
  page107_i106
#ISCELL
  mstr_standard tap *
  page107_i107
#ISCELL
  mstr_standard tap *
  page107_i108
#ISCELL
  mstr_standard tap *
  page107_i109
#ISCELL
  mstr_standard offpage *
  page107_i11
#ISCELL
  mstr_standard tap *
  page107_i110
#ISCELL
  mstr_standard tap *
  page107_i111
#ISCELL
  mstr_standard tap *
  page107_i112
#ISCELL
  mstr_standard tap *
  page107_i113
#ISCELL
  mstr_standard tap *
  page107_i114
#ISCELL
  mstr_standard tap *
  page107_i115
#ISCELL
  mstr_standard tap *
  page107_i116
#ISCELL
  mstr_standard tap *
  page107_i117
#ISCELL
  mstr_standard tap *
  page107_i118
#ISCELL
  mstr_standard tap *
  page107_i119
#ISCELL
  mstr_standard offpage *
  page107_i12
#ISCELL
  mstr_standard tap *
  page107_i120
#ISCELL
  mstr_standard tap *
  page107_i121
#ISCELL
  mstr_standard tap *
  page107_i122
#ISCELL
  mstr_standard tap *
  page107_i123
#ISCELL
  mstr_standard offpage *
  page107_i124
#ISCELL
  mstr_standard offpage *
  page107_i125
#ISCELL
  mstr_symbols gnd *
  page107_i126
#ISCELL
  mstr_standard offpage *
  page107_i127
#ISCELL
  mstr_standard offpage *
  page107_i13
#CELL
  pure_quanta q_res *
  page107_i136
#ISCELL
  mstr_symbols gnd *
  page107_i137
#ISCELL
  mstr_symbols gnd *
  page107_i138
#CELL
  pure_quanta sconn288_ddr506112002kq *
  page107_i139
#ISCELL
  mstr_standard offpage *
  page107_i14
#ISCELL
  mstr_standard offpage *
  page107_i15
#ISCELL
  mstr_standard offpage *
  page107_i16
#ISCELL
  mstr_standard offpage *
  page107_i17
#ISCELL
  mstr_standard offpage *
  page107_i18
#CELL
  pure_quanta q_cap *
  page107_i185
#ISCELL
  mstr_symbols gnd *
  page107_i186
#ISCELL
  mstr_standard offpage *
  page107_i187
#CELL
  pure_quanta q_res *
  page107_i188
#ISCELL
  mstr_symbols vcc_core *
  page107_i189
#ISCELL
  mstr_standard offpage *
  page107_i19
#CELL
  pure_quanta q_res *
  page107_i190
#ISCELL
  mstr_standard offpage *
  page107_i191
#ISCELL
  mstr_standard offpage *
  page107_i192
#ISCELL
  mstr_standard offpage *
  page107_i193
#ISCELL
  mstr_standard offpage *
  page107_i194
#ISCELL
  mstr_standard tap *
  page107_i195
#ISCELL
  mstr_standard tap *
  page107_i196
#ISCELL
  mstr_standard tap *
  page107_i197
#ISCELL
  mstr_standard tap *
  page107_i198
#ISCELL
  mstr_standard tap *
  page107_i199
#ISCELL
  mstr_standard offpage *
  page107_i2
#ISCELL
  mstr_standard offpage *
  page107_i20
#ISCELL
  mstr_standard tap *
  page107_i200
#ISCELL
  mstr_standard tap *
  page107_i201
#ISCELL
  mstr_standard tap *
  page107_i202
#ISCELL
  mstr_standard tap *
  page107_i203
#ISCELL
  mstr_standard tap *
  page107_i204
#ISCELL
  mstr_standard tap *
  page107_i205
#ISCELL
  mstr_standard tap *
  page107_i206
#ISCELL
  mstr_standard tap *
  page107_i207
#ISCELL
  mstr_standard tap *
  page107_i208
#ISCELL
  mstr_standard tap *
  page107_i209
#ISCELL
  mstr_standard offpage *
  page107_i21
#ISCELL
  mstr_standard tap *
  page107_i210
#ISCELL
  mstr_standard tap *
  page107_i211
#ISCELL
  mstr_standard tap *
  page107_i212
#ISCELL
  mstr_standard tap *
  page107_i213
#ISCELL
  mstr_standard tap *
  page107_i214
#ISCELL
  mstr_standard tap *
  page107_i215
#ISCELL
  mstr_standard tap *
  page107_i216
#ISCELL
  mstr_standard tap *
  page107_i217
#ISCELL
  mstr_standard tap *
  page107_i218
#ISCELL
  mstr_standard tap *
  page107_i219
#CELL
  pure_quanta sconn288_ddr506112002kq *
  page107_i22
#ISCELL
  mstr_standard tap *
  page107_i220
#ISCELL
  mstr_standard tap *
  page107_i221
#ISCELL
  mstr_standard tap *
  page107_i222
#ISCELL
  mstr_standard tap *
  page107_i223
#ISCELL
  mstr_standard tap *
  page107_i224
#ISCELL
  mstr_standard tap *
  page107_i225
#ISCELL
  mstr_standard tap *
  page107_i226
#ISCELL
  mstr_standard tap *
  page107_i227
#ISCELL
  mstr_standard tap *
  page107_i228
#ISCELL
  mstr_standard tap *
  page107_i229
#ISCELL
  mstr_standard tap *
  page107_i23
#ISCELL
  mstr_standard tap *
  page107_i230
#ISCELL
  mstr_standard tap *
  page107_i231
#ISCELL
  mstr_standard tap *
  page107_i232
#ISCELL
  mstr_standard tap *
  page107_i233
#ISCELL
  mstr_standard tap *
  page107_i234
#CELL
  pure_quanta sconn288_ddr506112002kq *
  page107_i235
#ISCELL
  pure_quanta_power gnd *
  page107_i236
#CELL
  pure_quanta q_cap *
  page107_i237
#CELL
  pure_quanta q_cap *
  page107_i238
#ISCELL
  pure_quanta_power universal_power *
  page107_i239
#ISCELL
  mstr_standard tap *
  page107_i24
#ISCELL
  mstr_standard offpage *
  page107_i240
#CELL
  pure_quanta q_res *
  page107_i241
#CELL
  pure_quanta q_res *
  page107_i242
#ISCELL
  mstr_standard offpage *
  page107_i243
#ISCELL
  mstr_standard tap *
  page107_i25
#ISCELL
  mstr_standard tap *
  page107_i26
#ISCELL
  mstr_standard tap *
  page107_i27
#ISCELL
  mstr_standard tap *
  page107_i28
#ISCELL
  mstr_standard tap *
  page107_i29
#ISCELL
  mstr_standard tap *
  page107_i30
#ISCELL
  mstr_standard tap *
  page107_i31
#ISCELL
  mstr_standard tap *
  page107_i32
#ISCELL
  mstr_standard tap *
  page107_i33
#ISCELL
  mstr_standard tap *
  page107_i34
#ISCELL
  mstr_standard tap *
  page107_i35
#ISCELL
  mstr_standard tap *
  page107_i36
#ISCELL
  mstr_standard tap *
  page107_i37
#ISCELL
  mstr_standard tap *
  page107_i38
#ISCELL
  mstr_standard tap *
  page107_i39
#ISCELL
  mstr_standard tap *
  page107_i40
#ISCELL
  mstr_standard tap *
  page107_i41
#ISCELL
  mstr_standard tap *
  page107_i42
#ISCELL
  mstr_standard tap *
  page107_i43
#ISCELL
  mstr_standard tap *
  page107_i44
#ISCELL
  mstr_standard tap *
  page107_i45
#ISCELL
  mstr_standard tap *
  page107_i46
#ISCELL
  mstr_standard tap *
  page107_i47
#ISCELL
  mstr_standard tap *
  page107_i48
#ISCELL
  mstr_standard tap *
  page107_i49
#ISCELL
  mstr_standard tap *
  page107_i50
#ISCELL
  mstr_standard tap *
  page107_i51
#ISCELL
  mstr_standard tap *
  page107_i52
#ISCELL
  mstr_standard tap *
  page107_i53
#ISCELL
  mstr_standard tap *
  page107_i54
#ISCELL
  mstr_standard tap *
  page107_i55
#ISCELL
  mstr_standard tap *
  page107_i56
#ISCELL
  mstr_standard tap *
  page107_i57
#ISCELL
  mstr_standard tap *
  page107_i58
#ISCELL
  mstr_standard tap *
  page107_i59
#ISCELL
  mstr_standard offpage *
  page107_i6
#ISCELL
  mstr_standard tap *
  page107_i60
#ISCELL
  mstr_standard tap *
  page107_i61
#ISCELL
  mstr_standard tap *
  page107_i62
#ISCELL
  mstr_standard tap *
  page107_i63
#ISCELL
  mstr_symbols vcc_core *
  page107_i7
#ISCELL
  mstr_standard tap *
  page107_i71
#ISCELL
  mstr_standard tap *
  page107_i72
#ISCELL
  mstr_standard tap *
  page107_i73
#ISCELL
  mstr_standard tap *
  page107_i74
#ISCELL
  mstr_standard tap *
  page107_i75
#ISCELL
  mstr_standard tap *
  page107_i76
#ISCELL
  mstr_standard tap *
  page107_i77
#ISCELL
  mstr_standard tap *
  page107_i78
#ISCELL
  mstr_standard tap *
  page107_i79
#ISCELL
  mstr_standard offpage *
  page107_i8
#ISCELL
  mstr_standard tap *
  page107_i80
#ISCELL
  mstr_standard tap *
  page107_i81
#ISCELL
  mstr_standard tap *
  page107_i82
#ISCELL
  mstr_standard tap *
  page107_i83
#ISCELL
  mstr_standard tap *
  page107_i84
#ISCELL
  mstr_standard tap *
  page107_i85
#ISCELL
  mstr_standard tap *
  page107_i86
#ISCELL
  mstr_standard tap *
  page107_i87
#ISCELL
  mstr_standard tap *
  page107_i88
#ISCELL
  mstr_standard tap *
  page107_i89
#ISCELL
  mstr_standard offpage *
  page107_i9
#ISCELL
  mstr_standard tap *
  page107_i90
#ISCELL
  mstr_standard tap *
  page107_i91
#ISCELL
  mstr_standard tap *
  page107_i92
#ISCELL
  mstr_standard tap *
  page107_i93
#ISCELL
  mstr_standard tap *
  page107_i94
#ISCELL
  mstr_standard tap *
  page107_i95
#ISCELL
  mstr_standard tap *
  page107_i96
#ISCELL
  mstr_standard tap *
  page107_i97
#ISCELL
  mstr_standard tap *
  page107_i98
#ISCELL
  mstr_standard tap *
  page107_i99
#ISCELL
  mstr_misc dns *
  *
#ISCELL
  pure_quanta quanta_title_block_c *
  *
#ISCELL
  mstr_standard tap *
  page108_i100
#ISCELL
  mstr_standard tap *
  page108_i101
#ISCELL
  mstr_standard tap *
  page108_i102
#ISCELL
  mstr_standard tap *
  page108_i103
#ISCELL
  mstr_standard tap *
  page108_i104
#ISCELL
  mstr_standard tap *
  page108_i105
#ISCELL
  mstr_standard tap *
  page108_i106
#ISCELL
  mstr_standard tap *
  page108_i107
#ISCELL
  mstr_standard tap *
  page108_i108
#ISCELL
  mstr_standard tap *
  page108_i109
#ISCELL
  mstr_standard offpage *
  page108_i11
#ISCELL
  mstr_standard tap *
  page108_i110
#ISCELL
  mstr_standard tap *
  page108_i111
#ISCELL
  mstr_standard tap *
  page108_i112
#ISCELL
  mstr_standard tap *
  page108_i113
#ISCELL
  mstr_standard tap *
  page108_i114
#ISCELL
  mstr_standard tap *
  page108_i115
#ISCELL
  mstr_standard tap *
  page108_i116
#ISCELL
  mstr_standard tap *
  page108_i117
#ISCELL
  mstr_standard tap *
  page108_i118
#ISCELL
  mstr_standard tap *
  page108_i119
#ISCELL
  mstr_standard offpage *
  page108_i12
#ISCELL
  mstr_standard tap *
  page108_i120
#ISCELL
  mstr_standard tap *
  page108_i121
#ISCELL
  mstr_standard tap *
  page108_i122
#ISCELL
  mstr_standard tap *
  page108_i123
#ISCELL
  mstr_standard offpage *
  page108_i124
#ISCELL
  mstr_standard offpage *
  page108_i125
#ISCELL
  mstr_symbols gnd *
  page108_i126
#ISCELL
  mstr_standard offpage *
  page108_i127
#ISCELL
  mstr_standard offpage *
  page108_i13
#CELL
  pure_quanta q_res *
  page108_i136
#ISCELL
  mstr_symbols gnd *
  page108_i137
#CELL
  pure_quanta sconn288_ddr506112002kq *
  page108_i138
#ISCELL
  mstr_symbols gnd *
  page108_i139
#ISCELL
  mstr_standard offpage *
  page108_i14
#ISCELL
  mstr_standard offpage *
  page108_i15
#ISCELL
  mstr_standard offpage *
  page108_i16
#ISCELL
  mstr_standard offpage *
  page108_i17
#ISCELL
  mstr_standard offpage *
  page108_i18
#CELL
  pure_quanta q_cap *
  page108_i185
#ISCELL
  mstr_symbols gnd *
  page108_i186
#ISCELL
  mstr_standard offpage *
  page108_i187
#CELL
  pure_quanta q_res *
  page108_i188
#ISCELL
  mstr_symbols vcc_core *
  page108_i189
#ISCELL
  mstr_standard offpage *
  page108_i19
#CELL
  pure_quanta q_res *
  page108_i190
#ISCELL
  mstr_standard offpage *
  page108_i191
#ISCELL
  mstr_standard offpage *
  page108_i192
#ISCELL
  mstr_standard offpage *
  page108_i193
#ISCELL
  mstr_standard offpage *
  page108_i194
#ISCELL
  mstr_standard tap *
  page108_i195
#ISCELL
  mstr_standard tap *
  page108_i196
#ISCELL
  mstr_standard tap *
  page108_i197
#ISCELL
  mstr_standard tap *
  page108_i198
#ISCELL
  mstr_standard tap *
  page108_i199
#ISCELL
  mstr_standard offpage *
  page108_i2
#ISCELL
  mstr_standard offpage *
  page108_i20
#ISCELL
  mstr_standard tap *
  page108_i200
#ISCELL
  mstr_standard tap *
  page108_i201
#ISCELL
  mstr_standard tap *
  page108_i202
#ISCELL
  mstr_standard tap *
  page108_i203
#ISCELL
  mstr_standard tap *
  page108_i204
#ISCELL
  mstr_standard tap *
  page108_i205
#ISCELL
  mstr_standard tap *
  page108_i206
#ISCELL
  mstr_standard tap *
  page108_i207
#ISCELL
  mstr_standard tap *
  page108_i208
#ISCELL
  mstr_standard tap *
  page108_i209
#ISCELL
  mstr_standard offpage *
  page108_i21
#ISCELL
  mstr_standard tap *
  page108_i210
#ISCELL
  mstr_standard tap *
  page108_i211
#ISCELL
  mstr_standard tap *
  page108_i212
#ISCELL
  mstr_standard tap *
  page108_i213
#ISCELL
  mstr_standard tap *
  page108_i214
#ISCELL
  mstr_standard tap *
  page108_i215
#ISCELL
  mstr_standard tap *
  page108_i216
#ISCELL
  mstr_standard tap *
  page108_i217
#ISCELL
  mstr_standard tap *
  page108_i218
#ISCELL
  mstr_standard tap *
  page108_i219
#CELL
  pure_quanta sconn288_ddr506112002kq *
  page108_i22
#ISCELL
  mstr_standard tap *
  page108_i220
#ISCELL
  mstr_standard tap *
  page108_i221
#ISCELL
  mstr_standard tap *
  page108_i222
#ISCELL
  mstr_standard tap *
  page108_i223
#ISCELL
  mstr_standard tap *
  page108_i224
#ISCELL
  mstr_standard tap *
  page108_i225
#ISCELL
  mstr_standard tap *
  page108_i226
#ISCELL
  mstr_standard tap *
  page108_i227
#ISCELL
  mstr_standard tap *
  page108_i228
#ISCELL
  mstr_standard tap *
  page108_i229
#ISCELL
  mstr_standard tap *
  page108_i23
#ISCELL
  mstr_standard tap *
  page108_i230
#ISCELL
  mstr_standard tap *
  page108_i231
#ISCELL
  mstr_standard tap *
  page108_i232
#ISCELL
  mstr_standard tap *
  page108_i233
#ISCELL
  mstr_standard tap *
  page108_i234
#CELL
  pure_quanta sconn288_ddr506112002kq *
  page108_i235
#ISCELL
  pure_quanta_power gnd *
  page108_i236
#CELL
  pure_quanta q_cap *
  page108_i237
#CELL
  pure_quanta q_cap *
  page108_i238
#ISCELL
  pure_quanta_power universal_power *
  page108_i239
#ISCELL
  mstr_standard tap *
  page108_i24
#ISCELL
  mstr_standard offpage *
  page108_i240
#CELL
  pure_quanta q_res *
  page108_i241
#CELL
  pure_quanta q_res *
  page108_i242
#ISCELL
  mstr_standard offpage *
  page108_i243
#ISCELL
  mstr_standard tap *
  page108_i25
#ISCELL
  mstr_standard tap *
  page108_i26
#ISCELL
  mstr_standard tap *
  page108_i27
#ISCELL
  mstr_standard tap *
  page108_i28
#ISCELL
  mstr_standard tap *
  page108_i29
#ISCELL
  mstr_standard offpage *
  page108_i3
#ISCELL
  mstr_standard tap *
  page108_i30
#ISCELL
  mstr_standard tap *
  page108_i31
#ISCELL
  mstr_standard tap *
  page108_i32
#ISCELL
  mstr_standard tap *
  page108_i33
#ISCELL
  mstr_standard tap *
  page108_i34
#ISCELL
  mstr_standard tap *
  page108_i35
#ISCELL
  mstr_standard tap *
  page108_i36
#ISCELL
  mstr_standard tap *
  page108_i37
#ISCELL
  mstr_standard tap *
  page108_i38
#ISCELL
  mstr_standard tap *
  page108_i39
#ISCELL
  mstr_standard offpage *
  page108_i4
#ISCELL
  mstr_standard tap *
  page108_i40
#ISCELL
  mstr_standard tap *
  page108_i41
#ISCELL
  mstr_standard tap *
  page108_i42
#ISCELL
  mstr_standard tap *
  page108_i43
#ISCELL
  mstr_standard tap *
  page108_i44
#ISCELL
  mstr_standard tap *
  page108_i45
#ISCELL
  mstr_standard tap *
  page108_i46
#ISCELL
  mstr_standard tap *
  page108_i47
#ISCELL
  mstr_standard tap *
  page108_i48
#ISCELL
  mstr_standard tap *
  page108_i49
#ISCELL
  mstr_symbols vcc_core *
  page108_i5
#ISCELL
  mstr_standard tap *
  page108_i50
#ISCELL
  mstr_standard tap *
  page108_i51
#ISCELL
  mstr_standard tap *
  page108_i52
#ISCELL
  mstr_standard tap *
  page108_i53
#ISCELL
  mstr_standard tap *
  page108_i54
#ISCELL
  mstr_standard tap *
  page108_i55
#ISCELL
  mstr_standard tap *
  page108_i56
#ISCELL
  mstr_standard tap *
  page108_i57
#ISCELL
  mstr_standard tap *
  page108_i58
#ISCELL
  mstr_standard tap *
  page108_i59
#ISCELL
  mstr_standard offpage *
  page108_i6
#ISCELL
  mstr_standard tap *
  page108_i60
#ISCELL
  mstr_standard tap *
  page108_i61
#ISCELL
  mstr_standard tap *
  page108_i69
#ISCELL
  mstr_standard tap *
  page108_i70
#ISCELL
  mstr_standard tap *
  page108_i71
#ISCELL
  mstr_standard tap *
  page108_i72
#ISCELL
  mstr_standard tap *
  page108_i73
#ISCELL
  mstr_standard tap *
  page108_i74
#ISCELL
  mstr_standard tap *
  page108_i75
#ISCELL
  mstr_standard tap *
  page108_i76
#ISCELL
  mstr_standard tap *
  page108_i77
#ISCELL
  mstr_standard tap *
  page108_i78
#ISCELL
  mstr_standard tap *
  page108_i79
#ISCELL
  mstr_standard offpage *
  page108_i8
#ISCELL
  mstr_standard tap *
  page108_i80
#ISCELL
  mstr_standard tap *
  page108_i81
#ISCELL
  mstr_standard tap *
  page108_i82
#ISCELL
  mstr_standard tap *
  page108_i83
#ISCELL
  mstr_standard tap *
  page108_i84
#ISCELL
  mstr_standard tap *
  page108_i85
#ISCELL
  mstr_standard tap *
  page108_i86
#ISCELL
  mstr_standard tap *
  page108_i87
#ISCELL
  mstr_standard tap *
  page108_i88
#ISCELL
  mstr_standard tap *
  page108_i89
#ISCELL
  mstr_standard offpage *
  page108_i9
#ISCELL
  mstr_standard tap *
  page108_i90
#ISCELL
  mstr_standard tap *
  page108_i91
#ISCELL
  mstr_standard tap *
  page108_i92
#ISCELL
  mstr_standard tap *
  page108_i93
#ISCELL
  mstr_standard tap *
  page108_i94
#ISCELL
  mstr_standard tap *
  page108_i95
#ISCELL
  mstr_standard tap *
  page108_i96
#ISCELL
  mstr_standard tap *
  page108_i97
#ISCELL
  mstr_standard tap *
  page108_i98
#ISCELL
  mstr_standard tap *
  page108_i99
#ISCELL
  pure_quanta quanta_title_block_c *
  *
#ISCELL
  mstr_misc dns *
  *
#ISCELL
  pure_quanta quanta_title_block_c *
  *
#ISCELL
  pure_quanta_power universal_gnd *
  page110_i1
#ISCELL
  pure_quanta_power universal_gnd *
  page110_i10
#ISCELL
  pure_quanta_power universal_gnd *
  page110_i11
#CELL
  pure_quanta q_res *
  page110_i12
#ISCELL
  pure_quanta_power universal_power *
  page110_i13
#CELL
  pure_quanta q_res *
  page110_i14
#ISCELL
  pure_quanta_power universal_gnd *
  page110_i15
#CELL
  pure_quanta q_res *
  page110_i16
#ISCELL
  pure_quanta_power universal_gnd *
  page110_i17
#CELL
  pure_quanta q_res *
  page110_i18
#CELL
  pure_quanta q_res *
  page110_i19
#CELL
  pure_quanta q_res *
  page110_i2
#ISCELL
  standard offpage *
  page110_i20
#ISCELL
  standard offpage *
  page110_i21
#CELL
  pure_quanta q_res *
  page110_i22
#ISCELL
  pure_quanta_power universal_gnd *
  page110_i23
#ISCELL
  pure_quanta_power universal_gnd *
  page110_i24
#CELL
  pure_quanta q_res *
  page110_i25
#CELL
  pure_quanta q_res *
  page110_i26
#ISCELL
  pure_quanta_power universal_power *
  page110_i27
#ISCELL
  pure_quanta_power universal_gnd *
  page110_i28
#CELL
  pure_quanta q_res *
  page110_i29
#ISCELL
  pure_quanta_power universal_gnd *
  page110_i3
#ISCELL
  standard offpage *
  page110_i30
#ISCELL
  standard offpage *
  page110_i31
#CELL
  pure_quanta q_res *
  page110_i32
#ISCELL
  pure_quanta_power universal_gnd *
  page110_i33
#CELL
  pure_quanta q_res *
  page110_i34
#ISCELL
  pure_quanta_power universal_gnd *
  page110_i35
#CELL
  pure_quanta q_res *
  page110_i36
#CELL
  pure_quanta q_res *
  page110_i37
#ISCELL
  standard offpage *
  page110_i38
#ISCELL
  standard offpage *
  page110_i39
#CELL
  pure_quanta q_res *
  page110_i4
#ISCELL
  pure_quanta_power universal_gnd *
  page110_i40
#ISCELL
  pure_quanta_power universal_gnd *
  page110_i41
#CELL
  pure_quanta q_res *
  page110_i42
#ISCELL
  pure_quanta_power universal_gnd *
  page110_i43
#CELL
  pure_quanta q_res *
  page110_i44
#CELL
  pure_quanta q_res *
  page110_i45
#ISCELL
  pure_quanta_power universal_power *
  page110_i46
#ISCELL
  standard offpage *
  page110_i47
#ISCELL
  standard offpage *
  page110_i48
#ISCELL
  standard offpage *
  page110_i49
#CELL
  pure_quanta q_res *
  page110_i5
#ISCELL
  standard offpage *
  page110_i50
#ISCELL
  standard offpage *
  page110_i51
#ISCELL
  standard offpage *
  page110_i52
#ISCELL
  standard offpage *
  page110_i53
#ISCELL
  standard offpage *
  page110_i54
#ISCELL
  standard offpage *
  page110_i55
#ISCELL
  standard offpage *
  page110_i56
#ISCELL
  standard offpage *
  page110_i57
#ISCELL
  standard offpage *
  page110_i58
#ISCELL
  pure_quanta_power universal_gnd *
  page110_i59
#ISCELL
  pure_quanta_power universal_power *
  page110_i6
#CELL
  pure_quanta q_cap *
  page110_i60
#CELL
  pure_quanta q_cap *
  page110_i61
#CELL
  pure_quanta q_cap *
  page110_i62
#CELL
  pure_quanta pi3eqx12902azlex *
  page110_i63
#CELL
  pure_quanta q_cap *
  page110_i64
#CELL
  pure_quanta q_cap *
  page110_i65
#ISCELL
  pure_quanta_power universal_power *
  page110_i66
#CELL
  pure_quanta q_res *
  page110_i67
#ISCELL
  standard offpage *
  page110_i68
#ISCELL
  pure_quanta_power universal_gnd *
  page110_i7
#ISCELL
  pure_quanta_power universal_gnd *
  page110_i73
#CELL
  pure_quanta q_res *
  page110_i74
#ISCELL
  pure_quanta_power universal_gnd *
  page110_i75
#CELL
  pure_quanta q_res *
  page110_i76
#CELL
  pure_quanta q_res *
  page110_i77
#ISCELL
  standard offpage *
  page110_i78
#ISCELL
  standard offpage *
  page110_i79
#CELL
  pure_quanta q_res *
  page110_i8
#ISCELL
  pure_quanta_power universal_gnd *
  page110_i80
#CELL
  pure_quanta q_res *
  page110_i81
#ISCELL
  standard offpage *
  page110_i82
#ISCELL
  standard offpage *
  page110_i83
#ISCELL
  standard offpage *
  page110_i84
#ISCELL
  standard offpage *
  page110_i85
#ISCELL
  standard offpage *
  page110_i86
#ISCELL
  pure_quanta_power universal_gnd *
  page110_i87
#CELL
  pure_quanta q_res *
  page110_i88
#CELL
  pure_quanta q_res *
  page110_i89
#CELL
  pure_quanta q_res *
  page110_i9
#ISCELL
  pure_quanta_power universal_gnd *
  page110_i90
#ISCELL
  pure_quanta_power universal_power *
  page110_i91
#CELL
  pure_quanta q_res *
  page110_i92
#CELL
  pure_quanta q_res *
  page110_i93
#ISCELL
  pure_quanta_power universal_power *
  page110_i94
#ISCELL
  standard offpage *
  page110_i95
#ISCELL
  standard offpage *
  page110_i96
#ISCELL
  mstr_misc dns *
  *
#ISCELL
  pure_quanta quanta_title_block_c *
  *
#CELL
  pure_quanta ds125br111rtwr *
  page111_i1
#ISCELL
  standard offpage *
  page111_i10
#ISCELL
  standard offpage *
  page111_i11
#CELL
  pure_quanta q_res *
  page111_i12
#ISCELL
  pure_quanta_power universal_gnd *
  page111_i13
#ISCELL
  standard offpage *
  page111_i14
#ISCELL
  standard offpage *
  page111_i15
#ISCELL
  standard offpage *
  page111_i16
#ISCELL
  standard offpage *
  page111_i17
#ISCELL
  standard offpage *
  page111_i18
#ISCELL
  standard offpage *
  page111_i19
#ISCELL
  pure_quanta_power universal_power *
  page111_i2
#ISCELL
  standard offpage *
  page111_i20
#ISCELL
  standard offpage *
  page111_i21
#ISCELL
  standard offpage *
  page111_i22
#CELL
  pure_quanta q_res *
  page111_i23
#ISCELL
  standard offpage *
  page111_i24
#ISCELL
  standard offpage *
  page111_i25
#ISCELL
  standard offpage *
  page111_i26
#ISCELL
  standard offpage *
  page111_i27
#ISCELL
  standard offpage *
  page111_i28
#ISCELL
  pure_quanta_power universal_gnd *
  page111_i29
#CELL
  pure_quanta q_cap *
  page111_i3
#ISCELL
  pure_quanta_power universal_power *
  page111_i30
#CELL
  pure_quanta q_res *
  page111_i32
#ISCELL
  pure_quanta_power universal_gnd *
  page111_i35
#ISCELL
  pure_quanta_power universal_gnd *
  page111_i36
#ISCELL
  standard offpage *
  page111_i37
#ISCELL
  standard offpage *
  page111_i38
#CELL
  pure_quanta q_res *
  page111_i39
#ISCELL
  pure_quanta_power universal_gnd *
  page111_i4
#CELL
  pure_quanta q_res *
  page111_i40
#CELL
  pure_quanta q_res *
  page111_i41
#ISCELL
  standard offpage *
  page111_i42
#ISCELL
  standard offpage *
  page111_i43
#CELL
  pure_quanta q_res *
  page111_i44
#CELL
  pure_quanta q_res *
  page111_i45
#ISCELL
  pure_quanta_power universal_gnd *
  page111_i46
#ISCELL
  pure_quanta_power universal_power *
  page111_i47
#CELL
  pure_quanta q_res *
  page111_i48
#CELL
  pure_quanta q_res *
  page111_i49
#CELL
  pure_quanta q_cap *
  page111_i5
#ISCELL
  pure_quanta_power universal_gnd *
  page111_i50
#ISCELL
  standard offpage *
  page111_i51
#ISCELL
  standard offpage *
  page111_i52
#CELL
  pure_quanta q_res *
  page111_i53
#ISCELL
  pure_quanta_power universal_gnd *
  page111_i55
#ISCELL
  pure_quanta_power universal_power *
  page111_i56
#CELL
  pure_quanta q_res *
  page111_i57
#CELL
  pure_quanta q_res *
  page111_i58
#ISCELL
  pure_quanta_power universal_gnd *
  page111_i59
#CELL
  pure_quanta q_cap *
  page111_i6
#CELL
  pure_quanta q_res *
  page111_i60
#ISCELL
  standard offpage *
  page111_i61
#CELL
  pure_quanta q_res *
  page111_i63
#CELL
  pure_quanta q_res *
  page111_i64
#ISCELL
  pure_quanta_power universal_gnd *
  page111_i65
#ISCELL
  pure_quanta_power universal_power *
  page111_i66
#ISCELL
  pure_quanta_power universal_gnd *
  page111_i67
#CELL
  pure_quanta q_res *
  page111_i68
#CELL
  pure_quanta q_cap *
  page111_i7
#ISCELL
  pure_quanta_power universal_power *
  page111_i70
#ISCELL
  standard offpage *
  page111_i71
#ISCELL
  pure_quanta_power universal_gnd *
  page111_i72
#CELL
  pure_quanta q_res *
  page111_i73
#ISCELL
  pure_quanta_power universal_power *
  page111_i75
#ISCELL
  standard offpage *
  page111_i76
#CELL
  pure_quanta q_res *
  page111_i77
#CELL
  pure_quanta q_res *
  page111_i78
#ISCELL
  standard offpage *
  page111_i8
#ISCELL
  standard offpage *
  page111_i9
#ISCELL
  pure_quanta quanta_title_block_c *
  *
#ISCELL
  pure_quanta_power cad_note *
  *
#CELL
  pure_quanta q_res *
  page112_i1
#ISCELL
  standard offpage *
  page112_i10
#CELL
  pure_quanta q_cap *
  page112_i11
#CELL
  pure_quanta q_cap *
  page112_i12
#CELL
  pure_quanta q_cap *
  page112_i13
#CELL
  pure_quanta q_cap *
  page112_i14
#ISCELL
  standard offpage *
  page112_i15
#ISCELL
  standard offpage *
  page112_i16
#ISCELL
  standard offpage *
  page112_i17
#ISCELL
  standard offpage *
  page112_i18
#ISCELL
  standard offpage *
  page112_i19
#CELL
  pure_quanta q_res *
  page112_i2
#ISCELL
  standard offpage *
  page112_i20
#CELL
  pure_quanta q_res *
  page112_i21
#CELL
  pure_quanta q_res *
  page112_i22
#CELL
  pure_quanta q_res *
  page112_i23
#CELL
  pure_quanta q_res *
  page112_i24
#ISCELL
  standard offpage *
  page112_i25
#ISCELL
  standard offpage *
  page112_i26
#CELL
  pure_quanta q_res *
  page112_i3
#ISCELL
  standard offpage *
  page112_i33
#ISCELL
  standard offpage *
  page112_i34
#CELL
  pure_quanta q_cap *
  page112_i35
#CELL
  pure_quanta q_cap *
  page112_i36
#ISCELL
  standard offpage *
  page112_i37
#ISCELL
  standard offpage *
  page112_i38
#ISCELL
  standard offpage *
  page112_i39
#ISCELL
  standard offpage *
  page112_i4
#ISCELL
  standard offpage *
  page112_i40
#CELL
  pure_quanta q_cap *
  page112_i43
#CELL
  pure_quanta q_cap *
  page112_i44
#ISCELL
  standard offpage *
  page112_i45
#ISCELL
  standard offpage *
  page112_i46
#ISCELL
  standard offpage *
  page112_i47
#ISCELL
  standard offpage *
  page112_i48
#ISCELL
  standard offpage *
  page112_i5
#ISCELL
  standard offpage *
  page112_i6
#ISCELL
  standard offpage *
  page112_i7
#CELL
  pure_quanta q_res *
  page112_i8
#ISCELL
  standard offpage *
  page112_i9
#ISCELL
  pure_quanta quanta_title_block_c *
  *
#ISCELL
  pure_quanta quanta_title_block_c *
  *
#ISCELL
  standard offpage *
  page326_i1
#ISCELL
  standard offpage *
  page326_i10
#ISCELL
  standard offpage *
  page326_i11
#ISCELL
  standard offpage *
  page326_i12
#ISCELL
  standard offpage *
  page326_i13
#ISCELL
  standard offpage *
  page326_i14
#ISCELL
  standard offpage *
  page326_i15
#ISCELL
  standard offpage *
  page326_i16
#ISCELL
  standard offpage *
  page326_i17
#ISCELL
  standard offpage *
  page326_i18
#ISCELL
  pure_quanta_power universal_gnd *
  page326_i19
#ISCELL
  standard offpage *
  page326_i2
#ISCELL
  standard offpage *
  page326_i20
#ISCELL
  standard offpage *
  page326_i21
#ISCELL
  standard offpage *
  page326_i22
#ISCELL
  standard offpage *
  page326_i23
#ISCELL
  standard offpage *
  page326_i24
#ISCELL
  standard offpage *
  page326_i25
#ISCELL
  standard offpage *
  page326_i26
#ISCELL
  standard offpage *
  page326_i27
#ISCELL
  standard offpage *
  page326_i28
#ISCELL
  standard offpage *
  page326_i29
#ISCELL
  standard offpage *
  page326_i3
#ISCELL
  standard offpage *
  page326_i30
#ISCELL
  standard offpage *
  page326_i31
#ISCELL
  standard offpage *
  page326_i32
#ISCELL
  standard offpage *
  page326_i33
#ISCELL
  standard offpage *
  page326_i34
#ISCELL
  standard offpage *
  page326_i35
#ISCELL
  standard offpage *
  page326_i36
#ISCELL
  standard offpage *
  page326_i37
#ISCELL
  standard offpage *
  page326_i38
#ISCELL
  standard offpage *
  page326_i39
#ISCELL
  standard offpage *
  page326_i4
#ISCELL
  standard offpage *
  page326_i40
#ISCELL
  standard offpage *
  page326_i41
#ISCELL
  standard offpage *
  page326_i42
#ISCELL
  standard offpage *
  page326_i43
#ISCELL
  standard offpage *
  page326_i44
#ISCELL
  standard offpage *
  page326_i45
#ISCELL
  standard offpage *
  page326_i46
#ISCELL
  standard offpage *
  page326_i47
#ISCELL
  standard offpage *
  page326_i48
#ISCELL
  standard offpage *
  page326_i49
#ISCELL
  standard offpage *
  page326_i5
#ISCELL
  standard offpage *
  page326_i50
#ISCELL
  standard offpage *
  page326_i51
#ISCELL
  standard offpage *
  page326_i52
#ISCELL
  standard offpage *
  page326_i53
#ISCELL
  standard offpage *
  page326_i54
#ISCELL
  standard offpage *
  page326_i55
#ISCELL
  standard offpage *
  page326_i56
#ISCELL
  standard offpage *
  page326_i57
#ISCELL
  standard offpage *
  page326_i58
#ISCELL
  standard offpage *
  page326_i59
#ISCELL
  standard offpage *
  page326_i6
#ISCELL
  standard offpage *
  page326_i60
#ISCELL
  standard offpage *
  page326_i61
#ISCELL
  standard offpage *
  page326_i62
#ISCELL
  standard offpage *
  page326_i63
#ISCELL
  standard offpage *
  page326_i64
#ISCELL
  standard offpage *
  page326_i65
#ISCELL
  standard offpage *
  page326_i66
#ISCELL
  standard offpage *
  page326_i67
#ISCELL
  standard offpage *
  page326_i68
#ISCELL
  standard offpage *
  page326_i69
#ISCELL
  standard offpage *
  page326_i7
#ISCELL
  standard offpage *
  page326_i70
#ISCELL
  standard offpage *
  page326_i71
#ISCELL
  standard offpage *
  page326_i72
#ISCELL
  standard offpage *
  page326_i73
#ISCELL
  pure_quanta_power universal_gnd *
  page326_i74
#CELL
  pure_quanta conn112_10137002101lf *
  page326_i75
#CELL
  pure_quanta conn112_10137002101lf *
  page326_i76
#ISCELL
  standard offpage *
  page326_i8
#ISCELL
  standard offpage *
  page326_i9
#ISCELL
  pure_quanta quanta_title_block_c *
  *
#ISCELL
  standard offpage *
  page327_i1
#ISCELL
  standard offpage *
  page327_i10
#ISCELL
  standard offpage *
  page327_i11
#ISCELL
  standard offpage *
  page327_i12
#ISCELL
  standard offpage *
  page327_i13
#ISCELL
  standard offpage *
  page327_i14
#ISCELL
  standard offpage *
  page327_i15
#ISCELL
  standard offpage *
  page327_i16
#ISCELL
  standard offpage *
  page327_i17
#ISCELL
  pure_quanta_power universal_gnd *
  page327_i18
#CELL
  pure_quanta conn112_10137002101lf *
  page327_i19
#ISCELL
  standard offpage *
  page327_i2
#ISCELL
  standard offpage *
  page327_i20
#ISCELL
  standard offpage *
  page327_i21
#ISCELL
  standard offpage *
  page327_i22
#ISCELL
  standard offpage *
  page327_i23
#ISCELL
  standard offpage *
  page327_i24
#ISCELL
  standard offpage *
  page327_i25
#ISCELL
  standard offpage *
  page327_i26
#ISCELL
  standard offpage *
  page327_i27
#ISCELL
  standard offpage *
  page327_i28
#ISCELL
  standard offpage *
  page327_i29
#ISCELL
  standard offpage *
  page327_i3
#ISCELL
  standard offpage *
  page327_i30
#ISCELL
  standard offpage *
  page327_i31
#ISCELL
  standard offpage *
  page327_i32
#ISCELL
  standard offpage *
  page327_i33
#ISCELL
  standard offpage *
  page327_i34
#ISCELL
  standard offpage *
  page327_i35
#ISCELL
  standard offpage *
  page327_i36
#ISCELL
  standard offpage *
  page327_i37
#ISCELL
  standard offpage *
  page327_i38
#ISCELL
  standard offpage *
  page327_i39
#ISCELL
  standard offpage *
  page327_i4
#ISCELL
  standard offpage *
  page327_i40
#ISCELL
  standard offpage *
  page327_i41
#ISCELL
  standard offpage *
  page327_i42
#ISCELL
  standard offpage *
  page327_i43
#ISCELL
  standard offpage *
  page327_i44
#ISCELL
  standard offpage *
  page327_i45
#ISCELL
  standard offpage *
  page327_i46
#ISCELL
  standard offpage *
  page327_i47
#ISCELL
  standard offpage *
  page327_i48
#ISCELL
  standard offpage *
  page327_i49
#ISCELL
  standard offpage *
  page327_i5
#ISCELL
  standard offpage *
  page327_i50
#ISCELL
  standard offpage *
  page327_i51
#ISCELL
  standard offpage *
  page327_i52
#ISCELL
  standard offpage *
  page327_i53
#ISCELL
  standard offpage *
  page327_i54
#ISCELL
  pure_quanta_power universal_gnd *
  page327_i55
#ISCELL
  standard offpage *
  page327_i56
#ISCELL
  standard offpage *
  page327_i57
#ISCELL
  standard offpage *
  page327_i58
#ISCELL
  standard offpage *
  page327_i59
#ISCELL
  standard offpage *
  page327_i6
#ISCELL
  standard offpage *
  page327_i60
#ISCELL
  standard offpage *
  page327_i61
#ISCELL
  standard offpage *
  page327_i62
#ISCELL
  standard offpage *
  page327_i63
#ISCELL
  standard offpage *
  page327_i64
#ISCELL
  standard offpage *
  page327_i65
#ISCELL
  standard offpage *
  page327_i66
#ISCELL
  standard offpage *
  page327_i67
#ISCELL
  standard offpage *
  page327_i68
#ISCELL
  standard offpage *
  page327_i69
#ISCELL
  standard offpage *
  page327_i7
#ISCELL
  standard offpage *
  page327_i70
#ISCELL
  standard offpage *
  page327_i71
#ISCELL
  standard offpage *
  page327_i72
#ISCELL
  standard offpage *
  page327_i73
#CELL
  pure_quanta conn112_10137002101lf *
  page327_i74
#ISCELL
  standard offpage *
  page327_i75
#ISCELL
  standard offpage *
  page327_i8
#ISCELL
  standard offpage *
  page327_i9
#ISCELL
  pure_quanta quanta_title_block_c *
  *
#ISCELL
  standard offpage *
  page317_i1
#ISCELL
  standard offpage *
  page317_i10
#ISCELL
  standard offpage *
  page317_i11
#ISCELL
  standard offpage *
  page317_i12
#ISCELL
  pure_quanta_power universal_gnd *
  page317_i13
#ISCELL
  standard offpage *
  page317_i14
#ISCELL
  standard offpage *
  page317_i15
#ISCELL
  standard offpage *
  page317_i16
#ISCELL
  standard offpage *
  page317_i17
#ISCELL
  standard offpage *
  page317_i18
#ISCELL
  standard offpage *
  page317_i19
#ISCELL
  standard offpage *
  page317_i2
#ISCELL
  standard offpage *
  page317_i20
#ISCELL
  standard offpage *
  page317_i21
#ISCELL
  standard offpage *
  page317_i22
#ISCELL
  standard offpage *
  page317_i23
#ISCELL
  standard offpage *
  page317_i24
#ISCELL
  standard offpage *
  page317_i25
#ISCELL
  standard offpage *
  page317_i26
#ISCELL
  standard offpage *
  page317_i27
#ISCELL
  standard offpage *
  page317_i28
#ISCELL
  standard offpage *
  page317_i29
#ISCELL
  standard offpage *
  page317_i3
#ISCELL
  standard offpage *
  page317_i30
#ISCELL
  standard offpage *
  page317_i31
#ISCELL
  standard offpage *
  page317_i32
#ISCELL
  standard offpage *
  page317_i33
#ISCELL
  standard offpage *
  page317_i34
#ISCELL
  standard offpage *
  page317_i35
#ISCELL
  standard offpage *
  page317_i36
#ISCELL
  standard offpage *
  page317_i37
#ISCELL
  standard offpage *
  page317_i38
#ISCELL
  standard offpage *
  page317_i39
#ISCELL
  standard offpage *
  page317_i4
#ISCELL
  standard offpage *
  page317_i40
#ISCELL
  standard offpage *
  page317_i41
#ISCELL
  standard offpage *
  page317_i42
#ISCELL
  standard offpage *
  page317_i43
#ISCELL
  standard offpage *
  page317_i44
#ISCELL
  standard offpage *
  page317_i45
#ISCELL
  standard offpage *
  page317_i46
#ISCELL
  standard offpage *
  page317_i47
#ISCELL
  pure_quanta_power universal_gnd *
  page317_i48
#CELL
  pure_quanta conn112_10137002101lf *
  page317_i49
#ISCELL
  standard offpage *
  page317_i5
#ISCELL
  standard offpage *
  page317_i50
#ISCELL
  standard offpage *
  page317_i51
#ISCELL
  standard offpage *
  page317_i52
#ISCELL
  standard offpage *
  page317_i53
#ISCELL
  standard offpage *
  page317_i54
#ISCELL
  standard offpage *
  page317_i55
#ISCELL
  standard offpage *
  page317_i56
#ISCELL
  standard offpage *
  page317_i57
#ISCELL
  standard offpage *
  page317_i58
#ISCELL
  standard offpage *
  page317_i59
#ISCELL
  standard offpage *
  page317_i6
#ISCELL
  standard offpage *
  page317_i60
#ISCELL
  standard offpage *
  page317_i61
#ISCELL
  standard offpage *
  page317_i62
#ISCELL
  standard offpage *
  page317_i63
#ISCELL
  standard offpage *
  page317_i64
#ISCELL
  standard offpage *
  page317_i65
#ISCELL
  standard offpage *
  page317_i66
#ISCELL
  standard offpage *
  page317_i67
#ISCELL
  standard offpage *
  page317_i68
#ISCELL
  standard offpage *
  page317_i69
#ISCELL
  standard offpage *
  page317_i7
#CELL
  pure_quanta conn112_10137002101lf *
  page317_i70
#ISCELL
  standard offpage *
  page317_i71
#ISCELL
  standard offpage *
  page317_i8
#ISCELL
  standard offpage *
  page317_i9
#ISCELL
  pure_quanta quanta_title_block_c *
  *
#ISCELL
  standard offpage *
  page320_i1
#ISCELL
  standard offpage *
  page320_i10
#ISCELL
  standard offpage *
  page320_i11
#ISCELL
  standard offpage *
  page320_i12
#ISCELL
  standard offpage *
  page320_i13
#ISCELL
  pure_quanta_power universal_gnd *
  page320_i14
#CELL
  pure_quanta conn112_10137002101lf *
  page320_i15
#ISCELL
  standard offpage *
  page320_i16
#ISCELL
  standard offpage *
  page320_i17
#ISCELL
  standard offpage *
  page320_i18
#ISCELL
  standard offpage *
  page320_i19
#ISCELL
  standard offpage *
  page320_i2
#ISCELL
  standard offpage *
  page320_i20
#ISCELL
  standard offpage *
  page320_i21
#ISCELL
  standard offpage *
  page320_i22
#ISCELL
  standard offpage *
  page320_i23
#ISCELL
  standard offpage *
  page320_i24
#ISCELL
  standard offpage *
  page320_i25
#ISCELL
  standard offpage *
  page320_i26
#ISCELL
  standard offpage *
  page320_i27
#ISCELL
  standard offpage *
  page320_i28
#ISCELL
  standard offpage *
  page320_i29
#ISCELL
  standard offpage *
  page320_i3
#ISCELL
  standard offpage *
  page320_i30
#ISCELL
  standard offpage *
  page320_i31
#ISCELL
  standard offpage *
  page320_i32
#ISCELL
  standard offpage *
  page320_i33
#ISCELL
  standard offpage *
  page320_i34
#ISCELL
  standard offpage *
  page320_i35
#ISCELL
  standard offpage *
  page320_i36
#ISCELL
  standard offpage *
  page320_i37
#ISCELL
  standard offpage *
  page320_i38
#ISCELL
  standard offpage *
  page320_i39
#ISCELL
  standard offpage *
  page320_i4
#ISCELL
  standard offpage *
  page320_i40
#ISCELL
  standard offpage *
  page320_i41
#ISCELL
  standard offpage *
  page320_i42
#ISCELL
  standard offpage *
  page320_i43
#ISCELL
  standard offpage *
  page320_i44
#ISCELL
  standard offpage *
  page320_i45
#ISCELL
  standard offpage *
  page320_i46
#ISCELL
  standard offpage *
  page320_i47
#ISCELL
  standard offpage *
  page320_i48
#ISCELL
  standard offpage *
  page320_i49
#ISCELL
  standard offpage *
  page320_i5
#ISCELL
  standard offpage *
  page320_i50
#ISCELL
  pure_quanta_power universal_gnd *
  page320_i51
#ISCELL
  standard offpage *
  page320_i52
#ISCELL
  standard offpage *
  page320_i53
#ISCELL
  standard offpage *
  page320_i54
#ISCELL
  standard offpage *
  page320_i55
#ISCELL
  standard offpage *
  page320_i56
#ISCELL
  standard offpage *
  page320_i57
#ISCELL
  standard offpage *
  page320_i58
#ISCELL
  standard offpage *
  page320_i59
#ISCELL
  standard offpage *
  page320_i6
#ISCELL
  standard offpage *
  page320_i60
#ISCELL
  standard offpage *
  page320_i61
#ISCELL
  standard offpage *
  page320_i62
#ISCELL
  standard offpage *
  page320_i63
#ISCELL
  standard offpage *
  page320_i64
#ISCELL
  standard offpage *
  page320_i65
#ISCELL
  standard offpage *
  page320_i66
#ISCELL
  standard offpage *
  page320_i67
#ISCELL
  standard offpage *
  page320_i68
#ISCELL
  standard offpage *
  page320_i69
#ISCELL
  standard offpage *
  page320_i7
#ISCELL
  standard offpage *
  page320_i70
#ISCELL
  standard offpage *
  page320_i71
#CELL
  pure_quanta conn112_10137002101lf *
  page320_i72
#ISCELL
  standard offpage *
  page320_i73
#ISCELL
  standard offpage *
  page320_i8
#ISCELL
  standard offpage *
  page320_i9
#ISCELL
  pure_quanta quanta_title_block_c *
  *
#ISCELL
  standard offpage *
  page319_i1
#ISCELL
  standard offpage *
  page319_i10
#ISCELL
  standard offpage *
  page319_i11
#ISCELL
  standard offpage *
  page319_i12
#ISCELL
  standard offpage *
  page319_i13
#ISCELL
  standard offpage *
  page319_i14
#ISCELL
  pure_quanta_power universal_gnd *
  page319_i15
#CELL
  pure_quanta conn112_10137002101lf *
  page319_i16
#ISCELL
  standard offpage *
  page319_i17
#ISCELL
  standard offpage *
  page319_i18
#ISCELL
  standard offpage *
  page319_i19
#ISCELL
  standard offpage *
  page319_i2
#ISCELL
  standard offpage *
  page319_i20
#ISCELL
  standard offpage *
  page319_i21
#ISCELL
  standard offpage *
  page319_i22
#ISCELL
  standard offpage *
  page319_i23
#ISCELL
  standard offpage *
  page319_i24
#ISCELL
  standard offpage *
  page319_i25
#ISCELL
  standard offpage *
  page319_i26
#ISCELL
  standard offpage *
  page319_i27
#ISCELL
  standard offpage *
  page319_i28
#ISCELL
  standard offpage *
  page319_i29
#ISCELL
  standard offpage *
  page319_i3
#ISCELL
  standard offpage *
  page319_i30
#ISCELL
  standard offpage *
  page319_i31
#ISCELL
  standard offpage *
  page319_i32
#ISCELL
  standard offpage *
  page319_i33
#ISCELL
  standard offpage *
  page319_i34
#ISCELL
  standard offpage *
  page319_i35
#ISCELL
  standard offpage *
  page319_i36
#ISCELL
  standard offpage *
  page319_i37
#ISCELL
  standard offpage *
  page319_i38
#ISCELL
  standard offpage *
  page319_i39
#ISCELL
  standard offpage *
  page319_i4
#ISCELL
  standard offpage *
  page319_i40
#ISCELL
  standard offpage *
  page319_i41
#ISCELL
  standard offpage *
  page319_i42
#ISCELL
  standard offpage *
  page319_i43
#ISCELL
  standard offpage *
  page319_i44
#ISCELL
  standard offpage *
  page319_i45
#ISCELL
  standard offpage *
  page319_i46
#ISCELL
  standard offpage *
  page319_i47
#ISCELL
  standard offpage *
  page319_i48
#ISCELL
  standard offpage *
  page319_i49
#ISCELL
  standard offpage *
  page319_i5
#ISCELL
  standard offpage *
  page319_i50
#ISCELL
  standard offpage *
  page319_i51
#ISCELL
  standard offpage *
  page319_i52
#ISCELL
  standard offpage *
  page319_i53
#ISCELL
  pure_quanta_power universal_gnd *
  page319_i54
#ISCELL
  standard offpage *
  page319_i55
#ISCELL
  standard offpage *
  page319_i56
#ISCELL
  standard offpage *
  page319_i57
#ISCELL
  standard offpage *
  page319_i58
#ISCELL
  standard offpage *
  page319_i59
#ISCELL
  standard offpage *
  page319_i6
#ISCELL
  standard offpage *
  page319_i60
#ISCELL
  standard offpage *
  page319_i61
#ISCELL
  standard offpage *
  page319_i62
#ISCELL
  standard offpage *
  page319_i63
#ISCELL
  standard offpage *
  page319_i64
#ISCELL
  standard offpage *
  page319_i65
#ISCELL
  standard offpage *
  page319_i66
#ISCELL
  standard offpage *
  page319_i67
#ISCELL
  standard offpage *
  page319_i68
#ISCELL
  standard offpage *
  page319_i69
#ISCELL
  standard offpage *
  page319_i7
#ISCELL
  standard offpage *
  page319_i70
#ISCELL
  standard offpage *
  page319_i71
#ISCELL
  standard offpage *
  page319_i72
#ISCELL
  standard offpage *
  page319_i73
#ISCELL
  standard offpage *
  page319_i74
#ISCELL
  standard offpage *
  page319_i75
#CELL
  pure_quanta conn112_10137002101lf *
  page319_i76
#ISCELL
  standard offpage *
  page319_i8
#ISCELL
  standard offpage *
  page319_i9
#ISCELL
  pure_quanta quanta_title_block_c *
  *
#ISCELL
  standard offpage *
  page318_i1
#ISCELL
  standard offpage *
  page318_i10
#ISCELL
  standard offpage *
  page318_i11
#ISCELL
  standard offpage *
  page318_i12
#ISCELL
  standard offpage *
  page318_i13
#ISCELL
  standard offpage *
  page318_i14
#ISCELL
  pure_quanta_power universal_gnd *
  page318_i15
#CELL
  pure_quanta conn112_10137002101lf *
  page318_i16
#ISCELL
  standard offpage *
  page318_i17
#ISCELL
  standard offpage *
  page318_i18
#ISCELL
  standard offpage *
  page318_i19
#ISCELL
  standard offpage *
  page318_i2
#ISCELL
  standard offpage *
  page318_i20
#ISCELL
  standard offpage *
  page318_i21
#ISCELL
  standard offpage *
  page318_i22
#ISCELL
  standard offpage *
  page318_i23
#ISCELL
  standard offpage *
  page318_i24
#ISCELL
  standard offpage *
  page318_i25
#ISCELL
  standard offpage *
  page318_i26
#ISCELL
  standard offpage *
  page318_i27
#ISCELL
  standard offpage *
  page318_i28
#ISCELL
  standard offpage *
  page318_i29
#ISCELL
  standard offpage *
  page318_i3
#ISCELL
  standard offpage *
  page318_i30
#ISCELL
  standard offpage *
  page318_i31
#ISCELL
  standard offpage *
  page318_i32
#ISCELL
  standard offpage *
  page318_i33
#ISCELL
  standard offpage *
  page318_i34
#ISCELL
  standard offpage *
  page318_i35
#ISCELL
  standard offpage *
  page318_i36
#ISCELL
  standard offpage *
  page318_i37
#ISCELL
  standard offpage *
  page318_i38
#ISCELL
  standard offpage *
  page318_i39
#ISCELL
  standard offpage *
  page318_i4
#ISCELL
  standard offpage *
  page318_i40
#ISCELL
  standard offpage *
  page318_i41
#ISCELL
  standard offpage *
  page318_i42
#ISCELL
  standard offpage *
  page318_i43
#ISCELL
  standard offpage *
  page318_i44
#ISCELL
  standard offpage *
  page318_i45
#ISCELL
  standard offpage *
  page318_i46
#ISCELL
  standard offpage *
  page318_i47
#ISCELL
  standard offpage *
  page318_i48
#ISCELL
  standard offpage *
  page318_i49
#ISCELL
  standard offpage *
  page318_i5
#ISCELL
  standard offpage *
  page318_i50
#ISCELL
  standard offpage *
  page318_i51
#ISCELL
  standard offpage *
  page318_i52
#ISCELL
  pure_quanta_power universal_gnd *
  page318_i53
#ISCELL
  standard offpage *
  page318_i54
#ISCELL
  standard offpage *
  page318_i55
#ISCELL
  standard offpage *
  page318_i56
#ISCELL
  standard offpage *
  page318_i57
#ISCELL
  standard offpage *
  page318_i58
#ISCELL
  standard offpage *
  page318_i59
#ISCELL
  standard offpage *
  page318_i6
#ISCELL
  standard offpage *
  page318_i60
#ISCELL
  standard offpage *
  page318_i61
#ISCELL
  standard offpage *
  page318_i62
#ISCELL
  standard offpage *
  page318_i63
#ISCELL
  standard offpage *
  page318_i64
#ISCELL
  standard offpage *
  page318_i65
#ISCELL
  standard offpage *
  page318_i66
#ISCELL
  standard offpage *
  page318_i67
#ISCELL
  standard offpage *
  page318_i68
#ISCELL
  standard offpage *
  page318_i69
#ISCELL
  standard offpage *
  page318_i7
#ISCELL
  standard offpage *
  page318_i70
#ISCELL
  standard offpage *
  page318_i71
#ISCELL
  standard offpage *
  page318_i72
#ISCELL
  standard offpage *
  page318_i73
#ISCELL
  standard offpage *
  page318_i74
#ISCELL
  standard offpage *
  page318_i75
#CELL
  pure_quanta conn112_10137002101lf *
  page318_i76
#ISCELL
  standard offpage *
  page318_i8
#ISCELL
  standard offpage *
  page318_i9
#ISCELL
  pure_quanta quanta_title_block_c *
  *
#ISCELL
  pure_quanta_power universal_gnd *
  page328_i1
#ISCELL
  standard offpage *
  page328_i10
#ISCELL
  standard offpage *
  page328_i11
#ISCELL
  standard offpage *
  page328_i12
#ISCELL
  standard offpage *
  page328_i13
#ISCELL
  standard offpage *
  page328_i14
#ISCELL
  standard offpage *
  page328_i15
#ISCELL
  standard offpage *
  page328_i16
#ISCELL
  standard offpage *
  page328_i17
#ISCELL
  standard offpage *
  page328_i18
#ISCELL
  standard offpage *
  page328_i19
#ISCELL
  standard offpage *
  page328_i2
#ISCELL
  standard offpage *
  page328_i20
#ISCELL
  standard offpage *
  page328_i21
#ISCELL
  standard offpage *
  page328_i22
#ISCELL
  standard offpage *
  page328_i23
#ISCELL
  standard offpage *
  page328_i24
#ISCELL
  standard offpage *
  page328_i25
#ISCELL
  standard offpage *
  page328_i26
#ISCELL
  standard offpage *
  page328_i27
#ISCELL
  standard offpage *
  page328_i28
#ISCELL
  standard offpage *
  page328_i29
#ISCELL
  standard offpage *
  page328_i3
#ISCELL
  standard offpage *
  page328_i30
#ISCELL
  standard offpage *
  page328_i31
#ISCELL
  standard offpage *
  page328_i32
#ISCELL
  standard offpage *
  page328_i33
#ISCELL
  standard offpage *
  page328_i34
#ISCELL
  standard offpage *
  page328_i35
#ISCELL
  standard offpage *
  page328_i36
#ISCELL
  standard offpage *
  page328_i37
#CELL
  pure_quanta conn112_10137002101lf *
  page328_i38
#ISCELL
  pure_quanta_power universal_gnd *
  page328_i39
#ISCELL
  standard offpage *
  page328_i4
#ISCELL
  standard offpage *
  page328_i40
#ISCELL
  standard offpage *
  page328_i41
#ISCELL
  standard offpage *
  page328_i42
#ISCELL
  standard offpage *
  page328_i43
#ISCELL
  standard offpage *
  page328_i44
#ISCELL
  standard offpage *
  page328_i45
#ISCELL
  standard offpage *
  page328_i46
#ISCELL
  standard offpage *
  page328_i47
#ISCELL
  standard offpage *
  page328_i48
#ISCELL
  standard offpage *
  page328_i49
#ISCELL
  standard offpage *
  page328_i5
#ISCELL
  standard offpage *
  page328_i50
#ISCELL
  standard offpage *
  page328_i51
#ISCELL
  standard offpage *
  page328_i52
#ISCELL
  standard offpage *
  page328_i53
#ISCELL
  standard offpage *
  page328_i54
#ISCELL
  standard offpage *
  page328_i55
#ISCELL
  standard offpage *
  page328_i56
#ISCELL
  standard offpage *
  page328_i57
#ISCELL
  standard offpage *
  page328_i58
#ISCELL
  standard offpage *
  page328_i59
#ISCELL
  standard offpage *
  page328_i6
#ISCELL
  standard offpage *
  page328_i60
#ISCELL
  standard offpage *
  page328_i61
#ISCELL
  standard offpage *
  page328_i62
#ISCELL
  standard offpage *
  page328_i63
#ISCELL
  standard offpage *
  page328_i64
#ISCELL
  standard offpage *
  page328_i65
#ISCELL
  standard offpage *
  page328_i66
#ISCELL
  standard offpage *
  page328_i67
#ISCELL
  standard offpage *
  page328_i68
#ISCELL
  standard offpage *
  page328_i69
#ISCELL
  standard offpage *
  page328_i7
#ISCELL
  standard offpage *
  page328_i70
#ISCELL
  standard offpage *
  page328_i71
#ISCELL
  standard offpage *
  page328_i72
#ISCELL
  standard offpage *
  page328_i73
#ISCELL
  standard offpage *
  page328_i74
#ISCELL
  standard offpage *
  page328_i75
#CELL
  pure_quanta conn112_10137002101lf *
  page328_i76
#ISCELL
  standard offpage *
  page328_i8
#ISCELL
  standard offpage *
  page328_i9
#ISCELL
  pure_quanta quanta_title_block_c *
  *
#ISCELL
  standard offpage *
  page329_i1
#ISCELL
  standard offpage *
  page329_i10
#ISCELL
  standard offpage *
  page329_i100
#ISCELL
  standard offpage *
  page329_i101
#CELL
  pure_quanta conn160_10131762101lf *
  page329_i102
#ISCELL
  standard offpage *
  page329_i11
#ISCELL
  standard offpage *
  page329_i12
#ISCELL
  standard offpage *
  page329_i13
#ISCELL
  standard offpage *
  page329_i14
#ISCELL
  standard offpage *
  page329_i15
#ISCELL
  standard offpage *
  page329_i16
#ISCELL
  standard offpage *
  page329_i17
#ISCELL
  standard offpage *
  page329_i18
#ISCELL
  standard offpage *
  page329_i19
#ISCELL
  standard offpage *
  page329_i2
#ISCELL
  standard offpage *
  page329_i20
#ISCELL
  standard offpage *
  page329_i21
#ISCELL
  standard offpage *
  page329_i22
#ISCELL
  standard offpage *
  page329_i23
#ISCELL
  standard offpage *
  page329_i24
#ISCELL
  standard offpage *
  page329_i25
#ISCELL
  standard offpage *
  page329_i26
#ISCELL
  standard offpage *
  page329_i27
#ISCELL
  standard offpage *
  page329_i28
#ISCELL
  standard offpage *
  page329_i29
#ISCELL
  standard offpage *
  page329_i3
#ISCELL
  standard offpage *
  page329_i30
#ISCELL
  standard offpage *
  page329_i31
#ISCELL
  standard offpage *
  page329_i32
#ISCELL
  standard offpage *
  page329_i33
#ISCELL
  standard offpage *
  page329_i34
#ISCELL
  standard offpage *
  page329_i35
#ISCELL
  standard offpage *
  page329_i36
#ISCELL
  standard offpage *
  page329_i37
#ISCELL
  standard offpage *
  page329_i38
#ISCELL
  standard offpage *
  page329_i39
#ISCELL
  standard offpage *
  page329_i4
#ISCELL
  standard offpage *
  page329_i40
#ISCELL
  standard offpage *
  page329_i41
#ISCELL
  standard offpage *
  page329_i42
#ISCELL
  standard offpage *
  page329_i43
#ISCELL
  standard offpage *
  page329_i44
#ISCELL
  standard offpage *
  page329_i45
#ISCELL
  standard offpage *
  page329_i46
#ISCELL
  standard offpage *
  page329_i47
#ISCELL
  standard offpage *
  page329_i48
#ISCELL
  standard offpage *
  page329_i49
#ISCELL
  standard offpage *
  page329_i5
#ISCELL
  standard offpage *
  page329_i50
#ISCELL
  standard offpage *
  page329_i51
#ISCELL
  standard offpage *
  page329_i52
#ISCELL
  standard offpage *
  page329_i53
#ISCELL
  standard offpage *
  page329_i54
#ISCELL
  standard offpage *
  page329_i55
#ISCELL
  standard offpage *
  page329_i56
#ISCELL
  standard offpage *
  page329_i57
#ISCELL
  standard offpage *
  page329_i58
#ISCELL
  pure_quanta_power universal_gnd *
  page329_i59
#ISCELL
  pure_quanta_power universal_gnd *
  page329_i6
#ISCELL
  standard offpage *
  page329_i60
#ISCELL
  standard offpage *
  page329_i61
#ISCELL
  standard offpage *
  page329_i62
#ISCELL
  standard offpage *
  page329_i63
#ISCELL
  standard offpage *
  page329_i64
#ISCELL
  standard offpage *
  page329_i65
#ISCELL
  standard offpage *
  page329_i66
#ISCELL
  standard offpage *
  page329_i67
#ISCELL
  standard offpage *
  page329_i68
#ISCELL
  standard offpage *
  page329_i69
#CELL
  pure_quanta conn160_10131762101lf *
  page329_i7
#ISCELL
  standard offpage *
  page329_i70
#ISCELL
  standard offpage *
  page329_i71
#ISCELL
  standard offpage *
  page329_i72
#ISCELL
  standard offpage *
  page329_i73
#ISCELL
  standard offpage *
  page329_i74
#ISCELL
  standard offpage *
  page329_i75
#ISCELL
  standard offpage *
  page329_i76
#ISCELL
  standard offpage *
  page329_i77
#ISCELL
  standard offpage *
  page329_i78
#ISCELL
  standard offpage *
  page329_i79
#ISCELL
  standard offpage *
  page329_i8
#ISCELL
  standard offpage *
  page329_i80
#ISCELL
  standard offpage *
  page329_i81
#ISCELL
  standard offpage *
  page329_i82
#ISCELL
  standard offpage *
  page329_i83
#ISCELL
  standard offpage *
  page329_i84
#ISCELL
  standard offpage *
  page329_i85
#ISCELL
  standard offpage *
  page329_i86
#ISCELL
  standard offpage *
  page329_i87
#ISCELL
  standard offpage *
  page329_i88
#ISCELL
  standard offpage *
  page329_i89
#ISCELL
  standard offpage *
  page329_i9
#ISCELL
  standard offpage *
  page329_i90
#ISCELL
  standard offpage *
  page329_i91
#ISCELL
  standard offpage *
  page329_i92
#ISCELL
  standard offpage *
  page329_i93
#ISCELL
  standard offpage *
  page329_i94
#ISCELL
  standard offpage *
  page329_i95
#ISCELL
  standard offpage *
  page329_i96
#ISCELL
  standard offpage *
  page329_i97
#ISCELL
  standard offpage *
  page329_i98
#ISCELL
  standard offpage *
  page329_i99
#ISCELL
  mstr_misc dns *
  *
#ISCELL
  pure_quanta quanta_title_block_c *
  *
#ISCELL
  pure_quanta_power universal_gnd *
  page330_i1
#ISCELL
  standard offpage *
  page330_i10
#ISCELL
  pure_quanta_power universal_gnd *
  page330_i11
#CELL
  pure_quanta q_res *
  page330_i12
#CELL
  pure_quanta q_res *
  page330_i13
#ISCELL
  pure_quanta_power universal_gnd *
  page330_i14
#CELL
  pure_quanta q_res *
  page330_i15
#ISCELL
  pure_quanta_power universal_power *
  page330_i16
#CELL
  pure_quanta q_res *
  page330_i17
#ISCELL
  pure_quanta_power universal_power *
  page330_i18
#ISCELL
  pure_quanta_power universal_gnd *
  page330_i19
#CELL
  pure_quanta q_res *
  page330_i2
#CELL
  pure_quanta q_res *
  page330_i20
#CELL
  pure_quanta mosfet_nch_dual *
  page330_i21
#CELL
  pure_quanta mosfet_nch_dual *
  page330_i22
#CELL
  pure_quanta q_res *
  page330_i23
#ISCELL
  pure_quanta_power universal_power *
  page330_i24
#ISCELL
  pure_quanta_power universal_gnd *
  page330_i25
#CELL
  pure_quanta q_res *
  page330_i26
#ISCELL
  pure_quanta_power universal_power *
  page330_i27
#ISCELL
  pure_quanta_power universal_gnd *
  page330_i28
#CELL
  pure_quanta mosfet_nch_dual *
  page330_i29
#CELL
  pure_quanta mosfet_nch_dual *
  page330_i3
#CELL
  pure_quanta mosfet_nch_dual *
  page330_i30
#CELL
  pure_quanta mosfet_nch_dual *
  page330_i31
#CELL
  pure_quanta q_res *
  page330_i32
#ISCELL
  pure_quanta_power universal_gnd *
  page330_i33
#ISCELL
  pure_quanta_power universal_power *
  page330_i34
#ISCELL
  pure_quanta_power universal_gnd *
  page330_i35
#CELL
  pure_quanta q_cap *
  page330_i36
#ISCELL
  standard offpage *
  page330_i37
#ISCELL
  standard offpage *
  page330_i38
#ISCELL
  standard offpage *
  page330_i39
#ISCELL
  pure_quanta_power universal_gnd *
  page330_i4
#ISCELL
  standard offpage *
  page330_i40
#ISCELL
  pure_quanta_power universal_gnd *
  page330_i41
#CELL
  pure_quanta q_cap *
  page330_i42
#ISCELL
  standard offpage *
  page330_i43
#ISCELL
  pure_quanta_power universal_gnd *
  page330_i44
#CELL
  pure_quanta q_cap *
  page330_i45
#ISCELL
  standard offpage *
  page330_i46
#ISCELL
  standard offpage *
  page330_i47
#ISCELL
  standard offpage *
  page330_i48
#ISCELL
  pure_quanta_power universal_gnd *
  page330_i49
#ISCELL
  pure_quanta_power universal_gnd *
  page330_i5
#CELL
  pure_quanta q_res *
  page330_i50
#CELL
  pure_quanta q_res *
  page330_i51
#CELL
  pure_quanta mosfet_nch_dual *
  page330_i52
#ISCELL
  pure_quanta_power universal_gnd *
  page330_i53
#ISCELL
  pure_quanta_power universal_power *
  page330_i54
#CELL
  pure_quanta q_res *
  page330_i55
#ISCELL
  pure_quanta_power universal_power *
  page330_i56
#CELL
  pure_quanta q_res *
  page330_i57
#ISCELL
  pure_quanta_power universal_power *
  page330_i58
#ISCELL
  standard offpage *
  page330_i59
#ISCELL
  standard offpage *
  page330_i6
#ISCELL
  pure_quanta_power universal_power *
  page330_i60
#CELL
  pure_quanta q_res *
  page330_i61
#ISCELL
  pure_quanta_power universal_power *
  page330_i62
#ISCELL
  pure_quanta_power universal_gnd *
  page330_i63
#CELL
  pure_quanta q_res *
  page330_i64
#CELL
  pure_quanta q_res *
  page330_i65
#CELL
  pure_quanta q_res *
  page330_i66
#CELL
  pure_quanta q_res *
  page330_i67
#ISCELL
  pure_quanta_power universal_gnd *
  page330_i68
#CELL
  pure_quanta q_res *
  page330_i69
#ISCELL
  standard offpage *
  page330_i7
#ISCELL
  pure_quanta_power universal_gnd *
  page330_i70
#CELL
  pure_quanta q_cap *
  page330_i71
#CELL
  pure_quanta q_res *
  page330_i72
#ISCELL
  pure_quanta_power universal_power *
  page330_i73
#ISCELL
  standard offpage *
  page330_i74
#CELL
  pure_quanta mosfet_nch_dual *
  page330_i75
#CELL
  pure_quanta q_res *
  page330_i8
#ISCELL
  pure_quanta_power universal_power *
  page330_i9
#ISCELL
  mstr_misc dns *
  *
#ISCELL
  pure_quanta quanta_title_block_c *
  *
#ISCELL
  standard offpage *
  page331_i1
#ISCELL
  pure_quanta_power universal_power *
  page331_i10
#ISCELL
  pure_quanta_power universal_gnd *
  page331_i100
#ISCELL
  pure_quanta_power universal_gnd *
  page331_i101
#ISCELL
  pure_quanta_power universal_gnd *
  page331_i102
#CELL
  pure_quanta q_res *
  page331_i107
#CELL
  pure_quanta q_res *
  page331_i108
#CELL
  pure_quanta q_res *
  page331_i109
#ISCELL
  pure_quanta_power universal_gnd *
  page331_i11
#CELL
  pure_quanta q_res *
  page331_i110
#CELL
  pure_quanta q_cap *
  page331_i111
#ISCELL
  standard offpage *
  page331_i12
#CELL
  pure_quanta q_res *
  page331_i13
#CELL
  pure_quanta q_res *
  page331_i14
#ISCELL
  pure_quanta_power universal_power *
  page331_i15
#ISCELL
  pure_quanta_power universal_gnd *
  page331_i16
#CELL
  pure_quanta mosfet_nch_dual *
  page331_i17
#CELL
  pure_quanta q_res *
  page331_i18
#ISCELL
  pure_quanta_power universal_power *
  page331_i19
#CELL
  pure_quanta q_res *
  page331_i2
#ISCELL
  pure_quanta_power universal_gnd *
  page331_i20
#CELL
  pure_quanta mosfet_nch_dual *
  page331_i21
#CELL
  pure_quanta mosfet_nch_dual *
  page331_i22
#CELL
  pure_quanta q_res *
  page331_i23
#ISCELL
  pure_quanta_power universal_power *
  page331_i24
#CELL
  pure_quanta mosfet_nch_dual *
  page331_i25
#ISCELL
  pure_quanta_power universal_gnd *
  page331_i26
#CELL
  pure_quanta q_res *
  page331_i27
#CELL
  pure_quanta mosfet_nch_dual *
  page331_i28
#CELL
  pure_quanta mosfet_nch_dual *
  page331_i29
#ISCELL
  pure_quanta_power universal_gnd *
  page331_i3
#ISCELL
  pure_quanta_power universal_power *
  page331_i30
#ISCELL
  pure_quanta_power universal_gnd *
  page331_i31
#ISCELL
  pure_quanta_power universal_gnd *
  page331_i32
#CELL
  pure_quanta q_cap *
  page331_i33
#ISCELL
  pure_quanta_power universal_gnd *
  page331_i34
#CELL
  pure_quanta q_res *
  page331_i35
#ISCELL
  pure_quanta_power universal_power *
  page331_i36
#ISCELL
  pure_quanta_power universal_gnd *
  page331_i37
#ISCELL
  standard offpage *
  page331_i38
#CELL
  pure_quanta q_res *
  page331_i39
#CELL
  pure_quanta q_res *
  page331_i4
#ISCELL
  pure_quanta_power universal_power *
  page331_i40
#ISCELL
  pure_quanta_power universal_gnd *
  page331_i41
#CELL
  pure_quanta q_cap *
  page331_i42
#ISCELL
  pure_quanta_power universal_gnd *
  page331_i43
#CELL
  pure_quanta q_cap *
  page331_i44
#ISCELL
  standard offpage *
  page331_i45
#ISCELL
  standard offpage *
  page331_i46
#CELL
  pure_quanta q_res *
  page331_i47
#ISCELL
  pure_quanta_power universal_power *
  page331_i48
#ISCELL
  pure_quanta_power universal_power *
  page331_i49
#ISCELL
  standard offpage *
  page331_i5
#ISCELL
  standard offpage *
  page331_i51
#ISCELL
  pure_quanta_power universal_gnd *
  page331_i53
#ISCELL
  pure_quanta_power universal_gnd *
  page331_i54
#CELL
  pure_quanta mosfet_nch_dual *
  page331_i55
#ISCELL
  pure_quanta_power universal_power *
  page331_i56
#CELL
  pure_quanta q_res *
  page331_i57
#ISCELL
  pure_quanta_power universal_power *
  page331_i58
#ISCELL
  pure_quanta_power universal_power *
  page331_i6
#ISCELL
  pure_quanta_power universal_gnd *
  page331_i60
#CELL
  pure_quanta mosfet_nch_dual *
  page331_i61
#CELL
  pure_quanta q_res *
  page331_i62
#ISCELL
  pure_quanta_power universal_gnd *
  page331_i63
#ISCELL
  standard offpage *
  page331_i64
#ISCELL
  pure_quanta_power universal_gnd *
  page331_i7
#CELL
  pure_quanta q_res *
  page331_i8
#CELL
  pure_quanta q_res *
  page331_i85
#CELL
  pure_quanta 74lvc2g17gw *
  page331_i86
#CELL
  pure_quanta q_res *
  page331_i87
#ISCELL
  pure_quanta_power universal_power *
  page331_i88
#CELL
  pure_quanta q_res *
  page331_i89
#CELL
  pure_quanta q_res *
  page331_i9
#ISCELL
  pure_quanta_power universal_gnd *
  page331_i90
#ISCELL
  standard offpage *
  page331_i91
#ISCELL
  pure_quanta_power universal_gnd *
  page331_i92
#CELL
  pure_quanta q_cap *
  page331_i93
#ISCELL
  pure_quanta_power universal_power *
  page331_i94
#ISCELL
  standard offpage *
  page331_i95
#ISCELL
  pure_quanta_power universal_power *
  page331_i96
#CELL
  pure_quanta q_res *
  page331_i97
#CELL
  pure_quanta q_res *
  page331_i98
#CELL
  pure_quanta q_res *
  page331_i99
#ISCELL
  mstr_misc dns *
  *
#ISCELL
  pure_quanta quanta_title_block_c *
  *
#ISCELL
  pure_quanta_power universal_gnd *
  page332_i1
#CELL
  pure_quanta mosfet_nch_dual *
  page332_i10
#ISCELL
  pure_quanta_power universal_power *
  page332_i100
#ISCELL
  pure_quanta_power universal_gnd *
  page332_i101
#CELL
  pure_quanta mosfet_nch_dual *
  page332_i102
#CELL
  pure_quanta q_res *
  page332_i103
#CELL
  pure_quanta q_res *
  page332_i104
#ISCELL
  pure_quanta_power universal_power *
  page332_i105
#ISCELL
  pure_quanta_power universal_power *
  page332_i106
#CELL
  pure_quanta q_res *
  page332_i107
#ISCELL
  pure_quanta_power universal_power *
  page332_i108
#CELL
  pure_quanta q_res *
  page332_i109
#ISCELL
  standard offpage *
  page332_i11
#CELL
  pure_quanta q_res *
  page332_i110
#ISCELL
  pure_quanta_power universal_power *
  page332_i111
#ISCELL
  pure_quanta_power universal_gnd *
  page332_i112
#CELL
  pure_quanta mosfet_nch_dual *
  page332_i113
#CELL
  pure_quanta q_res *
  page332_i114
#ISCELL
  pure_quanta_power universal_power *
  page332_i115
#ISCELL
  pure_quanta_power universal_gnd *
  page332_i116
#ISCELL
  standard offpage *
  page332_i117
#CELL
  pure_quanta q_cap *
  page332_i118
#ISCELL
  standard offpage *
  page332_i119
#ISCELL
  pure_quanta_power universal_gnd *
  page332_i12
#CELL
  pure_quanta mosfet_nch_dual *
  page332_i120
#ISCELL
  pure_quanta_power universal_gnd *
  page332_i121
#CELL
  pure_quanta q_res *
  page332_i122
#CELL
  pure_quanta mosfet_nch_dual *
  page332_i123
#ISCELL
  pure_quanta_power universal_power *
  page332_i124
#ISCELL
  pure_quanta_power universal_gnd *
  page332_i125
#ISCELL
  pure_quanta_power universal_gnd *
  page332_i126
#CELL
  pure_quanta q_cap *
  page332_i127
#ISCELL
  standard offpage *
  page332_i128
#ISCELL
  pure_quanta_power universal_gnd *
  page332_i129
#CELL
  pure_quanta q_res *
  page332_i13
#CELL
  pure_quanta q_cap *
  page332_i130
#CELL
  pure_quanta q_res *
  page332_i131
#ISCELL
  pure_quanta_power universal_power *
  page332_i132
#ISCELL
  standard offpage *
  page332_i133
#CELL
  pure_quanta mosfet_nch_dual *
  page332_i134
#CELL
  pure_quanta q_res *
  page332_i135
#CELL
  pure_quanta q_res *
  page332_i14
#ISCELL
  standard offpage *
  page332_i15
#ISCELL
  pure_quanta_power universal_power *
  page332_i16
#ISCELL
  pure_quanta_power universal_gnd *
  page332_i17
#CELL
  pure_quanta q_res *
  page332_i18
#ISCELL
  pure_quanta_power universal_power *
  page332_i19
#CELL
  pure_quanta q_res *
  page332_i2
#ISCELL
  pure_quanta_power universal_gnd *
  page332_i20
#ISCELL
  standard offpage *
  page332_i21
#CELL
  pure_quanta q_res *
  page332_i22
#CELL
  pure_quanta q_res *
  page332_i23
#ISCELL
  pure_quanta_power universal_power *
  page332_i24
#CELL
  pure_quanta mosfet_nch_dual *
  page332_i25
#ISCELL
  pure_quanta_power universal_gnd *
  page332_i26
#CELL
  pure_quanta q_res *
  page332_i27
#ISCELL
  pure_quanta_power universal_power *
  page332_i28
#ISCELL
  pure_quanta_power universal_gnd *
  page332_i29
#ISCELL
  standard offpage *
  page332_i3
#CELL
  pure_quanta mosfet_nch_dual *
  page332_i30
#CELL
  pure_quanta q_res *
  page332_i31
#CELL
  pure_quanta mosfet_nch_dual *
  page332_i32
#CELL
  pure_quanta q_res *
  page332_i33
#ISCELL
  pure_quanta_power universal_power *
  page332_i34
#CELL
  pure_quanta q_res *
  page332_i35
#ISCELL
  pure_quanta_power universal_power *
  page332_i36
#CELL
  pure_quanta mosfet_nch_dual *
  page332_i37
#ISCELL
  pure_quanta_power universal_gnd *
  page332_i38
#CELL
  pure_quanta q_res *
  page332_i39
#CELL
  pure_quanta q_res *
  page332_i4
#CELL
  pure_quanta mosfet_nch_dual *
  page332_i40
#CELL
  pure_quanta q_res *
  page332_i41
#CELL
  pure_quanta mosfet_nch_dual *
  page332_i42
#ISCELL
  pure_quanta_power universal_power *
  page332_i43
#CELL
  pure_quanta q_res *
  page332_i44
#ISCELL
  pure_quanta_power universal_gnd *
  page332_i45
#ISCELL
  pure_quanta_power universal_gnd *
  page332_i46
#ISCELL
  pure_quanta_power universal_gnd *
  page332_i47
#CELL
  pure_quanta q_res *
  page332_i48
#ISCELL
  pure_quanta_power universal_gnd *
  page332_i49
#ISCELL
  pure_quanta_power universal_power *
  page332_i5
#CELL
  pure_quanta q_cap *
  page332_i50
#ISCELL
  standard offpage *
  page332_i51
#ISCELL
  standard offpage *
  page332_i52
#ISCELL
  pure_quanta_power universal_gnd *
  page332_i53
#CELL
  pure_quanta q_res *
  page332_i54
#CELL
  pure_quanta q_res *
  page332_i55
#ISCELL
  pure_quanta_power universal_power *
  page332_i56
#CELL
  pure_quanta mosfet_nch_dual *
  page332_i57
#ISCELL
  pure_quanta_power universal_gnd *
  page332_i58
#ISCELL
  pure_quanta_power universal_gnd *
  page332_i59
#CELL
  pure_quanta mosfet_nch_dual *
  page332_i6
#ISCELL
  pure_quanta_power universal_gnd *
  page332_i60
#CELL
  pure_quanta q_cap *
  page332_i61
#CELL
  pure_quanta q_res *
  page332_i62
#ISCELL
  pure_quanta_power universal_power *
  page332_i63
#CELL
  pure_quanta q_cap *
  page332_i64
#ISCELL
  pure_quanta_power universal_gnd *
  page332_i65
#CELL
  pure_quanta q_res *
  page332_i66
#ISCELL
  pure_quanta_power universal_gnd *
  page332_i67
#ISCELL
  standard offpage *
  page332_i68
#ISCELL
  standard offpage *
  page332_i69
#ISCELL
  pure_quanta_power universal_gnd *
  page332_i7
#CELL
  pure_quanta q_res *
  page332_i70
#ISCELL
  pure_quanta_power universal_power *
  page332_i71
#ISCELL
  pure_quanta_power universal_gnd *
  page332_i72
#CELL
  pure_quanta q_cap *
  page332_i73
#ISCELL
  pure_quanta_power universal_gnd *
  page332_i74
#CELL
  pure_quanta q_cap *
  page332_i75
#ISCELL
  standard offpage *
  page332_i76
#ISCELL
  standard offpage *
  page332_i77
#ISCELL
  standard offpage *
  page332_i78
#ISCELL
  standard offpage *
  page332_i79
#CELL
  pure_quanta q_res *
  page332_i8
#ISCELL
  pure_quanta_power universal_gnd *
  page332_i80
#CELL
  pure_quanta q_res *
  page332_i81
#CELL
  pure_quanta q_res *
  page332_i82
#ISCELL
  pure_quanta_power universal_power *
  page332_i83
#ISCELL
  pure_quanta_power universal_gnd *
  page332_i84
#ISCELL
  pure_quanta_power universal_power *
  page332_i85
#CELL
  pure_quanta mosfet_nch_dual *
  page332_i86
#ISCELL
  pure_quanta_power universal_gnd *
  page332_i87
#CELL
  pure_quanta q_res *
  page332_i88
#ISCELL
  pure_quanta_power universal_power *
  page332_i89
#ISCELL
  pure_quanta_power universal_power *
  page332_i9
#ISCELL
  pure_quanta_power universal_gnd *
  page332_i90
#CELL
  pure_quanta q_res *
  page332_i91
#CELL
  pure_quanta q_res *
  page332_i92
#CELL
  pure_quanta q_res *
  page332_i93
#ISCELL
  pure_quanta_power universal_power *
  page332_i94
#ISCELL
  pure_quanta_power universal_gnd *
  page332_i95
#CELL
  pure_quanta q_res *
  page332_i96
#CELL
  pure_quanta q_res *
  page332_i97
#CELL
  pure_quanta mosfet_nch_dual *
  page332_i98
#CELL
  pure_quanta q_res *
  page332_i99
#ISCELL
  mstr_misc dns *
  *
#ISCELL
  pure_quanta quanta_title_block_c *
  *
#ISCELL
  pure_quanta_power design_note *
  *
#ISCELL
  standard offpage *
  page299_i1
#ISCELL
  pure_quanta_power universal_power *
  page299_i10
#ISCELL
  pure_quanta_power universal_gnd *
  page299_i11
#ISCELL
  standard offpage *
  page299_i12
#CELL
  pure_quanta q_cap *
  page299_i129
#CELL
  pure_quanta q_res *
  page299_i130
#CELL
  pure_quanta q_res *
  page299_i131
#CELL
  pure_quanta q_res *
  page299_i132
#CELL
  pure_quanta q_res *
  page299_i133
#CELL
  pure_quanta q_res *
  page299_i134
#ISCELL
  pure_quanta_power universal_power *
  page299_i15
#ISCELL
  pure_quanta_power universal_power *
  page299_i150
#ISCELL
  standard offpage *
  page299_i151
#CELL
  pure_quanta q_cap *
  page299_i152
#ISCELL
  pure_quanta_power universal_gnd *
  page299_i153
#CELL
  pure_quanta q_res *
  page299_i154
#ISCELL
  pure_quanta_power universal_power *
  page299_i155
#ISCELL
  pure_quanta_power universal_gnd *
  page299_i156
#CELL
  pure_quanta mosfet_nch_dual *
  page299_i157
#CELL
  pure_quanta q_res *
  page299_i158
#ISCELL
  pure_quanta_power universal_gnd *
  page299_i159
#ISCELL
  pure_quanta_power universal_gnd *
  page299_i16
#CELL
  pure_quanta mosfet_nch_dual *
  page299_i160
#ISCELL
  pure_quanta_power universal_power *
  page299_i161
#CELL
  pure_quanta q_res *
  page299_i163
#ISCELL
  pure_quanta_power universal_gnd *
  page299_i164
#ISCELL
  standard offpage *
  page299_i165
#CELL
  pure_quanta q_res *
  page299_i166
#CELL
  pure_quanta q_res *
  page299_i167
#CELL
  pure_quanta mosfet_nch_dual *
  page299_i168
#CELL
  pure_quanta mosfet_nch_dual *
  page299_i169
#CELL
  pure_quanta q_res *
  page299_i17
#ISCELL
  standard offpage *
  page299_i170
#CELL
  pure_quanta q_cap *
  page299_i171
#ISCELL
  pure_quanta_power universal_gnd *
  page299_i172
#ISCELL
  pure_quanta_power universal_power *
  page299_i173
#CELL
  pure_quanta q_res *
  page299_i174
#ISCELL
  pure_quanta_power universal_gnd *
  page299_i175
#ISCELL
  pure_quanta_power universal_power *
  page299_i176
#CELL
  pure_quanta q_res *
  page299_i177
#ISCELL
  pure_quanta_power universal_gnd *
  page299_i178
#ISCELL
  pure_quanta_power universal_power *
  page299_i179
#ISCELL
  standard offpage *
  page299_i18
#CELL
  pure_quanta q_res *
  page299_i181
#ISCELL
  pure_quanta_power universal_gnd *
  page299_i182
#ISCELL
  standard offpage *
  page299_i183
#CELL
  pure_quanta q_res *
  page299_i184
#ISCELL
  standard offpage *
  page299_i185
#ISCELL
  pure_quanta_power universal_gnd *
  page299_i186
#CELL
  pure_quanta q_res *
  page299_i187
#ISCELL
  standard offpage *
  page299_i188
#ISCELL
  pure_quanta_power universal_power *
  page299_i190
#ISCELL
  pure_quanta_power universal_gnd *
  page299_i191
#CELL
  pure_quanta q_res *
  page299_i192
#ISCELL
  pure_quanta_power universal_power *
  page299_i193
#ISCELL
  pure_quanta_power universal_gnd *
  page299_i194
#CELL
  pure_quanta q_res *
  page299_i195
#ISCELL
  pure_quanta_power universal_power *
  page299_i196
#ISCELL
  pure_quanta_power universal_gnd *
  page299_i197
#CELL
  pure_quanta q_res *
  page299_i198
#ISCELL
  standard offpage *
  page299_i199
#ISCELL
  pure_quanta_power universal_gnd *
  page299_i2
#ISCELL
  pure_quanta_power universal_power *
  page299_i20
#CELL
  pure_quanta mosfet_nch_dual *
  page299_i200
#CELL
  pure_quanta mosfet_nch_dual *
  page299_i201
#CELL
  pure_quanta q_res *
  page299_i202
#CELL
  pure_quanta mosfet_nch_dual *
  page299_i21
#ISCELL
  pure_quanta_power universal_gnd *
  page299_i22
#CELL
  pure_quanta q_res *
  page299_i23
#ISCELL
  pure_quanta_power universal_power *
  page299_i24
#ISCELL
  pure_quanta_power universal_gnd *
  page299_i25
#CELL
  pure_quanta mosfet_nch_dual *
  page299_i26
#CELL
  pure_quanta q_res *
  page299_i27
#ISCELL
  pure_quanta_power universal_power *
  page299_i28
#ISCELL
  pure_quanta_power universal_gnd *
  page299_i29
#CELL
  pure_quanta q_res *
  page299_i3
#CELL
  pure_quanta q_cap *
  page299_i30
#ISCELL
  standard offpage *
  page299_i31
#CELL
  pure_quanta mosfet_nch_dual *
  page299_i37
#ISCELL
  pure_quanta_power universal_gnd *
  page299_i38
#CELL
  pure_quanta q_res *
  page299_i39
#CELL
  pure_quanta mosfet_nch_dual *
  page299_i40
#ISCELL
  pure_quanta_power universal_power *
  page299_i41
#ISCELL
  pure_quanta_power universal_gnd *
  page299_i42
#CELL
  pure_quanta mosfet_nch_dual *
  page299_i43
#ISCELL
  pure_quanta_power universal_gnd *
  page299_i44
#CELL
  pure_quanta q_res *
  page299_i45
#ISCELL
  pure_quanta_power universal_power *
  page299_i46
#ISCELL
  pure_quanta_power universal_gnd *
  page299_i47
#CELL
  pure_quanta mosfet_nch_dual *
  page299_i48
#CELL
  pure_quanta q_res *
  page299_i49
#ISCELL
  pure_quanta_power universal_power *
  page299_i5
#ISCELL
  pure_quanta_power universal_power *
  page299_i50
#ISCELL
  pure_quanta_power universal_gnd *
  page299_i51
#CELL
  pure_quanta mosfet_nch_dual *
  page299_i52
#CELL
  pure_quanta q_res *
  page299_i53
#ISCELL
  pure_quanta_power universal_power *
  page299_i54
#CELL
  pure_quanta q_res *
  page299_i55
#ISCELL
  pure_quanta_power universal_power *
  page299_i56
#CELL
  pure_quanta mosfet_nch_dual *
  page299_i57
#ISCELL
  pure_quanta_power universal_gnd *
  page299_i58
#CELL
  pure_quanta q_res *
  page299_i59
#ISCELL
  standard offpage *
  page299_i6
#ISCELL
  pure_quanta_power universal_gnd *
  page299_i60
#ISCELL
  pure_quanta_power universal_gnd *
  page299_i61
#ISCELL
  standard offpage *
  page299_i62
#ISCELL
  pure_quanta_power universal_gnd *
  page299_i7
#CELL
  pure_quanta q_cap *
  page299_i71
#ISCELL
  standard offpage *
  page299_i72
#ISCELL
  pure_quanta_power universal_gnd *
  page299_i73
#CELL
  pure_quanta q_cap *
  page299_i74
#ISCELL
  standard offpage *
  page299_i75
#ISCELL
  pure_quanta_power universal_power *
  page299_i83
#ISCELL
  mstr_misc dns *
  *
#ISCELL
  pure_quanta quanta_title_block_c *
  *
#ISCELL
  pure_quanta_power universal_gnd *
  page333_i10
#CELL
  pure_quanta mosfet_nch_dual *
  page333_i100
#CELL
  pure_quanta q_res *
  page333_i101
#ISCELL
  pure_quanta_power universal_power *
  page333_i102
#ISCELL
  pure_quanta_power universal_gnd *
  page333_i103
#ISCELL
  pure_quanta_power universal_gnd *
  page333_i104
#CELL
  pure_quanta q_cap *
  page333_i105
#ISCELL
  standard offpage *
  page333_i106
#ISCELL
  pure_quanta_power universal_gnd *
  page333_i108
#CELL
  pure_quanta q_res *
  page333_i109
#ISCELL
  pure_quanta_power universal_gnd *
  page333_i11
#ISCELL
  pure_quanta_power universal_power *
  page333_i110
#CELL
  pure_quanta q_cap *
  page333_i111
#ISCELL
  pure_quanta_power universal_gnd *
  page333_i112
#ISCELL
  pure_quanta_power universal_gnd *
  page333_i113
#CELL
  pure_quanta q_cap *
  page333_i114
#ISCELL
  pure_quanta_power universal_gnd *
  page333_i115
#CELL
  pure_quanta q_cap *
  page333_i116
#CELL
  pure_quanta mosfet_nch_dual *
  page333_i117
#CELL
  pure_quanta mosfet_nch_dual *
  page333_i118
#CELL
  pure_quanta mosfet_nch_dual *
  page333_i119
#ISCELL
  pure_quanta_power universal_gnd *
  page333_i12
#CELL
  pure_quanta mosfet_nch_dual *
  page333_i120
#CELL
  pure_quanta mosfet_nch_dual *
  page333_i121
#CELL
  pure_quanta mosfet_nch_dual *
  page333_i122
#ISCELL
  pure_quanta_power universal_power *
  page333_i123
#ISCELL
  standard offpage *
  page333_i124
#CELL
  pure_quanta q_cap *
  page333_i125
#ISCELL
  pure_quanta_power universal_gnd *
  page333_i126
#ISCELL
  pure_quanta_power universal_power *
  page333_i128
#CELL
  pure_quanta q_res *
  page333_i129
#ISCELL
  pure_quanta_power universal_power *
  page333_i13
#ISCELL
  pure_quanta_power universal_gnd *
  page333_i130
#ISCELL
  pure_quanta_power universal_gnd *
  page333_i131
#ISCELL
  pure_quanta_power universal_power *
  page333_i132
#CELL
  pure_quanta q_res *
  page333_i134
#ISCELL
  pure_quanta_power universal_gnd *
  page333_i135
#ISCELL
  standard offpage *
  page333_i136
#ISCELL
  standard offpage *
  page333_i137
#ISCELL
  pure_quanta_power universal_gnd *
  page333_i138
#CELL
  pure_quanta q_res *
  page333_i139
#CELL
  pure_quanta q_res *
  page333_i14
#ISCELL
  pure_quanta_power universal_power *
  page333_i141
#ISCELL
  pure_quanta_power universal_gnd *
  page333_i142
#ISCELL
  pure_quanta_power universal_gnd *
  page333_i143
#CELL
  pure_quanta q_res *
  page333_i144
#ISCELL
  pure_quanta_power universal_power *
  page333_i145
#ISCELL
  pure_quanta_power universal_gnd *
  page333_i147
#CELL
  pure_quanta q_cap *
  page333_i148
#ISCELL
  standard offpage *
  page333_i149
#ISCELL
  pure_quanta_power universal_power *
  page333_i150
#CELL
  pure_quanta mosfet_nch_dual *
  page333_i151
#CELL
  pure_quanta mosfet_nch_dual *
  page333_i152
#ISCELL
  pure_quanta_power universal_power *
  page333_i153
#CELL
  pure_quanta mosfet_nch_dual *
  page333_i154
#ISCELL
  standard offpage *
  page333_i155
#CELL
  pure_quanta q_cap *
  page333_i156
#ISCELL
  pure_quanta_power universal_gnd *
  page333_i157
#CELL
  pure_quanta q_res *
  page333_i158
#CELL
  pure_quanta mosfet_nch_dual *
  page333_i159
#ISCELL
  pure_quanta_power universal_power *
  page333_i16
#ISCELL
  pure_quanta_power universal_gnd *
  page333_i160
#ISCELL
  pure_quanta_power universal_power *
  page333_i161
#CELL
  pure_quanta q_res *
  page333_i162
#ISCELL
  pure_quanta_power universal_gnd *
  page333_i163
#ISCELL
  pure_quanta_power universal_power *
  page333_i164
#ISCELL
  pure_quanta_power universal_gnd *
  page333_i167
#ISCELL
  standard offpage *
  page333_i168
#ISCELL
  standard offpage *
  page333_i169
#CELL
  pure_quanta q_res *
  page333_i171
#CELL
  pure_quanta q_res *
  page333_i172
#CELL
  pure_quanta q_res *
  page333_i173
#CELL
  pure_quanta q_res *
  page333_i174
#CELL
  pure_quanta q_res *
  page333_i175
#CELL
  pure_quanta q_res *
  page333_i176
#CELL
  pure_quanta q_res *
  page333_i177
#CELL
  pure_quanta q_res *
  page333_i178
#CELL
  pure_quanta q_res *
  page333_i179
#CELL
  pure_quanta q_res *
  page333_i18
#CELL
  pure_quanta q_res *
  page333_i180
#CELL
  pure_quanta q_res *
  page333_i19
#ISCELL
  pure_quanta_power universal_power *
  page333_i21
#ISCELL
  standard offpage *
  page333_i22
#ISCELL
  pure_quanta_power universal_gnd *
  page333_i23
#CELL
  pure_quanta q_res *
  page333_i24
#ISCELL
  pure_quanta_power universal_power *
  page333_i25
#ISCELL
  standard offpage *
  page333_i28
#ISCELL
  pure_quanta_power universal_gnd *
  page333_i29
#CELL
  pure_quanta q_res *
  page333_i30
#ISCELL
  pure_quanta_power universal_power *
  page333_i31
#CELL
  pure_quanta mosfet_nch_dual *
  page333_i33
#CELL
  pure_quanta mosfet_nch_dual *
  page333_i35
#CELL
  pure_quanta mosfet_nch_dual *
  page333_i37
#ISCELL
  pure_quanta_power universal_power *
  page333_i46
#ISCELL
  pure_quanta_power universal_power *
  page333_i47
#ISCELL
  pure_quanta_power universal_power *
  page333_i49
#ISCELL
  pure_quanta_power universal_power *
  page333_i51
#ISCELL
  pure_quanta_power universal_power *
  page333_i53
#ISCELL
  pure_quanta_power universal_gnd *
  page333_i55
#CELL
  pure_quanta q_res *
  page333_i56
#ISCELL
  pure_quanta_power universal_gnd *
  page333_i57
#CELL
  pure_quanta q_res *
  page333_i58
#ISCELL
  pure_quanta_power universal_gnd *
  page333_i59
#ISCELL
  standard offpage *
  page333_i6
#CELL
  pure_quanta q_res *
  page333_i60
#ISCELL
  pure_quanta_power universal_gnd *
  page333_i61
#CELL
  pure_quanta q_res *
  page333_i62
#ISCELL
  pure_quanta_power universal_gnd *
  page333_i63
#CELL
  pure_quanta q_res *
  page333_i66
#CELL
  pure_quanta q_res *
  page333_i67
#CELL
  pure_quanta q_res *
  page333_i68
#ISCELL
  standard offpage *
  page333_i7
#ISCELL
  standard offpage *
  page333_i8
#CELL
  pure_quanta q_res *
  page333_i80
#CELL
  pure_quanta mosfet_nch_dual *
  page333_i82
#ISCELL
  pure_quanta_power universal_gnd *
  page333_i83
#ISCELL
  pure_quanta_power universal_power *
  page333_i85
#ISCELL
  standard offpage *
  page333_i86
#ISCELL
  standard offpage *
  page333_i87
#CELL
  pure_quanta mosfet_nch_dual *
  page333_i88
#ISCELL
  pure_quanta_power universal_gnd *
  page333_i89
#ISCELL
  pure_quanta_power universal_power *
  page333_i90
#CELL
  pure_quanta q_res *
  page333_i91
#CELL
  pure_quanta q_cap *
  page333_i92
#ISCELL
  pure_quanta_power universal_gnd *
  page333_i93
#ISCELL
  standard offpage *
  page333_i94
#ISCELL
  pure_quanta_power universal_gnd *
  page333_i96
#ISCELL
  pure_quanta_power universal_power *
  page333_i98
#ISCELL
  standard offpage *
  page333_i99
#ISCELL
  mstr_misc dns *
  *
#ISCELL
  pure_quanta quanta_title_block_c *
  *
#CELL
  pure_quanta q_res *
  page334_i123
#CELL
  pure_quanta q_res *
  page334_i124
#ISCELL
  pure_quanta_power universal_power *
  page334_i125
#ISCELL
  pure_quanta_power universal_gnd *
  page334_i126
#CELL
  pure_quanta q_res *
  page334_i127
#ISCELL
  pure_quanta_power universal_gnd *
  page334_i137
#ISCELL
  pure_quanta_power universal_gnd *
  page334_i138
#CELL
  pure_quanta q_res *
  page334_i139
#CELL
  pure_quanta q_res *
  page334_i140
#ISCELL
  standard offpage *
  page334_i146
#CELL
  pure_quanta q_cap *
  page334_i148
#ISCELL
  pure_quanta_power universal_gnd *
  page334_i149
#CELL
  pure_quanta 74lvc2g17gw *
  page334_i153
#ISCELL
  pure_quanta_power universal_power *
  page334_i154
#ISCELL
  pure_quanta_power universal_gnd *
  page334_i16
#ISCELL
  standard offpage *
  page334_i161
#CELL
  pure_quanta q_res *
  page334_i162
#ISCELL
  pure_quanta_power universal_power *
  page334_i163
#CELL
  pure_quanta q_res *
  page334_i164
#CELL
  pure_quanta q_res *
  page334_i165
#ISCELL
  pure_quanta_power universal_gnd *
  page334_i166
#ISCELL
  pure_quanta_power universal_power *
  page334_i167
#CELL
  pure_quanta q_res *
  page334_i168
#ISCELL
  standard offpage *
  page334_i169
#CELL
  pure_quanta q_res *
  page334_i170
#ISCELL
  pure_quanta_power universal_gnd *
  page334_i171
#ISCELL
  standard offpage *
  page334_i172
#CELL
  pure_quanta 74lvc2g17gw *
  page334_i173
#ISCELL
  pure_quanta_power universal_power *
  page334_i174
#CELL
  pure_quanta q_cap *
  page334_i175
#ISCELL
  pure_quanta_power universal_gnd *
  page334_i176
#ISCELL
  pure_quanta_power universal_gnd *
  page334_i177
#ISCELL
  pure_quanta_power universal_gnd *
  page334_i178
#ISCELL
  standard offpage *
  page334_i179
#ISCELL
  standard offpage *
  page334_i18
#CELL
  pure_quanta q_res *
  page334_i180
#CELL
  pure_quanta q_res *
  page334_i181
#ISCELL
  standard offpage *
  page334_i182
#CELL
  pure_quanta q_res *
  page334_i183
#CELL
  pure_quanta q_res *
  page334_i184
#ISCELL
  pure_quanta_power universal_gnd *
  page334_i185
#ISCELL
  pure_quanta_power universal_power *
  page334_i186
#CELL
  pure_quanta q_res *
  page334_i187
#CELL
  pure_quanta q_res *
  page334_i188
#ISCELL
  pure_quanta_power universal_gnd *
  page334_i189
#ISCELL
  standard offpage *
  page334_i190
#ISCELL
  pure_quanta_power universal_power *
  page334_i191
#CELL
  pure_quanta q_res *
  page334_i192
#CELL
  pure_quanta q_res *
  page334_i193
#ISCELL
  standard offpage *
  page334_i194
#CELL
  pure_quanta q_res *
  page334_i195
#ISCELL
  pure_quanta_power universal_gnd *
  page334_i196
#ISCELL
  standard offpage *
  page334_i197
#ISCELL
  standard offpage *
  page334_i198
#ISCELL
  pure_quanta_power universal_power *
  page334_i20
#CELL
  pure_quanta 74lvc2g17gw *
  page334_i26
#ISCELL
  pure_quanta_power universal_gnd *
  page334_i27
#ISCELL
  pure_quanta_power universal_gnd *
  page334_i28
#CELL
  pure_quanta q_cap *
  page334_i29
#ISCELL
  pure_quanta_power universal_power *
  page334_i30
#CELL
  pure_quanta q_res *
  page334_i62
#ISCELL
  standard offpage *
  page334_i67
#CELL
  pure_quanta q_res *
  page334_i95
#ISCELL
  mstr_misc dns *
  *
#ISCELL
  pure_quanta quanta_title_block_c *
  *
#ISCELL
  pure_quanta_power universal_power *
  page255_i11
#ISCELL
  pure_quanta_power universal_gnd *
  page255_i12
#CELL
  pure_quanta q_cap *
  page255_i13
#CELL
  pure_quanta 74lvc2g07dw7 *
  page255_i16
#ISCELL
  pure_quanta_power universal_gnd *
  page255_i17
#ISCELL
  pure_quanta_power universal_power *
  page255_i28
#ISCELL
  pure_quanta_power universal_gnd *
  page255_i30
#CELL
  pure_quanta q_res *
  page255_i31
#ISCELL
  standard offpage *
  page255_i32
#CELL
  pure_quanta q_res *
  page255_i33
#ISCELL
  pure_quanta_power universal_power *
  page255_i34
#CELL
  pure_quanta q_res *
  page255_i35
#ISCELL
  standard offpage *
  page255_i36
#CELL
  pure_quanta q_res *
  page255_i37
#ISCELL
  pure_quanta_power universal_gnd *
  page255_i38
#ISCELL
  pure_quanta_power universal_power *
  page255_i39
#CELL
  pure_quanta q_res *
  page255_i40
#ISCELL
  standard offpage *
  page255_i41
#CELL
  pure_quanta q_res *
  page255_i42
#ISCELL
  pure_quanta_power universal_gnd *
  page255_i43
#ISCELL
  standard offpage *
  page255_i44
#CELL
  pure_quanta q_res *
  page255_i45
#ISCELL
  pure_quanta_power universal_power *
  page255_i46
#CELL
  pure_quanta q_res *
  page255_i47
#CELL
  pure_quanta q_res *
  page255_i48
#ISCELL
  pure_quanta_power universal_gnd *
  page255_i49
#CELL
  pure_quanta 74lvc2g07dw7 *
  page255_i50
#ISCELL
  standard offpage *
  page255_i51
#CELL
  pure_quanta q_res *
  page255_i53
#ISCELL
  pure_quanta_power universal_power *
  page255_i54
#CELL
  pure_quanta q_res *
  page255_i55
#ISCELL
  pure_quanta_power universal_power *
  page255_i56
#CELL
  pure_quanta q_res *
  page255_i57
#ISCELL
  standard offpage *
  page255_i58
#CELL
  pure_quanta q_res *
  page255_i62
#ISCELL
  pure_quanta_power universal_gnd *
  page255_i63
#ISCELL
  pure_quanta_power universal_power *
  page255_i66
#CELL
  pure_quanta q_cap *
  page255_i67
#ISCELL
  pure_quanta_power universal_gnd *
  page255_i68
#ISCELL
  pure_quanta_power universal_gnd *
  page255_i69
#CELL
  pure_quanta q_res *
  page255_i70
#ISCELL
  pure_quanta_power universal_gnd *
  page255_i74
#CELL
  pure_quanta q_res *
  page255_i75
#ISCELL
  mstr_misc dns *
  *
#ISCELL
  pure_quanta quanta_title_block_c *
  *
#CELL
  pure_quanta q_res *
  page256_i121
#ISCELL
  pure_quanta_power universal_gnd *
  page256_i122
#ISCELL
  pure_quanta_power universal_gnd *
  page256_i125
#CELL
  pure_quanta 74lvc2g17gw *
  page256_i127
#ISCELL
  standard offpage *
  page256_i129
#ISCELL
  pure_quanta_power universal_gnd *
  page256_i132
#ISCELL
  pure_quanta_power universal_power *
  page256_i139
#CELL
  pure_quanta q_cap *
  page256_i140
#ISCELL
  pure_quanta_power universal_gnd *
  page256_i141
#ISCELL
  pure_quanta_power universal_gnd *
  page256_i142
#ISCELL
  standard offpage *
  page256_i146
#CELL
  pure_quanta q_res *
  page256_i147
#ISCELL
  pure_quanta_power universal_power *
  page256_i148
#CELL
  pure_quanta q_res *
  page256_i153
#CELL
  pure_quanta q_res *
  page256_i154
#CELL
  pure_quanta q_res *
  page256_i155
#CELL
  pure_quanta q_res *
  page256_i156
#ISCELL
  pure_quanta_power universal_gnd *
  page256_i159
#CELL
  pure_quanta q_res *
  page256_i160
#ISCELL
  pure_quanta_power universal_power *
  page256_i161
#CELL
  pure_quanta q_res *
  page256_i162
#ISCELL
  standard offpage *
  page256_i163
#ISCELL
  pure_quanta_power universal_power *
  page256_i165
#CELL
  pure_quanta q_cap *
  page256_i166
#ISCELL
  pure_quanta_power universal_gnd *
  page256_i167
#CELL
  pure_quanta q_res *
  page256_i170
#CELL
  pure_quanta q_res *
  page256_i171
#ISCELL
  standard offpage *
  page256_i172
#ISCELL
  standard offpage *
  page256_i173
#ISCELL
  pure_quanta_power universal_power *
  page256_i174
#ISCELL
  standard offpage *
  page256_i177
#ISCELL
  pure_quanta_power universal_gnd *
  page256_i178
#ISCELL
  standard offpage *
  page256_i180
#CELL
  pure_quanta q_res *
  page256_i181
#ISCELL
  pure_quanta_power universal_power *
  page256_i183
#ISCELL
  pure_quanta_power universal_gnd *
  page256_i184
#CELL
  pure_quanta q_res *
  page256_i190
#CELL
  pure_quanta q_res *
  page256_i191
#CELL
  pure_quanta q_res *
  page256_i192
#CELL
  pure_quanta q_res *
  page256_i193
#CELL
  pure_quanta q_res *
  page256_i194
#CELL
  pure_quanta 74lvc1g126se7 *
  page256_i195
#ISCELL
  pure_quanta_power universal_gnd *
  page256_i196
#CELL
  pure_quanta q_res *
  page256_i197
#CELL
  pure_quanta q_res *
  page256_i198
#ISCELL
  pure_quanta_power universal_power *
  page256_i199
#CELL
  pure_quanta q_res *
  page256_i200
#ISCELL
  pure_quanta_power universal_power *
  page256_i201
#CELL
  pure_quanta q_res *
  page256_i203
#CELL
  pure_quanta q_res *
  page256_i204
#CELL
  pure_quanta 74lvc2g17gw *
  page256_i65
#ISCELL
  pure_quanta_power universal_power *
  page256_i67
#CELL
  pure_quanta q_res *
  page256_i68
#ISCELL
  pure_quanta_power universal_gnd *
  page256_i69
#ISCELL
  standard offpage *
  page256_i70
#ISCELL
  pure_quanta_power universal_power *
  page256_i71
#ISCELL
  pure_quanta_power universal_gnd *
  page256_i74
#ISCELL
  standard offpage *
  page256_i75
#ISCELL
  pure_quanta_power universal_gnd *
  page256_i76
#CELL
  pure_quanta q_res *
  page256_i78
#ISCELL
  standard offpage *
  page256_i79
#ISCELL
  pure_quanta_power universal_power *
  page256_i80
#ISCELL
  standard offpage *
  page256_i82
#ISCELL
  pure_quanta_power universal_power *
  page256_i83
#ISCELL
  pure_quanta_power universal_power *
  page256_i87
#ISCELL
  pure_quanta_power universal_gnd *
  page256_i88
#CELL
  pure_quanta q_cap *
  page256_i89
#CELL
  pure_quanta q_res *
  page256_i92
#CELL
  pure_quanta q_res *
  page256_i93
#ISCELL
  mstr_misc dns *
  *
#ISCELL
  pure_quanta quanta_title_block_c *
  *
#ISCELL
  pure_quanta_power cad_note *
  *
#ISCELL
  pure_quanta_power universal_gnd *
  page335_i1
#ISCELL
  standard offpage *
  page335_i10
#ISCELL
  standard tap *
  page335_i100
#ISCELL
  standard tap *
  page335_i101
#ISCELL
  standard tap *
  page335_i102
#ISCELL
  standard tap *
  page335_i103
#ISCELL
  standard tap *
  page335_i104
#ISCELL
  standard tap *
  page335_i105
#ISCELL
  standard tap *
  page335_i106
#ISCELL
  standard tap *
  page335_i107
#CELL
  pure_quanta q_res *
  page335_i108
#ISCELL
  pure_quanta_power universal_gnd *
  page335_i109
#ISCELL
  pure_quanta_power universal_gnd *
  page335_i11
#CELL
  pure_quanta q_cap *
  page335_i110
#CELL
  pure_quanta q_cap *
  page335_i111
#CELL
  pure_quanta q_cap *
  page335_i112
#ISCELL
  pure_quanta_power universal_gnd *
  page335_i113
#CELL
  pure_quanta q_cap *
  page335_i114
#ISCELL
  standard offpage *
  page335_i115
#ISCELL
  standard offpage *
  page335_i116
#ISCELL
  pure_quanta_power universal_power *
  page335_i117
#ISCELL
  standard tap *
  page335_i118
#ISCELL
  standard tap *
  page335_i119
#CELL
  pure_quanta q_res *
  page335_i12
#ISCELL
  standard tap *
  page335_i120
#ISCELL
  standard tap *
  page335_i121
#ISCELL
  standard tap *
  page335_i122
#ISCELL
  standard tap *
  page335_i123
#ISCELL
  standard tap *
  page335_i124
#ISCELL
  standard tap *
  page335_i125
#ISCELL
  standard tap *
  page335_i126
#ISCELL
  standard tap *
  page335_i127
#ISCELL
  standard tap *
  page335_i128
#ISCELL
  standard tap *
  page335_i129
#ISCELL
  standard offpage *
  page335_i13
#ISCELL
  standard tap *
  page335_i130
#ISCELL
  standard tap *
  page335_i131
#ISCELL
  standard tap *
  page335_i132
#ISCELL
  standard tap *
  page335_i133
#ISCELL
  standard offpage *
  page335_i134
#ISCELL
  standard offpage *
  page335_i135
#ISCELL
  standard offpage *
  page335_i136
#ISCELL
  standard offpage *
  page335_i137
#ISCELL
  standard offpage *
  page335_i138
#ISCELL
  standard offpage *
  page335_i14
#ISCELL
  standard offpage *
  page335_i141
#ISCELL
  standard offpage *
  page335_i142
#ISCELL
  standard offpage *
  page335_i143
#ISCELL
  standard offpage *
  page335_i144
#ISCELL
  standard offpage *
  page335_i145
#ISCELL
  standard offpage *
  page335_i146
#ISCELL
  standard offpage *
  page335_i147
#ISCELL
  standard offpage *
  page335_i148
#ISCELL
  standard offpage *
  page335_i149
#ISCELL
  standard offpage *
  page335_i15
#ISCELL
  standard offpage *
  page335_i150
#ISCELL
  standard offpage *
  page335_i151
#ISCELL
  standard offpage *
  page335_i152
#ISCELL
  standard offpage *
  page335_i153
#ISCELL
  standard offpage *
  page335_i154
#ISCELL
  pure_quanta_power universal_gnd *
  page335_i155
#ISCELL
  standard offpage *
  page335_i157
#ISCELL
  standard offpage *
  page335_i158
#ISCELL
  standard offpage *
  page335_i159
#ISCELL
  standard offpage *
  page335_i16
#ISCELL
  standard offpage *
  page335_i160
#ISCELL
  standard offpage *
  page335_i161
#ISCELL
  standard tap *
  page335_i162
#CELL
  pure_quanta q_cap *
  page335_i163
#CELL
  pure_quanta q_cap *
  page335_i164
#ISCELL
  standard offpage *
  page335_i165
#CELL
  pure_quanta q_res *
  page335_i166
#ISCELL
  standard tap *
  page335_i167
#CELL
  pure_quanta sconn168_me1016810202011 *
  page335_i168
#CELL
  pure_quanta q_res *
  page335_i169
#CELL
  pure_quanta q_res *
  page335_i17
#CELL
  pure_quanta q_res *
  page335_i170
#CELL
  pure_quanta q_res *
  page335_i171
#ISCELL
  standard offpage *
  page335_i18
#CELL
  pure_quanta q_res *
  page335_i19
#CELL
  pure_quanta q_res *
  page335_i2
#CELL
  pure_quanta q_res *
  page335_i20
#CELL
  pure_quanta q_res *
  page335_i21
#CELL
  pure_quanta q_res *
  page335_i22
#ISCELL
  pure_quanta_power universal_gnd *
  page335_i23
#ISCELL
  standard tap *
  page335_i24
#ISCELL
  standard tap *
  page335_i25
#ISCELL
  standard tap *
  page335_i26
#ISCELL
  standard tap *
  page335_i27
#ISCELL
  pure_quanta_power universal_gnd *
  page335_i28
#ISCELL
  standard tap *
  page335_i29
#CELL
  pure_quanta q_res *
  page335_i3
#ISCELL
  standard tap *
  page335_i30
#ISCELL
  standard tap *
  page335_i31
#ISCELL
  standard tap *
  page335_i32
#ISCELL
  standard tap *
  page335_i33
#ISCELL
  standard tap *
  page335_i34
#ISCELL
  standard tap *
  page335_i35
#ISCELL
  standard tap *
  page335_i36
#ISCELL
  standard tap *
  page335_i37
#ISCELL
  standard tap *
  page335_i38
#ISCELL
  standard tap *
  page335_i39
#ISCELL
  pure_quanta_power universal_power *
  page335_i4
#ISCELL
  pure_quanta_power universal_power *
  page335_i40
#ISCELL
  standard offpage *
  page335_i41
#ISCELL
  standard offpage *
  page335_i42
#ISCELL
  standard offpage *
  page335_i43
#ISCELL
  standard offpage *
  page335_i44
#ISCELL
  standard offpage *
  page335_i45
#ISCELL
  standard offpage *
  page335_i46
#ISCELL
  standard offpage *
  page335_i47
#ISCELL
  standard offpage *
  page335_i48
#ISCELL
  standard offpage *
  page335_i49
#ISCELL
  pure_quanta_power universal_gnd *
  page335_i5
#ISCELL
  standard offpage *
  page335_i50
#ISCELL
  standard offpage *
  page335_i51
#ISCELL
  standard offpage *
  page335_i52
#ISCELL
  standard offpage *
  page335_i53
#CELL
  pure_quanta q_res *
  page335_i54
#CELL
  pure_quanta q_res *
  page335_i55
#CELL
  pure_quanta q_res *
  page335_i56
#CELL
  pure_quanta q_res *
  page335_i57
#ISCELL
  pure_quanta_power universal_power *
  page335_i58
#CELL
  pure_quanta q_res *
  page335_i59
#CELL
  pure_quanta q_res *
  page335_i6
#ISCELL
  standard offpage *
  page335_i60
#ISCELL
  standard offpage *
  page335_i61
#ISCELL
  standard offpage *
  page335_i62
#ISCELL
  standard offpage *
  page335_i63
#ISCELL
  standard offpage *
  page335_i64
#ISCELL
  standard offpage *
  page335_i65
#ISCELL
  standard offpage *
  page335_i66
#ISCELL
  standard offpage *
  page335_i67
#ISCELL
  standard offpage *
  page335_i68
#ISCELL
  standard offpage *
  page335_i69
#CELL
  pure_quanta q_res *
  page335_i7
#ISCELL
  standard tap *
  page335_i70
#ISCELL
  standard tap *
  page335_i71
#ISCELL
  standard tap *
  page335_i72
#ISCELL
  standard tap *
  page335_i73
#ISCELL
  standard tap *
  page335_i74
#ISCELL
  standard tap *
  page335_i75
#ISCELL
  standard tap *
  page335_i76
#ISCELL
  standard tap *
  page335_i77
#ISCELL
  standard tap *
  page335_i78
#ISCELL
  standard tap *
  page335_i79
#CELL
  pure_quanta q_res *
  page335_i8
#ISCELL
  standard tap *
  page335_i80
#ISCELL
  standard tap *
  page335_i81
#ISCELL
  standard tap *
  page335_i82
#ISCELL
  standard tap *
  page335_i83
#ISCELL
  standard tap *
  page335_i84
#ISCELL
  standard tap *
  page335_i85
#ISCELL
  pure_quanta_power universal_power *
  page335_i86
#CELL
  pure_quanta q_cap *
  page335_i87
#CELL
  pure_quanta q_cap *
  page335_i88
#CELL
  pure_quanta q_cap *
  page335_i89
#ISCELL
  standard offpage *
  page335_i9
#CELL
  pure_quanta q_cap *
  page335_i90
#ISCELL
  pure_quanta_power universal_gnd *
  page335_i91
#ISCELL
  pure_quanta_power universal_power *
  page335_i92
#ISCELL
  standard tap *
  page335_i93
#ISCELL
  standard tap *
  page335_i94
#ISCELL
  standard tap *
  page335_i95
#ISCELL
  standard tap *
  page335_i96
#ISCELL
  standard tap *
  page335_i97
#ISCELL
  standard tap *
  page335_i98
#ISCELL
  standard tap *
  page335_i99
#ISCELL
  mstr_misc dns *
  *
#ISCELL
  pure_quanta quanta_title_block_c *
  *
#CELL
  pure_quanta 74cbtlv3126pw *
  page336_i1
#CELL
  pure_quanta q_res *
  page336_i100
#CELL
  pure_quanta q_res *
  page336_i101
#CELL
  pure_quanta q_res *
  page336_i102
#CELL
  pure_quanta q_res *
  page336_i103
#CELL
  pure_quanta q_res *
  page336_i104
#ISCELL
  standard offpage *
  page336_i110
#ISCELL
  standard offpage *
  page336_i111
#ISCELL
  standard offpage *
  page336_i112
#CELL
  pure_quanta q_res *
  page336_i119
#ISCELL
  standard offpage *
  page336_i120
#CELL
  pure_quanta q_res *
  page336_i122
#CELL
  pure_quanta q_res *
  page336_i123
#CELL
  pure_quanta q_res *
  page336_i124
#ISCELL
  pure_quanta_power universal_gnd *
  page336_i125
#ISCELL
  standard offpage *
  page336_i128
#CELL
  pure_quanta q_res *
  page336_i129
#ISCELL
  pure_quanta_power universal_gnd *
  page336_i130
#CELL
  pure_quanta q_res *
  page336_i131
#CELL
  pure_quanta q_res *
  page336_i132
#CELL
  pure_quanta q_res *
  page336_i133
#CELL
  pure_quanta q_res *
  page336_i134
#CELL
  pure_quanta q_res *
  page336_i135
#CELL
  pure_quanta q_res *
  page336_i136
#ISCELL
  standard offpage *
  page336_i137
#ISCELL
  standard offpage *
  page336_i138
#ISCELL
  standard offpage *
  page336_i139
#ISCELL
  standard offpage *
  page336_i140
#ISCELL
  standard offpage *
  page336_i141
#ISCELL
  standard offpage *
  page336_i142
#ISCELL
  standard offpage *
  page336_i143
#ISCELL
  standard offpage *
  page336_i145
#ISCELL
  pure_quanta_power universal_gnd *
  page336_i146
#CELL
  pure_quanta q_cap *
  page336_i147
#ISCELL
  pure_quanta_power universal_gnd *
  page336_i15
#ISCELL
  pure_quanta_power universal_power *
  page336_i150
#ISCELL
  pure_quanta_power universal_gnd *
  page336_i151
#CELL
  pure_quanta q_res *
  page336_i152
#CELL
  pure_quanta q_res *
  page336_i153
#ISCELL
  standard offpage *
  page336_i154
#CELL
  pure_quanta q_res *
  page336_i156
#CELL
  pure_quanta 74lvc1g126se7 *
  page336_i157
#ISCELL
  pure_quanta_power universal_gnd *
  page336_i158
#CELL
  pure_quanta 74lvc1g126se7 *
  page336_i159
#CELL
  pure_quanta q_cap *
  page336_i16
#CELL
  pure_quanta q_res *
  page336_i160
#ISCELL
  standard offpage *
  page336_i161
#ISCELL
  pure_quanta_power universal_gnd *
  page336_i162
#ISCELL
  standard offpage *
  page336_i163
#CELL
  pure_quanta q_res *
  page336_i164
#CELL
  pure_quanta q_res *
  page336_i165
#CELL
  pure_quanta 74cbtlv3126pw *
  page336_i2
#ISCELL
  standard offpage *
  page336_i35
#ISCELL
  standard offpage *
  page336_i36
#ISCELL
  standard offpage *
  page336_i37
#ISCELL
  standard offpage *
  page336_i38
#ISCELL
  standard offpage *
  page336_i39
#ISCELL
  standard offpage *
  page336_i40
#ISCELL
  standard offpage *
  page336_i41
#ISCELL
  standard offpage *
  page336_i42
#ISCELL
  pure_quanta_power universal_power *
  page336_i43
#ISCELL
  pure_quanta_power universal_gnd *
  page336_i44
#ISCELL
  pure_quanta_power universal_gnd *
  page336_i45
#ISCELL
  pure_quanta_power universal_power *
  page336_i46
#CELL
  pure_quanta q_cap *
  page336_i47
#ISCELL
  pure_quanta_power universal_gnd *
  page336_i48
#ISCELL
  pure_quanta_power universal_power *
  page336_i54
#CELL
  pure_quanta q_res *
  page336_i56
#ISCELL
  pure_quanta_power universal_gnd *
  page336_i57
#ISCELL
  pure_quanta_power universal_gnd *
  page336_i58
#CELL
  pure_quanta q_cap *
  page336_i59
#ISCELL
  standard offpage *
  page336_i61
#ISCELL
  standard offpage *
  page336_i62
#ISCELL
  standard offpage *
  page336_i64
#ISCELL
  standard offpage *
  page336_i65
#ISCELL
  standard offpage *
  page336_i66
#ISCELL
  standard offpage *
  page336_i78
#ISCELL
  standard offpage *
  page336_i79
#ISCELL
  standard offpage *
  page336_i80
#ISCELL
  standard offpage *
  page336_i81
#CELL
  pure_quanta q_res *
  page336_i98
#CELL
  pure_quanta q_res *
  page336_i99
#ISCELL
  mstr_misc dns *
  *
#ISCELL
  pure_quanta quanta_title_block_c *
  *
#ISCELL
  pure_quanta_power cad_note *
  *
#CELL
  pure_quanta q_res *
  page337_i1
#ISCELL
  standard offpage *
  page337_i10
#CELL
  pure_quanta q_res *
  page337_i11
#CELL
  pure_quanta q_res *
  page337_i12
#ISCELL
  pure_quanta_power universal_power *
  page337_i13
#ISCELL
  standard offpage *
  page337_i14
#ISCELL
  pure_quanta_power universal_gnd *
  page337_i15
#CELL
  pure_quanta pi6cv304le *
  page337_i16
#ISCELL
  pure_quanta_power universal_power *
  page337_i17
#ISCELL
  pure_quanta_power universal_gnd *
  page337_i18
#CELL
  pure_quanta q_cap *
  page337_i19
#ISCELL
  pure_quanta_power universal_gnd *
  page337_i2
#CELL
  pure_quanta q_res *
  page337_i20
#CELL
  pure_quanta q_res *
  page337_i21
#CELL
  pure_quanta q_res *
  page337_i22
#ISCELL
  standard offpage *
  page337_i23
#ISCELL
  pure_quanta_power universal_gnd *
  page337_i24
#CELL
  pure_quanta 74lvc1g07gv *
  page337_i25
#ISCELL
  standard offpage *
  page337_i26
#ISCELL
  standard offpage *
  page337_i27
#ISCELL
  standard offpage *
  page337_i28
#CELL
  pure_quanta q_res *
  page337_i29
#CELL
  pure_quanta q_cap *
  page337_i3
#ISCELL
  standard offpage *
  page337_i30
#CELL
  pure_quanta q_res *
  page337_i31
#ISCELL
  pure_quanta_power universal_gnd *
  page337_i32
#CELL
  pure_quanta q_cap *
  page337_i33
#ISCELL
  pure_quanta_power universal_power *
  page337_i34
#CELL
  pure_quanta q_res *
  page337_i35
#ISCELL
  pure_quanta_power universal_power *
  page337_i36
#ISCELL
  pure_quanta_power universal_gnd *
  page337_i37
#CELL
  pure_quanta 74lvc1g07gv *
  page337_i38
#ISCELL
  pure_quanta_power universal_gnd *
  page337_i39
#CELL
  pure_quanta q_osc4p *
  page337_i4
#CELL
  pure_quanta q_cap *
  page337_i40
#ISCELL
  pure_quanta_power universal_power *
  page337_i41
#CELL
  pure_quanta q_res *
  page337_i42
#ISCELL
  pure_quanta_power universal_power *
  page337_i43
#CELL
  pure_quanta q_res *
  page337_i44
#ISCELL
  pure_quanta_power universal_power *
  page337_i45
#ISCELL
  pure_quanta_power universal_gnd *
  page337_i46
#CELL
  pure_quanta q_cap *
  page337_i47
#ISCELL
  standard offpage *
  page337_i48
#ISCELL
  pure_quanta_power universal_gnd *
  page337_i49
#ISCELL
  pure_quanta_power universal_power *
  page337_i5
#CELL
  pure_quanta q_res *
  page337_i50
#ISCELL
  standard offpage *
  page337_i51
#ISCELL
  pure_quanta_power universal_gnd *
  page337_i52
#CELL
  pure_quanta q_cap *
  page337_i53
#ISCELL
  pure_quanta_power universal_power *
  page337_i54
#ISCELL
  standard offpage *
  page337_i55
#CELL
  pure_quanta q_res *
  page337_i56
#ISCELL
  pure_quanta_power universal_power *
  page337_i57
#ISCELL
  standard offpage *
  page337_i59
#ISCELL
  pure_quanta_power universal_gnd *
  page337_i6
#ISCELL
  pure_quanta_power universal_gnd *
  page337_i60
#CELL
  pure_quanta q_cap *
  page337_i61
#ISCELL
  pure_quanta_power universal_gnd *
  page337_i62
#ISCELL
  pure_quanta_power universal_power *
  page337_i63
#CELL
  pure_quanta 74lvc1g17gw *
  page337_i64
#CELL
  pure_quanta q_res *
  page337_i7
#ISCELL
  standard offpage *
  page337_i74
#ISCELL
  standard offpage *
  page337_i75
#ISCELL
  standard offpage *
  page337_i76
#ISCELL
  standard offpage *
  page337_i77
#CELL
  pure_quanta q_res *
  page337_i78
#CELL
  pure_quanta q_res *
  page337_i79
#CELL
  pure_quanta 74lvc1g126se7 *
  page337_i8
#CELL
  pure_quanta q_res *
  page337_i80
#CELL
  pure_quanta q_res *
  page337_i81
#CELL
  pure_quanta 74lvc1g66gv *
  page337_i82
#ISCELL
  pure_quanta_power universal_gnd *
  page337_i9
#ISCELL
  mstr_misc dns *
  *
#ISCELL
  pure_quanta quanta_title_block_c *
  *
#ISCELL
  pure_quanta_power cad_note *
  *
#ISCELL
  pure_quanta_power universal_gnd *
  page338_i1
#ISCELL
  pure_quanta_power universal_power *
  page338_i10
#CELL
  pure_quanta q_cap *
  page338_i100
#CELL
  pure_quanta q_res *
  page338_i101
#ISCELL
  pure_quanta_power vccaux15 *
  page338_i102
#CELL
  pure_quanta q_cap *
  page338_i104
#ISCELL
  pure_quanta_power gnd *
  page338_i105
#CELL
  pure_quanta q_cap *
  page338_i106
#ISCELL
  pure_quanta_power universal_power *
  page338_i107
#ISCELL
  standard offpage *
  page338_i108
#ISCELL
  pure_quanta_power gnd *
  page338_i109
#CELL
  pure_quanta mosfet_nch_dual *
  page338_i11
#CELL
  pure_quanta q_cap *
  page338_i110
#CELL
  pure_quanta q_res *
  page338_i111
#CELL
  pure_quanta mosfet_nch_dual *
  page338_i112
#CELL
  pure_quanta max15090bewit *
  page338_i113
#CELL
  pure_quanta q_res *
  page338_i114
#CELL
  pure_quanta diode_tvs *
  page338_i115
#CELL
  pure_quanta q_res *
  page338_i116
#ISCELL
  standard offpage *
  page338_i117
#CELL
  pure_quanta q_res *
  page338_i118
#ISCELL
  pure_quanta_power gnd *
  page338_i12
#CELL
  pure_quanta q_res *
  page338_i123
#ISCELL
  standard offpage *
  page338_i124
#CELL
  pure_quanta q_res *
  page338_i125
#CELL
  pure_quanta q_res *
  page338_i126
#CELL
  pure_quanta q_res *
  page338_i127
#ISCELL
  standard offpage *
  page338_i129
#ISCELL
  standard offpage *
  page338_i13
#CELL
  pure_quanta q_res *
  page338_i130
#CELL
  pure_quanta q_res *
  page338_i131
#CELL
  pure_quanta q_res *
  page338_i132
#CELL
  pure_quanta q_res *
  page338_i133
#ISCELL
  standard offpage *
  page338_i134
#CELL
  pure_quanta q_res *
  page338_i135
#ISCELL
  standard offpage *
  page338_i14
#CELL
  pure_quanta q_res *
  page338_i15
#ISCELL
  pure_quanta_power universal_power *
  page338_i16
#CELL
  pure_quanta q_res *
  page338_i17
#ISCELL
  pure_quanta_power universal_power *
  page338_i18
#CELL
  pure_quanta mosfet_nch_dual *
  page338_i19
#ISCELL
  standard offpage *
  page338_i2
#ISCELL
  pure_quanta_power gnd *
  page338_i20
#CELL
  pure_quanta mosfet_nch_dual *
  page338_i23
#CELL
  pure_quanta q_res *
  page338_i24
#ISCELL
  pure_quanta_power universal_gnd *
  page338_i25
#CELL
  pure_quanta 74lvc2g07dw7 *
  page338_i26
#ISCELL
  pure_quanta_power universal_gnd *
  page338_i27
#CELL
  pure_quanta q_res *
  page338_i28
#CELL
  pure_quanta 74lvc2g07dw7 *
  page338_i29
#ISCELL
  standard offpage *
  page338_i3
#CELL
  pure_quanta q_cap *
  page338_i30
#ISCELL
  pure_quanta_power universal_power *
  page338_i31
#ISCELL
  pure_quanta_power universal_gnd *
  page338_i32
#CELL
  pure_quanta q_cap *
  page338_i33
#ISCELL
  pure_quanta_power universal_power *
  page338_i34
#ISCELL
  pure_quanta_power gnd *
  page338_i35
#CELL
  pure_quanta q_res *
  page338_i36
#ISCELL
  pure_quanta_power gnd *
  page338_i37
#ISCELL
  pure_quanta_power gnd *
  page338_i38
#ISCELL
  pure_quanta_power gnd *
  page338_i39
#CELL
  pure_quanta q_res *
  page338_i40
#ISCELL
  pure_quanta_power gnd *
  page338_i41
#CELL
  pure_quanta q_res *
  page338_i42
#CELL
  pure_quanta q_res *
  page338_i43
#ISCELL
  pure_quanta_power universal_power *
  page338_i44
#CELL
  pure_quanta q_cap *
  page338_i45
#CELL
  pure_quanta q_res *
  page338_i46
#CELL
  pure_quanta q_res *
  page338_i48
#ISCELL
  pure_quanta_power gnd *
  page338_i49
#ISCELL
  pure_quanta_power gnd *
  page338_i5
#CELL
  pure_quanta max15090bewit *
  page338_i50
#ISCELL
  pure_quanta_power universal_power *
  page338_i52
#ISCELL
  pure_quanta_power gnd *
  page338_i53
#CELL
  pure_quanta q_cap *
  page338_i54
#CELL
  pure_quanta q_cap *
  page338_i55
#CELL
  pure_quanta q_res *
  page338_i56
#ISCELL
  pure_quanta_power gnd *
  page338_i57
#ISCELL
  pure_quanta_power gnd *
  page338_i58
#CELL
  pure_quanta q_res *
  page338_i59
#ISCELL
  pure_quanta_power universal_power *
  page338_i60
#CELL
  pure_quanta q_res *
  page338_i61
#CELL
  pure_quanta q_cap *
  page338_i62
#ISCELL
  pure_quanta_power universal_power *
  page338_i63
#CELL
  pure_quanta q_res *
  page338_i64
#ISCELL
  pure_quanta_power gnd *
  page338_i65
#CELL
  pure_quanta q_res *
  page338_i66
#CELL
  pure_quanta q_cap *
  page338_i67
#CELL
  pure_quanta q_res *
  page338_i68
#ISCELL
  standard offpage *
  page338_i69
#ISCELL
  standard offpage *
  page338_i7
#CELL
  pure_quanta q_res *
  page338_i71
#ISCELL
  pure_quanta_power gnd *
  page338_i72
#CELL
  pure_quanta q_res *
  page338_i73
#CELL
  pure_quanta q_cap *
  page338_i74
#CELL
  pure_quanta q_res *
  page338_i75
#CELL
  pure_quanta q_res *
  page338_i76
#CELL
  pure_quanta q_cap *
  page338_i77
#ISCELL
  pure_quanta_power gnd *
  page338_i78
#CELL
  pure_quanta schottky_ac *
  page338_i79
#ISCELL
  standard offpage *
  page338_i8
#CELL
  pure_quanta q_res *
  page338_i80
#ISCELL
  pure_quanta_power gnd *
  page338_i81
#CELL
  pure_quanta q_res *
  page338_i82
#CELL
  pure_quanta q_res *
  page338_i83
#ISCELL
  pure_quanta_power vccaux15 *
  page338_i84
#CELL
  pure_quanta q_res *
  page338_i85
#CELL
  pure_quanta q_cap *
  page338_i86
#CELL
  pure_quanta q_cap *
  page338_i87
#ISCELL
  pure_quanta_power gnd *
  page338_i88
#CELL
  pure_quanta q_cap *
  page338_i89
#CELL
  pure_quanta q_res *
  page338_i9
#ISCELL
  pure_quanta_power universal_power *
  page338_i90
#ISCELL
  standard offpage *
  page338_i91
#ISCELL
  standard offpage *
  page338_i92
#ISCELL
  standard offpage *
  page338_i93
#CELL
  pure_quanta q_cap *
  page338_i94
#CELL
  pure_quanta q_res *
  page338_i95
#CELL
  pure_quanta q_res *
  page338_i96
#CELL
  pure_quanta schottky_ac *
  page338_i97
#ISCELL
  pure_quanta_power gnd *
  page338_i99
#ISCELL
  mstr_misc dns *
  *
#ISCELL
  pure_quanta quanta_title_block_c *
  *
#ISCELL
  pure_quanta_power cad_note *
  *
#CELL
  pure_quanta q_res *
  page339_i100
#ISCELL
  pure_quanta_power universal_gnd *
  page339_i101
#CELL
  pure_quanta q_res *
  page339_i102
#ISCELL
  pure_quanta_power universal_gnd *
  page339_i103
#CELL
  pure_quanta q_cap *
  page339_i104
#ISCELL
  pure_quanta_power universal_gnd *
  page339_i105
#CELL
  pure_quanta q_cap *
  page339_i106
#ISCELL
  pure_quanta_power universal_gnd *
  page339_i107
#CELL
  pure_quanta q_cap *
  page339_i108
#ISCELL
  pure_quanta_power universal_gnd *
  page339_i110
#CELL
  pure_quanta q_cap *
  page339_i111
#ISCELL
  pure_quanta_power universal_power *
  page339_i112
#CELL
  pure_quanta mp5016gqhlz *
  page339_i113
#ISCELL
  pure_quanta_power universal_power *
  page339_i114
#CELL
  pure_quanta q_res *
  page339_i128
#ISCELL
  standard offpage *
  page339_i129
#CELL
  pure_quanta q_res *
  page339_i130
#CELL
  pure_quanta q_res *
  page339_i131
#ISCELL
  standard offpage *
  page339_i133
#CELL
  pure_quanta q_res *
  page339_i134
#CELL
  pure_quanta q_res *
  page339_i135
#ISCELL
  standard offpage *
  page339_i136
#CELL
  pure_quanta rs31312r *
  page339_i137
#ISCELL
  standard offpage *
  page339_i58
#ISCELL
  pure_quanta_power gnd *
  page339_i59
#CELL
  pure_quanta q_cap *
  page339_i60
#ISCELL
  pure_quanta_power gnd *
  page339_i61
#ISCELL
  pure_quanta_power gnd *
  page339_i62
#CELL
  pure_quanta q_res *
  page339_i63
#CELL
  pure_quanta q_cap *
  page339_i64
#ISCELL
  pure_quanta_power gnd *
  page339_i66
#ISCELL
  pure_quanta_power gnd *
  page339_i67
#CELL
  pure_quanta q_cap *
  page339_i68
#ISCELL
  pure_quanta_power universal_power *
  page339_i69
#ISCELL
  pure_quanta_power gnd *
  page339_i70
#CELL
  pure_quanta q_res *
  page339_i71
#ISCELL
  pure_quanta_power gnd *
  page339_i72
#CELL
  pure_quanta q_cap *
  page339_i73
#CELL
  pure_quanta q_res *
  page339_i74
#CELL
  pure_quanta q_res *
  page339_i75
#CELL
  pure_quanta q_res *
  page339_i76
#ISCELL
  standard offpage *
  page339_i77
#ISCELL
  standard offpage *
  page339_i78
#ISCELL
  pure_quanta_power gnd *
  page339_i79
#CELL
  pure_quanta q_res *
  page339_i80
#CELL
  pure_quanta q_res *
  page339_i81
#CELL
  pure_quanta q_res *
  page339_i82
#ISCELL
  pure_quanta_power vccaux15 *
  page339_i83
#CELL
  pure_quanta q_res *
  page339_i84
#CELL
  pure_quanta q_res *
  page339_i85
#CELL
  pure_quanta q_cap *
  page339_i86
#ISCELL
  standard offpage *
  page339_i87
#CELL
  pure_quanta q_res *
  page339_i88
#ISCELL
  pure_quanta_power universal_power *
  page339_i89
#ISCELL
  pure_quanta_power gnd *
  page339_i90
#CELL
  pure_quanta q_cap *
  page339_i91
#ISCELL
  pure_quanta_power universal_power *
  page339_i92
#ISCELL
  standard offpage *
  page339_i93
#ISCELL
  standard offpage *
  page339_i94
#ISCELL
  pure_quanta_power vccaux15 *
  page339_i95
#ISCELL
  pure_quanta_power universal_gnd *
  page339_i97
#CELL
  pure_quanta q_cap *
  page339_i98
#ISCELL
  standard offpage *
  page339_i99
#ISCELL
  mstr_misc dns *
  *
#ISCELL
  pure_quanta quanta_title_block_c *
  *
#ISCELL
  pure_quanta_power design_note *
  *
#ISCELL
  standard offpage *
  page340_i1
#ISCELL
  standard offpage *
  page340_i100
#CELL
  pure_quanta q_res *
  page340_i101
#CELL
  pure_quanta q_res *
  page340_i102
#ISCELL
  standard offpage *
  page340_i12
#CELL
  pure_quanta q_res *
  page340_i13
#CELL
  pure_quanta q_res *
  page340_i14
#CELL
  pure_quanta q_res *
  page340_i15
#ISCELL
  pure_quanta_power universal_gnd *
  page340_i16
#CELL
  pure_quanta q_res *
  page340_i18
#ISCELL
  pure_quanta_power universal_gnd *
  page340_i19
#CELL
  pure_quanta q_res *
  page340_i2
#ISCELL
  pure_quanta_power universal_power *
  page340_i21
#CELL
  pure_quanta q_res *
  page340_i22
#ISCELL
  standard offpage *
  page340_i23
#ISCELL
  pure_quanta_power universal_gnd *
  page340_i24
#CELL
  pure_quanta 74lvc1g08w57 *
  page340_i25
#ISCELL
  pure_quanta_power universal_gnd *
  page340_i26
#CELL
  pure_quanta q_cap *
  page340_i27
#ISCELL
  pure_quanta_power universal_power *
  page340_i28
#CELL
  pure_quanta q_res *
  page340_i29
#CELL
  pure_quanta q_res *
  page340_i3
#ISCELL
  standard offpage *
  page340_i30
#CELL
  pure_quanta mosfet_n *
  page340_i31
#ISCELL
  pure_quanta_power universal_gnd *
  page340_i32
#ISCELL
  standard offpage *
  page340_i33
#CELL
  pure_quanta q_res *
  page340_i34
#ISCELL
  pure_quanta_power universal_power *
  page340_i35
#CELL
  pure_quanta 74lvc1g08w57 *
  page340_i36
#ISCELL
  pure_quanta_power universal_gnd *
  page340_i37
#ISCELL
  pure_quanta_power universal_power *
  page340_i39
#ISCELL
  pure_quanta_power universal_power *
  page340_i4
#CELL
  pure_quanta q_cap *
  page340_i40
#ISCELL
  pure_quanta_power universal_gnd *
  page340_i41
#ISCELL
  pure_quanta_power universal_power *
  page340_i43
#CELL
  pure_quanta q_res *
  page340_i44
#CELL
  pure_quanta q_res *
  page340_i47
#ISCELL
  standard offpage *
  page340_i48
#CELL
  pure_quanta q_res *
  page340_i49
#ISCELL
  standard offpage *
  page340_i50
#CELL
  pure_quanta sn74lvc1g07dbvr *
  page340_i51
#ISCELL
  pure_quanta_power universal_power *
  page340_i52
#CELL
  pure_quanta q_cap *
  page340_i53
#ISCELL
  pure_quanta_power universal_gnd *
  page340_i54
#ISCELL
  pure_quanta_power universal_gnd *
  page340_i55
#ISCELL
  standard offpage *
  page340_i56
#CELL
  pure_quanta q_res *
  page340_i57
#CELL
  pure_quanta q_res *
  page340_i58
#ISCELL
  standard offpage *
  page340_i59
#ISCELL
  pure_quanta_power universal_power *
  page340_i60
#CELL
  pure_quanta q_res *
  page340_i61
#ISCELL
  standard offpage *
  page340_i62
#ISCELL
  pure_quanta_power universal_power *
  page340_i63
#CELL
  pure_quanta q_res *
  page340_i64
#CELL
  pure_quanta q_res *
  page340_i65
#CELL
  pure_quanta sn74lvc1g07dbvr *
  page340_i66
#ISCELL
  pure_quanta_power universal_gnd *
  page340_i67
#ISCELL
  pure_quanta_power universal_power *
  page340_i68
#CELL
  pure_quanta q_cap *
  page340_i69
#ISCELL
  pure_quanta_power universal_gnd *
  page340_i70
#CELL
  pure_quanta q_res *
  page340_i71
#ISCELL
  standard offpage *
  page340_i72
#ISCELL
  standard offpage *
  page340_i73
#CELL
  pure_quanta 74lvc1g32gw *
  page340_i74
#CELL
  pure_quanta q_cap *
  page340_i75
#CELL
  pure_quanta q_res *
  page340_i76
#ISCELL
  pure_quanta_power universal_power *
  page340_i77
#ISCELL
  pure_quanta_power universal_gnd *
  page340_i78
#CELL
  pure_quanta q_cap *
  page340_i79
#CELL
  pure_quanta apx80929sag7 *
  page340_i80
#ISCELL
  pure_quanta_power universal_power *
  page340_i81
#ISCELL
  pure_quanta_power universal_gnd *
  page340_i82
#ISCELL
  pure_quanta_power universal_gnd *
  page340_i83
#CELL
  pure_quanta q_res *
  page340_i84
#CELL
  pure_quanta q_res *
  page340_i85
#ISCELL
  standard offpage *
  page340_i86
#ISCELL
  pure_quanta_power universal_power *
  page340_i87
#CELL
  pure_quanta q_res *
  page340_i90
#CELL
  pure_quanta 74lvc1g08w57 *
  page340_i91
#ISCELL
  pure_quanta_power universal_gnd *
  page340_i92
#ISCELL
  pure_quanta_power universal_power *
  page340_i93
#CELL
  pure_quanta q_cap *
  page340_i94
#ISCELL
  pure_quanta_power universal_gnd *
  page340_i95
#CELL
  pure_quanta q_res *
  page340_i96
#ISCELL
  standard offpage *
  page340_i97
#ISCELL
  standard offpage *
  page340_i98
#ISCELL
  standard offpage *
  page340_i99
#ISCELL
  mstr_misc dns *
  *
#ISCELL
  pure_quanta quanta_title_block_c *
  *
#ISCELL
  pure_quanta_power cad_note *
  *
#ISCELL
  pure_quanta_power universal_gnd *
  page341_i1
#CELL
  pure_quanta q_res *
  page341_i10
#ISCELL
  pure_quanta_power universal_gnd *
  page341_i100
#ISCELL
  standard tap *
  page341_i101
#ISCELL
  pure_quanta_power universal_power *
  page341_i102
#ISCELL
  standard tap *
  page341_i103
#ISCELL
  standard tap *
  page341_i104
#ISCELL
  standard tap *
  page341_i105
#ISCELL
  standard tap *
  page341_i106
#ISCELL
  standard tap *
  page341_i107
#ISCELL
  standard tap *
  page341_i108
#ISCELL
  standard tap *
  page341_i109
#CELL
  pure_quanta q_res *
  page341_i11
#ISCELL
  standard tap *
  page341_i110
#ISCELL
  standard tap *
  page341_i111
#ISCELL
  standard tap *
  page341_i112
#ISCELL
  standard tap *
  page341_i113
#ISCELL
  standard tap *
  page341_i114
#ISCELL
  standard tap *
  page341_i115
#ISCELL
  standard tap *
  page341_i116
#ISCELL
  standard tap *
  page341_i117
#ISCELL
  standard tap *
  page341_i118
#ISCELL
  standard tap *
  page341_i119
#CELL
  pure_quanta q_res *
  page341_i12
#ISCELL
  standard tap *
  page341_i120
#ISCELL
  standard tap *
  page341_i121
#ISCELL
  standard tap *
  page341_i122
#ISCELL
  standard tap *
  page341_i123
#ISCELL
  standard tap *
  page341_i124
#ISCELL
  standard tap *
  page341_i125
#ISCELL
  standard tap *
  page341_i126
#ISCELL
  standard tap *
  page341_i127
#ISCELL
  standard tap *
  page341_i128
#ISCELL
  standard tap *
  page341_i129
#CELL
  pure_quanta q_cap *
  page341_i13
#ISCELL
  standard tap *
  page341_i130
#ISCELL
  standard tap *
  page341_i131
#ISCELL
  standard tap *
  page341_i132
#ISCELL
  standard tap *
  page341_i133
#ISCELL
  standard offpage *
  page341_i134
#CELL
  pure_quanta q_res *
  page341_i135
#CELL
  pure_quanta q_res *
  page341_i136
#ISCELL
  pure_quanta_power universal_power *
  page341_i137
#ISCELL
  standard offpage *
  page341_i138
#CELL
  pure_quanta q_cap *
  page341_i14
#ISCELL
  standard offpage *
  page341_i141
#ISCELL
  standard offpage *
  page341_i142
#ISCELL
  standard offpage *
  page341_i143
#ISCELL
  standard offpage *
  page341_i144
#ISCELL
  standard offpage *
  page341_i145
#ISCELL
  standard offpage *
  page341_i146
#ISCELL
  standard offpage *
  page341_i147
#ISCELL
  standard offpage *
  page341_i148
#ISCELL
  standard offpage *
  page341_i149
#CELL
  pure_quanta q_cap *
  page341_i15
#CELL
  pure_quanta q_res *
  page341_i150
#ISCELL
  pure_quanta_power universal_gnd *
  page341_i151
#ISCELL
  standard offpage *
  page341_i152
#ISCELL
  standard offpage *
  page341_i153
#ISCELL
  standard offpage *
  page341_i154
#ISCELL
  standard offpage *
  page341_i155
#ISCELL
  standard offpage *
  page341_i156
#ISCELL
  standard offpage *
  page341_i157
#ISCELL
  standard offpage *
  page341_i158
#ISCELL
  standard offpage *
  page341_i159
#CELL
  pure_quanta q_cap *
  page341_i16
#ISCELL
  standard offpage *
  page341_i160
#ISCELL
  standard offpage *
  page341_i161
#ISCELL
  standard offpage *
  page341_i162
#ISCELL
  standard offpage *
  page341_i163
#ISCELL
  standard offpage *
  page341_i164
#ISCELL
  standard offpage *
  page341_i165
#ISCELL
  standard tap *
  page341_i166
#ISCELL
  standard tap *
  page341_i167
#CELL
  pure_quanta sconn168_me1016810202011 *
  page341_i168
#ISCELL
  pure_quanta_power universal_gnd *
  page341_i169
#CELL
  pure_quanta q_cap *
  page341_i17
#CELL
  pure_quanta q_res *
  page341_i170
#CELL
  pure_quanta q_res *
  page341_i171
#CELL
  pure_quanta q_cap *
  page341_i18
#ISCELL
  pure_quanta_power universal_gnd *
  page341_i19
#CELL
  pure_quanta q_res *
  page341_i2
#CELL
  pure_quanta q_cap *
  page341_i20
#CELL
  pure_quanta q_cap *
  page341_i21
#CELL
  pure_quanta q_cap *
  page341_i22
#CELL
  pure_quanta q_cap *
  page341_i23
#CELL
  pure_quanta q_cap *
  page341_i24
#ISCELL
  pure_quanta_power universal_gnd *
  page341_i25
#CELL
  pure_quanta q_res *
  page341_i26
#ISCELL
  pure_quanta_power universal_power *
  page341_i27
#CELL
  pure_quanta q_res *
  page341_i28
#ISCELL
  standard offpage *
  page341_i29
#CELL
  pure_quanta q_res *
  page341_i3
#ISCELL
  standard offpage *
  page341_i30
#ISCELL
  pure_quanta_power universal_gnd *
  page341_i31
#CELL
  pure_quanta q_res *
  page341_i32
#CELL
  pure_quanta q_res *
  page341_i33
#CELL
  pure_quanta q_res *
  page341_i34
#ISCELL
  standard offpage *
  page341_i35
#ISCELL
  standard offpage *
  page341_i36
#ISCELL
  standard offpage *
  page341_i37
#ISCELL
  standard offpage *
  page341_i38
#ISCELL
  standard offpage *
  page341_i39
#ISCELL
  pure_quanta_power universal_gnd *
  page341_i4
#ISCELL
  standard offpage *
  page341_i40
#ISCELL
  standard offpage *
  page341_i41
#CELL
  pure_quanta q_res *
  page341_i42
#CELL
  pure_quanta q_res *
  page341_i43
#CELL
  pure_quanta q_res *
  page341_i44
#CELL
  pure_quanta q_res *
  page341_i45
#ISCELL
  standard offpage *
  page341_i46
#ISCELL
  standard tap *
  page341_i47
#ISCELL
  standard tap *
  page341_i48
#ISCELL
  pure_quanta_power universal_gnd *
  page341_i49
#ISCELL
  standard offpage *
  page341_i5
#ISCELL
  standard tap *
  page341_i50
#ISCELL
  standard tap *
  page341_i51
#ISCELL
  standard tap *
  page341_i52
#ISCELL
  standard tap *
  page341_i53
#ISCELL
  standard tap *
  page341_i54
#ISCELL
  standard tap *
  page341_i55
#ISCELL
  standard tap *
  page341_i56
#ISCELL
  standard tap *
  page341_i57
#ISCELL
  standard tap *
  page341_i58
#ISCELL
  standard tap *
  page341_i59
#ISCELL
  standard offpage *
  page341_i6
#ISCELL
  standard tap *
  page341_i60
#ISCELL
  standard tap *
  page341_i61
#ISCELL
  standard offpage *
  page341_i62
#ISCELL
  standard offpage *
  page341_i63
#ISCELL
  standard offpage *
  page341_i64
#ISCELL
  standard offpage *
  page341_i65
#ISCELL
  standard offpage *
  page341_i66
#ISCELL
  standard offpage *
  page341_i67
#ISCELL
  standard tap *
  page341_i68
#ISCELL
  standard tap *
  page341_i69
#ISCELL
  standard offpage *
  page341_i7
#ISCELL
  standard tap *
  page341_i70
#ISCELL
  standard tap *
  page341_i71
#ISCELL
  standard tap *
  page341_i72
#ISCELL
  standard tap *
  page341_i73
#ISCELL
  standard tap *
  page341_i74
#ISCELL
  standard tap *
  page341_i75
#ISCELL
  standard tap *
  page341_i76
#ISCELL
  standard tap *
  page341_i77
#ISCELL
  standard tap *
  page341_i78
#ISCELL
  standard tap *
  page341_i79
#ISCELL
  standard offpage *
  page341_i8
#ISCELL
  standard tap *
  page341_i80
#ISCELL
  standard tap *
  page341_i81
#ISCELL
  standard tap *
  page341_i82
#ISCELL
  standard tap *
  page341_i83
#ISCELL
  standard offpage *
  page341_i84
#ISCELL
  standard offpage *
  page341_i85
#CELL
  pure_quanta q_res *
  page341_i86
#ISCELL
  standard offpage *
  page341_i87
#ISCELL
  standard offpage *
  page341_i88
#ISCELL
  standard offpage *
  page341_i89
#CELL
  pure_quanta q_res *
  page341_i9
#ISCELL
  standard offpage *
  page341_i90
#ISCELL
  standard offpage *
  page341_i91
#ISCELL
  standard offpage *
  page341_i92
#ISCELL
  standard offpage *
  page341_i93
#ISCELL
  standard offpage *
  page341_i94
#ISCELL
  standard offpage *
  page341_i95
#ISCELL
  standard offpage *
  page341_i96
#ISCELL
  pure_quanta_power universal_power *
  page341_i97
#ISCELL
  pure_quanta_power universal_power *
  page341_i98
#ISCELL
  pure_quanta_power universal_power *
  page341_i99
#ISCELL
  mstr_misc dns *
  *
#ISCELL
  pure_quanta quanta_title_block_c *
  *
#ISCELL
  pure_quanta_power universal_gnd *
  page307_i14
#CELL
  pure_quanta q_res *
  page307_i15
#CELL
  pure_quanta q_cap *
  page307_i17
#ISCELL
  pure_quanta_power universal_gnd *
  page307_i18
#ISCELL
  pure_quanta_power universal_power *
  page307_i19
#ISCELL
  standard offpage *
  page307_i20
#ISCELL
  standard offpage *
  page307_i21
#ISCELL
  standard offpage *
  page307_i22
#ISCELL
  standard offpage *
  page307_i23
#ISCELL
  pure_quanta_power universal_gnd *
  page307_i24
#ISCELL
  pure_quanta_power universal_gnd *
  page307_i25
#ISCELL
  pure_quanta_power universal_power *
  page307_i26
#ISCELL
  standard offpage *
  page307_i27
#ISCELL
  standard offpage *
  page307_i28
#ISCELL
  standard offpage *
  page307_i29
#ISCELL
  standard offpage *
  page307_i3
#ISCELL
  standard offpage *
  page307_i30
#ISCELL
  pure_quanta_power universal_gnd *
  page307_i31
#CELL
  pure_quanta 74cbtlv3126pw *
  page307_i32
#CELL
  pure_quanta q_cap *
  page307_i33
#ISCELL
  pure_quanta_power universal_gnd *
  page307_i34
#ISCELL
  pure_quanta_power universal_power *
  page307_i35
#CELL
  pure_quanta q_res *
  page307_i37
#CELL
  pure_quanta q_res *
  page307_i38
#ISCELL
  pure_quanta_power universal_gnd *
  page307_i39
#CELL
  pure_quanta q_res *
  page307_i40
#ISCELL
  standard offpage *
  page307_i44
#ISCELL
  standard offpage *
  page307_i45
#ISCELL
  standard offpage *
  page307_i46
#CELL
  pure_quanta q_res *
  page307_i56
#CELL
  pure_quanta q_res *
  page307_i60
#CELL
  pure_quanta q_res *
  page307_i61
#CELL
  pure_quanta q_res *
  page307_i62
#CELL
  pure_quanta q_res *
  page307_i63
#CELL
  pure_quanta q_res *
  page307_i64
#CELL
  pure_quanta q_res *
  page307_i65
#ISCELL
  standard offpage *
  page307_i66
#ISCELL
  standard offpage *
  page307_i67
#ISCELL
  standard offpage *
  page307_i68
#ISCELL
  standard offpage *
  page307_i69
#ISCELL
  standard offpage *
  page307_i73
#ISCELL
  standard offpage *
  page307_i74
#ISCELL
  standard offpage *
  page307_i75
#ISCELL
  standard offpage *
  page307_i76
#CELL
  pure_quanta q_cap *
  page307_i77
#CELL
  pure_quanta 74cbtlv3126pw *
  page307_i78
#CELL
  pure_quanta q_res *
  page307_i79
#CELL
  pure_quanta 74lvc1g126se7 *
  page307_i80
#CELL
  pure_quanta q_res *
  page307_i81
#ISCELL
  standard offpage *
  page307_i82
#ISCELL
  pure_quanta_power universal_gnd *
  page307_i83
#ISCELL
  standard offpage *
  page307_i84
#CELL
  pure_quanta q_res *
  page307_i85
#CELL
  pure_quanta q_res *
  page307_i86
#ISCELL
  standard offpage *
  page307_i9
#ISCELL
  mstr_misc dns *
  *
#ISCELL
  pure_quanta quanta_title_block_c *
  *
#ISCELL
  pure_quanta_power cad_note *
  *
#ISCELL
  standard offpage *
  page342_i1
#ISCELL
  pure_quanta_power universal_gnd *
  page342_i10
#ISCELL
  pure_quanta_power universal_gnd *
  page342_i11
#CELL
  pure_quanta q_cap *
  page342_i12
#ISCELL
  pure_quanta_power universal_power *
  page342_i13
#CELL
  pure_quanta 74lvc1g126se7 *
  page342_i14
#ISCELL
  standard offpage *
  page342_i15
#CELL
  pure_quanta q_cap *
  page342_i16
#ISCELL
  pure_quanta_power universal_gnd *
  page342_i17
#CELL
  pure_quanta q_res *
  page342_i18
#ISCELL
  pure_quanta_power universal_power *
  page342_i19
#ISCELL
  standard offpage *
  page342_i2
#ISCELL
  pure_quanta_power universal_power *
  page342_i20
#ISCELL
  pure_quanta_power universal_gnd *
  page342_i21
#CELL
  pure_quanta 74lvc1g07gv *
  page342_i22
#ISCELL
  pure_quanta_power universal_gnd *
  page342_i23
#CELL
  pure_quanta q_res *
  page342_i24
#CELL
  pure_quanta q_res *
  page342_i25
#ISCELL
  standard offpage *
  page342_i26
#ISCELL
  standard offpage *
  page342_i27
#ISCELL
  pure_quanta_power universal_gnd *
  page342_i28
#CELL
  pure_quanta q_res *
  page342_i29
#CELL
  pure_quanta q_res *
  page342_i3
#ISCELL
  pure_quanta_power universal_gnd *
  page342_i30
#CELL
  pure_quanta q_cap *
  page342_i31
#CELL
  pure_quanta 74lvc1g07gv *
  page342_i32
#CELL
  pure_quanta q_res *
  page342_i33
#CELL
  pure_quanta q_res *
  page342_i34
#ISCELL
  pure_quanta_power universal_power *
  page342_i35
#CELL
  pure_quanta q_res *
  page342_i36
#ISCELL
  standard offpage *
  page342_i37
#ISCELL
  pure_quanta_power universal_gnd *
  page342_i38
#ISCELL
  pure_quanta_power universal_power *
  page342_i39
#CELL
  pure_quanta q_res *
  page342_i4
#ISCELL
  pure_quanta_power universal_gnd *
  page342_i40
#CELL
  pure_quanta q_cap *
  page342_i41
#ISCELL
  standard offpage *
  page342_i42
#CELL
  pure_quanta q_res *
  page342_i43
#CELL
  pure_quanta q_res *
  page342_i44
#ISCELL
  pure_quanta_power universal_power *
  page342_i45
#ISCELL
  pure_quanta_power universal_gnd *
  page342_i46
#CELL
  pure_quanta q_cap *
  page342_i47
#ISCELL
  standard offpage *
  page342_i48
#ISCELL
  pure_quanta_power universal_power *
  page342_i49
#ISCELL
  pure_quanta_power universal_power *
  page342_i5
#ISCELL
  standard offpage *
  page342_i50
#ISCELL
  pure_quanta_power universal_power *
  page342_i51
#ISCELL
  standard offpage *
  page342_i53
#ISCELL
  pure_quanta_power universal_gnd *
  page342_i54
#CELL
  pure_quanta q_cap *
  page342_i55
#ISCELL
  pure_quanta_power universal_gnd *
  page342_i56
#ISCELL
  pure_quanta_power universal_power *
  page342_i57
#CELL
  pure_quanta 74lvc1g17gw *
  page342_i58
#CELL
  pure_quanta q_res *
  page342_i6
#ISCELL
  standard offpage *
  page342_i68
#ISCELL
  standard offpage *
  page342_i69
#ISCELL
  standard offpage *
  page342_i7
#ISCELL
  standard offpage *
  page342_i70
#ISCELL
  standard offpage *
  page342_i71
#CELL
  pure_quanta q_res *
  page342_i72
#CELL
  pure_quanta q_res *
  page342_i73
#CELL
  pure_quanta q_res *
  page342_i74
#CELL
  pure_quanta q_res *
  page342_i75
#CELL
  pure_quanta 74lvc1g66gv *
  page342_i76
#ISCELL
  pure_quanta_power universal_gnd *
  page342_i8
#CELL
  pure_quanta 74lvc1g126se7 *
  page342_i9
#ISCELL
  mstr_misc dns *
  *
#ISCELL
  pure_quanta quanta_title_block_c *
  *
#ISCELL
  pure_quanta_power cad_note *
  *
#ISCELL
  standard offpage *
  page343_i1
#CELL
  pure_quanta mosfet_nch_dual *
  page343_i10
#ISCELL
  pure_quanta_power gnd *
  page343_i100
#CELL
  pure_quanta q_cap *
  page343_i101
#ISCELL
  pure_quanta_power universal_power *
  page343_i102
#ISCELL
  pure_quanta_power gnd *
  page343_i103
#CELL
  pure_quanta q_cap *
  page343_i104
#CELL
  pure_quanta q_res *
  page343_i105
#CELL
  pure_quanta schottky_ac *
  page343_i106
#CELL
  pure_quanta q_res *
  page343_i107
#CELL
  pure_quanta q_cap *
  page343_i108
#ISCELL
  standard offpage *
  page343_i11
#ISCELL
  pure_quanta_power vccaux15 *
  page343_i110
#ISCELL
  pure_quanta_power gnd *
  page343_i111
#CELL
  pure_quanta q_cap *
  page343_i112
#ISCELL
  pure_quanta_power universal_power *
  page343_i113
#ISCELL
  standard offpage *
  page343_i114
#ISCELL
  pure_quanta_power universal_power *
  page343_i115
#CELL
  pure_quanta q_res *
  page343_i116
#ISCELL
  standard offpage *
  page343_i117
#CELL
  pure_quanta q_res *
  page343_i118
#CELL
  pure_quanta q_res *
  page343_i119
#ISCELL
  standard offpage *
  page343_i12
#CELL
  pure_quanta q_res *
  page343_i120
#CELL
  pure_quanta q_res *
  page343_i121
#CELL
  pure_quanta q_res *
  page343_i122
#CELL
  pure_quanta q_res *
  page343_i123
#ISCELL
  standard offpage *
  page343_i124
#ISCELL
  standard offpage *
  page343_i126
#CELL
  pure_quanta q_res *
  page343_i127
#CELL
  pure_quanta q_res *
  page343_i128
#CELL
  pure_quanta q_res *
  page343_i129
#ISCELL
  pure_quanta_power gnd *
  page343_i13
#CELL
  pure_quanta q_res *
  page343_i130
#ISCELL
  standard offpage *
  page343_i131
#CELL
  pure_quanta q_res *
  page343_i14
#ISCELL
  pure_quanta_power universal_power *
  page343_i15
#CELL
  pure_quanta q_res *
  page343_i16
#CELL
  pure_quanta q_res *
  page343_i17
#ISCELL
  pure_quanta_power universal_power *
  page343_i18
#CELL
  pure_quanta mosfet_nch_dual *
  page343_i19
#ISCELL
  standard offpage *
  page343_i2
#ISCELL
  pure_quanta_power gnd *
  page343_i20
#ISCELL
  pure_quanta_power universal_gnd *
  page343_i21
#CELL
  pure_quanta 74lvc2g07dw7 *
  page343_i22
#CELL
  pure_quanta q_cap *
  page343_i23
#ISCELL
  pure_quanta_power universal_gnd *
  page343_i24
#ISCELL
  pure_quanta_power universal_gnd *
  page343_i25
#ISCELL
  pure_quanta_power universal_power *
  page343_i26
#ISCELL
  pure_quanta_power universal_gnd *
  page343_i27
#CELL
  pure_quanta 74lvc2g07dw7 *
  page343_i28
#CELL
  pure_quanta q_cap *
  page343_i29
#ISCELL
  standard offpage *
  page343_i3
#ISCELL
  pure_quanta_power universal_power *
  page343_i30
#CELL
  pure_quanta q_res *
  page343_i31
#ISCELL
  pure_quanta_power gnd *
  page343_i32
#CELL
  pure_quanta q_res *
  page343_i33
#ISCELL
  pure_quanta_power gnd *
  page343_i34
#CELL
  pure_quanta q_res *
  page343_i35
#CELL
  pure_quanta q_res *
  page343_i36
#ISCELL
  standard offpage *
  page343_i37
#ISCELL
  pure_quanta_power gnd *
  page343_i39
#CELL
  pure_quanta q_res *
  page343_i4
#ISCELL
  pure_quanta_power gnd *
  page343_i41
#CELL
  pure_quanta mosfet_nch_dual *
  page343_i42
#CELL
  pure_quanta q_res *
  page343_i43
#ISCELL
  pure_quanta_power universal_power *
  page343_i44
#CELL
  pure_quanta mosfet_nch_dual *
  page343_i45
#ISCELL
  pure_quanta_power gnd *
  page343_i46
#CELL
  pure_quanta diode_tvs *
  page343_i47
#ISCELL
  pure_quanta_power universal_power *
  page343_i48
#CELL
  pure_quanta q_cap *
  page343_i49
#ISCELL
  pure_quanta_power universal_power *
  page343_i5
#CELL
  pure_quanta q_res *
  page343_i50
#CELL
  pure_quanta q_res *
  page343_i51
#ISCELL
  pure_quanta_power gnd *
  page343_i52
#CELL
  pure_quanta q_res *
  page343_i53
#ISCELL
  pure_quanta_power gnd *
  page343_i54
#CELL
  pure_quanta q_cap *
  page343_i55
#CELL
  pure_quanta q_res *
  page343_i56
#ISCELL
  pure_quanta_power universal_power *
  page343_i57
#CELL
  pure_quanta q_res *
  page343_i59
#CELL
  pure_quanta q_res *
  page343_i6
#ISCELL
  standard offpage *
  page343_i61
#ISCELL
  pure_quanta_power gnd *
  page343_i62
#CELL
  pure_quanta q_res *
  page343_i63
#ISCELL
  pure_quanta_power gnd *
  page343_i64
#CELL
  pure_quanta q_cap *
  page343_i65
#CELL
  pure_quanta q_cap *
  page343_i66
#CELL
  pure_quanta max15090bewit *
  page343_i67
#CELL
  pure_quanta q_res *
  page343_i69
#ISCELL
  pure_quanta_power gnd *
  page343_i70
#CELL
  pure_quanta q_res *
  page343_i71
#CELL
  pure_quanta q_cap *
  page343_i72
#CELL
  pure_quanta q_res *
  page343_i73
#CELL
  pure_quanta q_res *
  page343_i74
#CELL
  pure_quanta q_cap *
  page343_i75
#CELL
  pure_quanta q_res *
  page343_i76
#CELL
  pure_quanta q_res *
  page343_i77
#ISCELL
  pure_quanta_power gnd *
  page343_i78
#CELL
  pure_quanta q_res *
  page343_i79
#ISCELL
  pure_quanta_power gnd *
  page343_i8
#CELL
  pure_quanta q_res *
  page343_i80
#ISCELL
  standard offpage *
  page343_i81
#ISCELL
  standard offpage *
  page343_i82
#ISCELL
  standard offpage *
  page343_i83
#CELL
  pure_quanta q_res *
  page343_i84
#ISCELL
  pure_quanta_power gnd *
  page343_i85
#CELL
  pure_quanta q_cap *
  page343_i86
#ISCELL
  pure_quanta_power gnd *
  page343_i87
#CELL
  pure_quanta q_res *
  page343_i88
#CELL
  pure_quanta max15090bewit *
  page343_i89
#CELL
  pure_quanta q_cap *
  page343_i90
#CELL
  pure_quanta q_res *
  page343_i91
#CELL
  pure_quanta schottky_ac *
  page343_i92
#ISCELL
  pure_quanta_power gnd *
  page343_i93
#CELL
  pure_quanta q_res *
  page343_i94
#CELL
  pure_quanta q_cap *
  page343_i95
#CELL
  pure_quanta q_cap *
  page343_i97
#ISCELL
  pure_quanta_power vccaux15 *
  page343_i98
#CELL
  pure_quanta q_cap *
  page343_i99
#ISCELL
  mstr_misc dns *
  *
#ISCELL
  pure_quanta quanta_title_block_c *
  *
#ISCELL
  pure_quanta_power cad_note *
  *
#ISCELL
  pure_quanta_power gnd *
  page344_i1
#ISCELL
  pure_quanta_power gnd *
  page344_i11
#ISCELL
  pure_quanta_power gnd *
  page344_i12
#CELL
  pure_quanta q_cap *
  page344_i13
#ISCELL
  pure_quanta_power universal_power *
  page344_i14
#CELL
  pure_quanta q_res *
  page344_i15
#ISCELL
  pure_quanta_power gnd *
  page344_i16
#CELL
  pure_quanta q_res *
  page344_i18
#ISCELL
  pure_quanta_power vccaux15 *
  page344_i19
#CELL
  pure_quanta q_cap *
  page344_i2
#CELL
  pure_quanta q_res *
  page344_i20
#ISCELL
  pure_quanta_power gnd *
  page344_i21
#CELL
  pure_quanta q_res *
  page344_i22
#CELL
  pure_quanta q_res *
  page344_i23
#CELL
  pure_quanta q_cap *
  page344_i24
#ISCELL
  standard offpage *
  page344_i25
#ISCELL
  standard offpage *
  page344_i26
#CELL
  pure_quanta q_res *
  page344_i27
#ISCELL
  pure_quanta_power vccaux15 *
  page344_i28
#ISCELL
  standard offpage *
  page344_i29
#ISCELL
  pure_quanta_power gnd *
  page344_i3
#CELL
  pure_quanta q_res *
  page344_i30
#CELL
  pure_quanta q_res *
  page344_i31
#ISCELL
  standard offpage *
  page344_i32
#ISCELL
  standard offpage *
  page344_i33
#ISCELL
  pure_quanta_power universal_gnd *
  page344_i34
#CELL
  pure_quanta q_cap *
  page344_i35
#CELL
  pure_quanta q_res *
  page344_i36
#CELL
  pure_quanta q_res *
  page344_i37
#ISCELL
  pure_quanta_power universal_power *
  page344_i38
#ISCELL
  pure_quanta_power gnd *
  page344_i39
#CELL
  pure_quanta q_res *
  page344_i4
#CELL
  pure_quanta q_cap *
  page344_i40
#ISCELL
  pure_quanta_power universal_power *
  page344_i41
#ISCELL
  standard offpage *
  page344_i42
#CELL
  pure_quanta q_res *
  page344_i43
#ISCELL
  pure_quanta_power universal_gnd *
  page344_i45
#CELL
  pure_quanta q_res *
  page344_i46
#ISCELL
  pure_quanta_power universal_gnd *
  page344_i47
#CELL
  pure_quanta q_cap *
  page344_i48
#ISCELL
  pure_quanta_power universal_gnd *
  page344_i49
#ISCELL
  pure_quanta_power gnd *
  page344_i5
#CELL
  pure_quanta q_cap *
  page344_i50
#CELL
  pure_quanta mp5016gqhlz *
  page344_i51
#ISCELL
  pure_quanta_power universal_power *
  page344_i52
#ISCELL
  pure_quanta_power universal_gnd *
  page344_i53
#CELL
  pure_quanta q_cap *
  page344_i54
#ISCELL
  pure_quanta_power universal_gnd *
  page344_i55
#CELL
  pure_quanta q_cap *
  page344_i56
#ISCELL
  pure_quanta_power universal_power *
  page344_i57
#CELL
  pure_quanta q_cap *
  page344_i58
#CELL
  pure_quanta q_cap *
  page344_i6
#ISCELL
  pure_quanta_power gnd *
  page344_i7
#CELL
  pure_quanta q_res *
  page344_i73
#CELL
  pure_quanta q_res *
  page344_i74
#ISCELL
  standard offpage *
  page344_i75
#CELL
  pure_quanta q_res *
  page344_i76
#ISCELL
  standard offpage *
  page344_i77
#CELL
  pure_quanta q_res *
  page344_i79
#CELL
  pure_quanta q_res *
  page344_i80
#ISCELL
  standard offpage *
  page344_i81
#CELL
  pure_quanta rs31312r *
  page344_i82
#ISCELL
  standard offpage *
  page344_i9
#ISCELL
  mstr_misc dns *
  *
#ISCELL
  pure_quanta quanta_title_block_c *
  *
#ISCELL
  pure_quanta_power design_note *
  *
#ISCELL
  standard offpage *
  page257_i1
#CELL
  pure_quanta q_res *
  page257_i10
#ISCELL
  pure_quanta_power universal_power *
  page257_i11
#CELL
  pure_quanta q_res *
  page257_i12
#ISCELL
  pure_quanta_power universal_gnd *
  page257_i13
#CELL
  pure_quanta q_cap *
  page257_i14
#ISCELL
  pure_quanta_power universal_power *
  page257_i15
#CELL
  pure_quanta q_res *
  page257_i16
#CELL
  pure_quanta q_res *
  page257_i17
#CELL
  pure_quanta q_res *
  page257_i18
#CELL
  pure_quanta q_res *
  page257_i19
#ISCELL
  standard offpage *
  page257_i2
#ISCELL
  pure_quanta_power universal_power *
  page257_i20
#ISCELL
  standard offpage *
  page257_i21
#ISCELL
  standard offpage *
  page257_i22
#ISCELL
  pure_quanta_power universal_gnd *
  page257_i23
#CELL
  pure_quanta mosfet_n *
  page257_i24
#CELL
  pure_quanta q_res *
  page257_i25
#ISCELL
  pure_quanta_power universal_power *
  page257_i26
#ISCELL
  standard offpage *
  page257_i27
#CELL
  pure_quanta q_res *
  page257_i28
#ISCELL
  standard offpage *
  page257_i29
#CELL
  pure_quanta q_res *
  page257_i3
#ISCELL
  pure_quanta_power universal_gnd *
  page257_i30
#CELL
  pure_quanta 74lvc1g08w57 *
  page257_i31
#CELL
  pure_quanta q_res *
  page257_i32
#ISCELL
  pure_quanta_power universal_power *
  page257_i33
#CELL
  pure_quanta q_res *
  page257_i34
#ISCELL
  pure_quanta_power universal_gnd *
  page257_i35
#CELL
  pure_quanta q_cap *
  page257_i36
#ISCELL
  pure_quanta_power universal_power *
  page257_i37
#ISCELL
  pure_quanta_power universal_gnd *
  page257_i38
#CELL
  pure_quanta q_res *
  page257_i39
#ISCELL
  pure_quanta_power universal_gnd *
  page257_i4
#CELL
  pure_quanta 74lvc1g32gw *
  page257_i40
#CELL
  pure_quanta q_res *
  page257_i41
#CELL
  pure_quanta q_res *
  page257_i42
#ISCELL
  pure_quanta_power universal_gnd *
  page257_i43
#ISCELL
  pure_quanta_power universal_gnd *
  page257_i44
#CELL
  pure_quanta sn74lvc1g07dbvr *
  page257_i45
#CELL
  pure_quanta q_cap *
  page257_i46
#ISCELL
  pure_quanta_power universal_gnd *
  page257_i47
#ISCELL
  pure_quanta_power universal_power *
  page257_i48
#CELL
  pure_quanta q_res *
  page257_i49
#CELL
  pure_quanta q_cap *
  page257_i5
#ISCELL
  standard offpage *
  page257_i50
#CELL
  pure_quanta q_res *
  page257_i51
#ISCELL
  pure_quanta_power universal_power *
  page257_i52
#ISCELL
  standard offpage *
  page257_i53
#ISCELL
  pure_quanta_power universal_gnd *
  page257_i54
#CELL
  pure_quanta q_cap *
  page257_i55
#ISCELL
  pure_quanta_power universal_power *
  page257_i56
#CELL
  pure_quanta q_res *
  page257_i57
#CELL
  pure_quanta q_res *
  page257_i58
#ISCELL
  standard offpage *
  page257_i59
#ISCELL
  pure_quanta_power universal_power *
  page257_i6
#CELL
  pure_quanta q_res *
  page257_i60
#ISCELL
  pure_quanta_power universal_power *
  page257_i61
#ISCELL
  standard offpage *
  page257_i62
#CELL
  pure_quanta 74lvc1g08w57 *
  page257_i63
#CELL
  pure_quanta sn74lvc1g07dbvr *
  page257_i64
#ISCELL
  pure_quanta_power universal_gnd *
  page257_i65
#CELL
  pure_quanta q_cap *
  page257_i66
#CELL
  pure_quanta apx80929sag7 *
  page257_i67
#ISCELL
  pure_quanta_power universal_power *
  page257_i68
#ISCELL
  pure_quanta_power universal_gnd *
  page257_i69
#ISCELL
  standard offpage *
  page257_i7
#CELL
  pure_quanta q_res *
  page257_i70
#ISCELL
  pure_quanta_power universal_gnd *
  page257_i71
#ISCELL
  pure_quanta_power universal_power *
  page257_i72
#CELL
  pure_quanta q_res *
  page257_i73
#ISCELL
  standard offpage *
  page257_i74
#CELL
  pure_quanta q_res *
  page257_i77
#CELL
  pure_quanta 74lvc1g08w57 *
  page257_i78
#ISCELL
  pure_quanta_power universal_gnd *
  page257_i79
#ISCELL
  standard offpage *
  page257_i8
#ISCELL
  pure_quanta_power universal_power *
  page257_i80
#CELL
  pure_quanta q_cap *
  page257_i81
#ISCELL
  pure_quanta_power universal_gnd *
  page257_i82
#ISCELL
  standard offpage *
  page257_i83
#CELL
  pure_quanta q_res *
  page257_i84
#ISCELL
  standard offpage *
  page257_i85
#ISCELL
  standard offpage *
  page257_i86
#ISCELL
  standard offpage *
  page257_i87
#CELL
  pure_quanta q_res *
  page257_i88
#CELL
  pure_quanta q_res *
  page257_i89
#ISCELL
  pure_quanta_power universal_gnd *
  page257_i9
#ISCELL
  mstr_misc dns *
  *
#ISCELL
  pure_quanta quanta_title_block_c *
  *
#CELL
  pure_quanta 74lvc2g08dp *
  page258_i1
#ISCELL
  standard offpage *
  page258_i10
#CELL
  pure_quanta 74lvc2g08dp *
  page258_i11
#CELL
  pure_quanta 74lvc2g08dp *
  page258_i12
#CELL
  pure_quanta 74lvc2g08dp *
  page258_i13
#CELL
  pure_quanta 74lvc2g08dp *
  page258_i14
#CELL
  pure_quanta nc7sb3157 *
  page258_i15
#CELL
  pure_quanta nc7sb3157 *
  page258_i16
#CELL
  pure_quanta nc7sb3157 *
  page258_i17
#CELL
  pure_quanta nc7sb3157 *
  page258_i18
#ISCELL
  pure_quanta_power universal_gnd *
  page258_i19
#CELL
  pure_quanta 74lvc2g08dp *
  page258_i2
#ISCELL
  pure_quanta_power universal_power *
  page258_i20
#CELL
  pure_quanta q_cap *
  page258_i21
#CELL
  pure_quanta q_cap *
  page258_i22
#ISCELL
  pure_quanta_power universal_power *
  page258_i23
#ISCELL
  pure_quanta_power universal_gnd *
  page258_i24
#ISCELL
  pure_quanta_power universal_gnd *
  page258_i25
#ISCELL
  pure_quanta_power universal_gnd *
  page258_i26
#CELL
  pure_quanta q_cap *
  page258_i27
#ISCELL
  pure_quanta_power universal_gnd *
  page258_i28
#ISCELL
  pure_quanta_power universal_power *
  page258_i29
#ISCELL
  standard offpage *
  page258_i3
#ISCELL
  pure_quanta_power universal_power *
  page258_i30
#CELL
  pure_quanta q_cap *
  page258_i31
#ISCELL
  pure_quanta_power universal_gnd *
  page258_i32
#ISCELL
  pure_quanta_power universal_power *
  page258_i33
#CELL
  pure_quanta q_cap *
  page258_i34
#ISCELL
  pure_quanta_power universal_gnd *
  page258_i35
#ISCELL
  pure_quanta_power universal_gnd *
  page258_i36
#CELL
  pure_quanta q_cap *
  page258_i37
#ISCELL
  pure_quanta_power universal_power *
  page258_i38
#ISCELL
  pure_quanta_power universal_gnd *
  page258_i39
#ISCELL
  standard offpage *
  page258_i4
#ISCELL
  pure_quanta_power universal_power *
  page258_i40
#CELL
  pure_quanta q_cap *
  page258_i41
#ISCELL
  pure_quanta_power universal_gnd *
  page258_i42
#CELL
  pure_quanta q_res *
  page258_i44
#CELL
  pure_quanta q_res *
  page258_i45
#CELL
  pure_quanta q_res *
  page258_i46
#CELL
  pure_quanta q_res *
  page258_i47
#ISCELL
  standard offpage *
  page258_i48
#ISCELL
  standard offpage *
  page258_i49
#ISCELL
  standard offpage *
  page258_i5
#CELL
  pure_quanta q_res *
  page258_i50
#ISCELL
  standard offpage *
  page258_i51
#CELL
  pure_quanta q_res *
  page258_i52
#ISCELL
  standard offpage *
  page258_i53
#ISCELL
  standard offpage *
  page258_i54
#ISCELL
  standard offpage *
  page258_i56
#ISCELL
  standard offpage *
  page258_i58
#ISCELL
  standard offpage *
  page258_i59
#ISCELL
  standard offpage *
  page258_i6
#ISCELL
  pure_quanta_power universal_gnd *
  page258_i60
#ISCELL
  pure_quanta_power universal_gnd *
  page258_i61
#ISCELL
  pure_quanta_power universal_gnd *
  page258_i62
#ISCELL
  pure_quanta_power universal_gnd *
  page258_i63
#CELL
  pure_quanta q_res *
  page258_i64
#CELL
  pure_quanta q_res *
  page258_i65
#CELL
  pure_quanta q_res *
  page258_i66
#CELL
  pure_quanta q_res *
  page258_i67
#CELL
  pure_quanta q_cap *
  page258_i68
#ISCELL
  pure_quanta_power universal_gnd *
  page258_i69
#ISCELL
  standard offpage *
  page258_i7
#CELL
  pure_quanta q_cap *
  page258_i70
#ISCELL
  pure_quanta_power universal_gnd *
  page258_i71
#CELL
  pure_quanta q_cap *
  page258_i72
#ISCELL
  pure_quanta_power universal_gnd *
  page258_i73
#CELL
  pure_quanta q_cap *
  page258_i74
#ISCELL
  pure_quanta_power universal_gnd *
  page258_i75
#ISCELL
  standard offpage *
  page258_i8
#ISCELL
  standard offpage *
  page258_i9
#ISCELL
  mstr_misc dns *
  *
#ISCELL
  pure_quanta quanta_title_block_c *
  *
#ISCELL
  standard offpage *
  page345_i1
#CELL
  pure_quanta q_res *
  page345_i10
#ISCELL
  pure_quanta_power universal_power *
  page345_i11
#CELL
  pure_quanta q_res *
  page345_i12
#ISCELL
  standard offpage *
  page345_i13
#ISCELL
  pure_quanta_power universal_gnd *
  page345_i14
#CELL
  pure_quanta q_res *
  page345_i15
#ISCELL
  standard offpage *
  page345_i16
#ISCELL
  standard offpage *
  page345_i17
#ISCELL
  standard offpage *
  page345_i18
#CELL
  pure_quanta q_res *
  page345_i19
#ISCELL
  standard offpage *
  page345_i2
#ISCELL
  standard offpage *
  page345_i20
#CELL
  pure_quanta q_res *
  page345_i21
#ISCELL
  pure_quanta_power universal_power *
  page345_i22
#ISCELL
  standard offpage *
  page345_i23
#CELL
  pure_quanta q_res *
  page345_i24
#ISCELL
  pure_quanta_power universal_power *
  page345_i25
#ISCELL
  standard offpage *
  page345_i26
#CELL
  pure_quanta q_res *
  page345_i27
#ISCELL
  standard offpage *
  page345_i28
#ISCELL
  standard offpage *
  page345_i29
#ISCELL
  pure_quanta_power universal_gnd *
  page345_i3
#CELL
  pure_quanta q_res *
  page345_i30
#ISCELL
  standard offpage *
  page345_i31
#CELL
  pure_quanta q_res *
  page345_i32
#ISCELL
  pure_quanta_power universal_gnd *
  page345_i33
#ISCELL
  standard tap *
  page345_i34
#ISCELL
  standard tap *
  page345_i35
#ISCELL
  standard tap *
  page345_i36
#ISCELL
  standard tap *
  page345_i37
#ISCELL
  standard tap *
  page345_i38
#ISCELL
  standard tap *
  page345_i39
#ISCELL
  pure_quanta_power universal_gnd *
  page345_i4
#ISCELL
  standard offpage *
  page345_i40
#ISCELL
  standard offpage *
  page345_i41
#ISCELL
  standard offpage *
  page345_i42
#ISCELL
  standard offpage *
  page345_i43
#ISCELL
  pure_quanta_power universal_power *
  page345_i44
#ISCELL
  standard tap *
  page345_i45
#ISCELL
  standard tap *
  page345_i46
#ISCELL
  standard tap *
  page345_i47
#ISCELL
  standard tap *
  page345_i48
#ISCELL
  standard tap *
  page345_i49
#CELL
  pure_quanta sn74lvc2g07dckr *
  page345_i5
#ISCELL
  standard tap *
  page345_i50
#CELL
  pure_quanta q_res *
  page345_i51
#ISCELL
  pure_quanta_power universal_power *
  page345_i52
#CELL
  pure_quanta 74lvc1g126se7 *
  page345_i53
#ISCELL
  pure_quanta_power universal_gnd *
  page345_i54
#ISCELL
  pure_quanta_power universal_gnd *
  page345_i55
#CELL
  pure_quanta q_cap *
  page345_i56
#ISCELL
  pure_quanta_power universal_power *
  page345_i57
#CELL
  pure_quanta q_res *
  page345_i58
#ISCELL
  pure_quanta_power universal_gnd *
  page345_i59
#CELL
  pure_quanta q_cap *
  page345_i6
#CELL
  pure_quanta q_res *
  page345_i60
#ISCELL
  pure_quanta_power universal_power *
  page345_i61
#CELL
  pure_quanta q_res *
  page345_i62
#ISCELL
  standard offpage *
  page345_i63
#ISCELL
  standard offpage *
  page345_i64
#ISCELL
  standard offpage *
  page345_i65
#CELL
  pure_quanta q_res *
  page345_i66
#ISCELL
  standard offpage *
  page345_i68
#ISCELL
  standard offpage *
  page345_i69
#ISCELL
  pure_quanta_power universal_power *
  page345_i7
#ISCELL
  standard offpage *
  page345_i70
#ISCELL
  standard offpage *
  page345_i71
#ISCELL
  standard offpage *
  page345_i72
#ISCELL
  pure_quanta_power universal_power *
  page345_i73
#ISCELL
  pure_quanta_power universal_power *
  page345_i75
#ISCELL
  pure_quanta_power universal_power *
  page345_i76
#CELL
  pure_quanta q_cap *
  page345_i77
#CELL
  pure_quanta q_cap *
  page345_i78
#CELL
  pure_quanta q_cap *
  page345_i79
#CELL
  pure_quanta mosfet_nch_dual *
  page345_i8
#ISCELL
  standard offpage *
  page345_i80
#ISCELL
  pure_quanta_power universal_gnd *
  page345_i81
#ISCELL
  pure_quanta_power universal_gnd *
  page345_i82
#CELL
  pure_quanta q_res *
  page345_i83
#CELL
  pure_quanta q_cap *
  page345_i84
#CELL
  pure_quanta q_cap *
  page345_i85
#CELL
  pure_quanta q_cap *
  page345_i86
#ISCELL
  standard offpage *
  page345_i87
#CELL
  pure_quanta sconn75k_apci0155p004a *
  page345_i88
#CELL
  pure_quanta mosfet_nch_dual *
  page345_i89
#ISCELL
  pure_quanta_power universal_gnd *
  page345_i9
#ISCELL
  mstr_misc dns *
  *
#ISCELL
  pure_quanta quanta_title_block_c *
  *
#ISCELL
  pure_quanta_power cad_note *
  *
#ISCELL
  pure_quanta_power design_note *
  *
#ISCELL
  standard offpage *
  page297_i1
#ISCELL
  pure_quanta_power universal_power *
  page297_i100
#CELL
  pure_quanta q_res *
  page297_i101
#CELL
  pure_quanta q_res *
  page297_i102
#ISCELL
  standard offpage *
  page297_i103
#ISCELL
  pure_quanta_power universal_power *
  page297_i104
#CELL
  pure_quanta q_res *
  page297_i105
#CELL
  pure_quanta q_res *
  page297_i106
#ISCELL
  pure_quanta_power universal_power *
  page297_i107
#ISCELL
  standard offpage *
  page297_i14
#ISCELL
  standard offpage *
  page297_i15
#ISCELL
  standard offpage *
  page297_i16
#ISCELL
  standard offpage *
  page297_i17
#ISCELL
  standard offpage *
  page297_i18
#CELL
  pure_quanta q_res *
  page297_i2
#ISCELL
  pure_quanta_power universal_gnd *
  page297_i20
#ISCELL
  standard tap *
  page297_i21
#ISCELL
  standard tap *
  page297_i22
#ISCELL
  standard tap *
  page297_i23
#ISCELL
  standard tap *
  page297_i24
#ISCELL
  standard tap *
  page297_i25
#ISCELL
  standard tap *
  page297_i26
#ISCELL
  standard tap *
  page297_i27
#ISCELL
  standard tap *
  page297_i28
#ISCELL
  standard offpage *
  page297_i29
#ISCELL
  pure_quanta_power universal_gnd *
  page297_i3
#CELL
  pure_quanta q_res *
  page297_i30
#CELL
  pure_quanta q_res *
  page297_i31
#ISCELL
  pure_quanta_power universal_power *
  page297_i33
#ISCELL
  pure_quanta_power universal_power *
  page297_i34
#ISCELL
  pure_quanta_power universal_gnd *
  page297_i35
#CELL
  pure_quanta q_cap *
  page297_i36
#CELL
  pure_quanta q_res *
  page297_i37
#CELL
  pure_quanta q_res *
  page297_i38
#CELL
  pure_quanta 74lvc2g07dw7 *
  page297_i4
#CELL
  pure_quanta q_res *
  page297_i40
#ISCELL
  standard offpage *
  page297_i41
#ISCELL
  standard offpage *
  page297_i42
#ISCELL
  pure_quanta_power universal_power *
  page297_i43
#ISCELL
  pure_quanta_power universal_gnd *
  page297_i5
#ISCELL
  pure_quanta_power universal_gnd *
  page297_i52
#ISCELL
  standard tap *
  page297_i54
#ISCELL
  standard tap *
  page297_i55
#ISCELL
  standard tap *
  page297_i56
#ISCELL
  standard tap *
  page297_i57
#ISCELL
  standard tap *
  page297_i58
#ISCELL
  standard tap *
  page297_i59
#CELL
  pure_quanta q_res *
  page297_i6
#ISCELL
  standard tap *
  page297_i60
#ISCELL
  standard tap *
  page297_i61
#ISCELL
  pure_quanta_power universal_power *
  page297_i64
#CELL
  pure_quanta q_cap *
  page297_i66
#CELL
  pure_quanta q_cap *
  page297_i67
#CELL
  pure_quanta q_cap *
  page297_i68
#ISCELL
  pure_quanta_power universal_power *
  page297_i69
#CELL
  pure_quanta q_res *
  page297_i7
#ISCELL
  standard offpage *
  page297_i70
#ISCELL
  standard offpage *
  page297_i71
#ISCELL
  standard offpage *
  page297_i72
#ISCELL
  pure_quanta_power universal_gnd *
  page297_i73
#CELL
  pure_quanta q_cap *
  page297_i74
#CELL
  pure_quanta q_res *
  page297_i75
#ISCELL
  pure_quanta_power universal_gnd *
  page297_i76
#ISCELL
  pure_quanta_power universal_power *
  page297_i78
#CELL
  pure_quanta q_res *
  page297_i79
#ISCELL
  pure_quanta_power universal_power *
  page297_i8
#ISCELL
  standard offpage *
  page297_i80
#ISCELL
  standard offpage *
  page297_i81
#ISCELL
  standard offpage *
  page297_i82
#ISCELL
  standard offpage *
  page297_i83
#ISCELL
  standard offpage *
  page297_i85
#ISCELL
  pure_quanta_power universal_gnd *
  page297_i86
#CELL
  pure_quanta q_cap *
  page297_i87
#CELL
  pure_quanta q_cap *
  page297_i88
#ISCELL
  pure_quanta_power universal_power *
  page297_i89
#ISCELL
  standard offpage *
  page297_i9
#CELL
  pure_quanta sconn56_123276793 *
  page297_i90
#ISCELL
  pure_quanta_power universal_gnd *
  page297_i91
#ISCELL
  pure_quanta_power universal_gnd *
  page297_i92
#ISCELL
  standard offpage *
  page297_i93
#CELL
  pure_quanta q_res *
  page297_i94
#CELL
  pure_quanta q_res *
  page297_i95
#ISCELL
  pure_quanta_power universal_gnd *
  page297_i96
#CELL
  pure_quanta 74lvc1g17gw *
  page297_i97
#ISCELL
  pure_quanta_power universal_gnd *
  page297_i98
#CELL
  pure_quanta q_cap *
  page297_i99
#ISCELL
  mstr_misc dns *
  *
#ISCELL
  pure_quanta quanta_title_block_c *
  *
#ISCELL
  pure_quanta_power cad_note *
  *
#ISCELL
  standard offpage *
  page324_i1
#ISCELL
  pure_quanta_power gnd *
  page324_i10
#CELL
  pure_quanta q_res *
  page324_i11
#CELL
  pure_quanta mosfet_nch_dual *
  page324_i12
#ISCELL
  pure_quanta_power gnd *
  page324_i13
#ISCELL
  pure_quanta_power gnd *
  page324_i14
#ISCELL
  pure_quanta_power gnd *
  page324_i15
#CELL
  pure_quanta q_res *
  page324_i16
#CELL
  pure_quanta q_res *
  page324_i17
#CELL
  pure_quanta q_res *
  page324_i18
#ISCELL
  pure_quanta_power gnd *
  page324_i19
#CELL
  pure_quanta q_res *
  page324_i2
#CELL
  pure_quanta q_cap *
  page324_i20
#CELL
  pure_quanta q_res *
  page324_i21
#ISCELL
  pure_quanta_power universal_power *
  page324_i22
#ISCELL
  standard offpage *
  page324_i23
#CELL
  pure_quanta q_res *
  page324_i24
#CELL
  pure_quanta q_res *
  page324_i25
#ISCELL
  pure_quanta_power universal_power *
  page324_i26
#CELL
  pure_quanta mosfet_nch_dual *
  page324_i27
#ISCELL
  pure_quanta_power gnd *
  page324_i28
#CELL
  pure_quanta q_res *
  page324_i29
#ISCELL
  pure_quanta_power gnd *
  page324_i3
#ISCELL
  pure_quanta_power gnd *
  page324_i30
#CELL
  pure_quanta q_res *
  page324_i31
#CELL
  pure_quanta q_res *
  page324_i32
#CELL
  pure_quanta diode_tvs *
  page324_i33
#ISCELL
  pure_quanta_power gnd *
  page324_i34
#ISCELL
  pure_quanta_power universal_power *
  page324_i35
#CELL
  pure_quanta q_cap *
  page324_i36
#CELL
  pure_quanta q_res *
  page324_i37
#ISCELL
  pure_quanta_power gnd *
  page324_i38
#CELL
  pure_quanta q_res *
  page324_i39
#CELL
  pure_quanta q_res *
  page324_i4
#ISCELL
  pure_quanta_power gnd *
  page324_i40
#CELL
  pure_quanta q_cap *
  page324_i41
#CELL
  pure_quanta q_cap *
  page324_i42
#CELL
  pure_quanta q_res *
  page324_i43
#ISCELL
  pure_quanta_power gnd *
  page324_i44
#CELL
  pure_quanta q_res *
  page324_i45
#CELL
  pure_quanta q_cap *
  page324_i46
#CELL
  pure_quanta q_res *
  page324_i47
#CELL
  pure_quanta q_res *
  page324_i48
#CELL
  pure_quanta q_cap *
  page324_i49
#ISCELL
  pure_quanta_power gnd *
  page324_i5
#CELL
  pure_quanta schottky_ac *
  page324_i50
#ISCELL
  pure_quanta_power gnd *
  page324_i51
#CELL
  pure_quanta q_res *
  page324_i52
#ISCELL
  pure_quanta_power vccaux15 *
  page324_i53
#CELL
  pure_quanta q_res *
  page324_i54
#ISCELL
  standard offpage *
  page324_i55
#ISCELL
  pure_quanta_power gnd *
  page324_i56
#CELL
  pure_quanta q_cap *
  page324_i57
#CELL
  pure_quanta q_cap *
  page324_i58
#ISCELL
  pure_quanta_power universal_power *
  page324_i59
#CELL
  pure_quanta mosfet_nch_dual *
  page324_i6
#ISCELL
  pure_quanta_power gnd *
  page324_i60
#CELL
  pure_quanta q_cap *
  page324_i61
#ISCELL
  pure_quanta_power gnd *
  page324_i62
#CELL
  pure_quanta q_res *
  page324_i63
#CELL
  pure_quanta q_cap *
  page324_i64
#CELL
  pure_quanta q_res *
  page324_i65
#CELL
  pure_quanta max15090bewit *
  page324_i66
#ISCELL
  pure_quanta_power gnd *
  page324_i67
#CELL
  pure_quanta q_res *
  page324_i68
#CELL
  pure_quanta q_cap *
  page324_i69
#CELL
  pure_quanta mosfet_nch_dual *
  page324_i7
#CELL
  pure_quanta q_res *
  page324_i70
#CELL
  pure_quanta q_res *
  page324_i71
#CELL
  pure_quanta q_cap *
  page324_i72
#CELL
  pure_quanta q_res *
  page324_i73
#CELL
  pure_quanta schottky_ac *
  page324_i74
#ISCELL
  pure_quanta_power gnd *
  page324_i75
#CELL
  pure_quanta q_res *
  page324_i76
#ISCELL
  pure_quanta_power vccaux15 *
  page324_i77
#CELL
  pure_quanta q_cap *
  page324_i78
#CELL
  pure_quanta q_cap *
  page324_i79
#CELL
  pure_quanta q_res *
  page324_i8
#CELL
  pure_quanta q_cap *
  page324_i80
#ISCELL
  pure_quanta_power universal_power *
  page324_i81
#ISCELL
  standard offpage *
  page324_i82
#ISCELL
  standard offpage *
  page324_i83
#ISCELL
  standard offpage *
  page324_i84
#ISCELL
  pure_quanta_power gnd *
  page324_i85
#CELL
  pure_quanta q_res *
  page324_i86
#CELL
  pure_quanta q_res *
  page324_i87
#CELL
  pure_quanta max15090bewit *
  page324_i88
#ISCELL
  pure_quanta_power universal_power *
  page324_i9
#ISCELL
  mstr_misc dns *
  *
#ISCELL
  pure_quanta quanta_title_block_c *
  *
#ISCELL
  pure_quanta_power cad_note *
  *
#ISCELL
  standard offpage *
  page323_i1
#ISCELL
  pure_quanta_power universal_power *
  page323_i10
#ISCELL
  standard offpage *
  page323_i11
#ISCELL
  pure_quanta_power gnd *
  page323_i12
#CELL
  pure_quanta q_cap *
  page323_i13
#ISCELL
  pure_quanta_power gnd *
  page323_i14
#CELL
  pure_quanta q_res *
  page323_i15
#ISCELL
  pure_quanta_power gnd *
  page323_i16
#CELL
  pure_quanta q_cap *
  page323_i17
#CELL
  pure_quanta q_res *
  page323_i18
#CELL
  pure_quanta q_res *
  page323_i19
#ISCELL
  pure_quanta_power universal_gnd *
  page323_i2
#ISCELL
  pure_quanta_power gnd *
  page323_i20
#ISCELL
  pure_quanta_power gnd *
  page323_i21
#CELL
  pure_quanta q_cap *
  page323_i22
#ISCELL
  pure_quanta_power gnd *
  page323_i23
#CELL
  pure_quanta q_cap *
  page323_i25
#ISCELL
  pure_quanta_power gnd *
  page323_i26
#ISCELL
  pure_quanta_power universal_power *
  page323_i27
#ISCELL
  pure_quanta_power universal_gnd *
  page323_i28
#ISCELL
  pure_quanta_power universal_gnd *
  page323_i29
#CELL
  pure_quanta q_cap *
  page323_i3
#CELL
  pure_quanta q_cap *
  page323_i30
#CELL
  pure_quanta mp5016gqhlz *
  page323_i31
#CELL
  pure_quanta q_cap *
  page323_i32
#ISCELL
  pure_quanta_power universal_gnd *
  page323_i33
#CELL
  pure_quanta q_cap *
  page323_i34
#ISCELL
  pure_quanta_power universal_power *
  page323_i35
#CELL
  pure_quanta q_res *
  page323_i36
#CELL
  pure_quanta q_res *
  page323_i37
#ISCELL
  pure_quanta_power gnd *
  page323_i38
#CELL
  pure_quanta q_cap *
  page323_i39
#CELL
  pure_quanta q_res *
  page323_i4
#CELL
  pure_quanta q_res *
  page323_i40
#ISCELL
  pure_quanta_power vccaux15 *
  page323_i41
#CELL
  pure_quanta q_res *
  page323_i42
#ISCELL
  standard offpage *
  page323_i43
#ISCELL
  standard offpage *
  page323_i44
#CELL
  pure_quanta q_res *
  page323_i45
#ISCELL
  pure_quanta_power vccaux15 *
  page323_i46
#CELL
  pure_quanta q_res *
  page323_i47
#CELL
  pure_quanta q_res *
  page323_i48
#CELL
  pure_quanta q_res *
  page323_i49
#CELL
  pure_quanta q_res *
  page323_i5
#ISCELL
  pure_quanta_power gnd *
  page323_i50
#CELL
  pure_quanta q_cap *
  page323_i51
#CELL
  pure_quanta q_res *
  page323_i52
#ISCELL
  pure_quanta_power universal_power *
  page323_i53
#CELL
  pure_quanta q_res *
  page323_i54
#ISCELL
  pure_quanta_power gnd *
  page323_i55
#CELL
  pure_quanta q_cap *
  page323_i56
#ISCELL
  pure_quanta_power universal_power *
  page323_i57
#ISCELL
  standard offpage *
  page323_i58
#ISCELL
  standard offpage *
  page323_i59
#CELL
  pure_quanta q_res *
  page323_i6
#ISCELL
  standard offpage *
  page323_i60
#ISCELL
  pure_quanta_power universal_gnd *
  page323_i63
#CELL
  pure_quanta q_cap *
  page323_i64
#CELL
  pure_quanta apx80929sag7 *
  page323_i65
#ISCELL
  pure_quanta_power universal_gnd *
  page323_i67
#CELL
  pure_quanta q_res *
  page323_i68
#ISCELL
  pure_quanta_power universal_gnd *
  page323_i69
#ISCELL
  pure_quanta_power universal_gnd *
  page323_i7
#CELL
  pure_quanta q_res *
  page323_i70
#CELL
  pure_quanta q_res *
  page323_i71
#ISCELL
  standard offpage *
  page323_i73
#ISCELL
  pure_quanta_power universal_power *
  page323_i74
#ISCELL
  pure_quanta_power universal_power *
  page323_i75
#CELL
  pure_quanta rs31312r *
  page323_i76
#ISCELL
  pure_quanta_power universal_gnd *
  page323_i8
#CELL
  pure_quanta q_cap *
  page323_i9
#ISCELL
  mstr_misc dns *
  *
#ISCELL
  pure_quanta quanta_title_block_c *
  *
#CELL
  pure_quanta pca9306dp1 *
  page346_i27
#CELL
  pure_quanta q_cap *
  page346_i28
#ISCELL
  pure_quanta_power universal_power *
  page346_i29
#ISCELL
  pure_quanta_power universal_gnd *
  page346_i30
#ISCELL
  pure_quanta_power universal_gnd *
  page346_i38
#CELL
  pure_quanta q_res *
  page346_i43
#CELL
  pure_quanta q_res *
  page346_i45
#ISCELL
  pure_quanta_power universal_power *
  page346_i47
#ISCELL
  pure_quanta_power universal_power *
  page346_i51
#CELL
  pure_quanta q_cap *
  page346_i52
#ISCELL
  pure_quanta_power universal_gnd *
  page346_i53
#ISCELL
  standard offpage *
  page346_i54
#ISCELL
  standard offpage *
  page346_i55
#CELL
  pure_quanta q_res *
  page346_i65
#CELL
  pure_quanta q_res *
  page346_i66
#ISCELL
  standard offpage *
  page346_i67
#ISCELL
  standard offpage *
  page346_i68
#CELL
  pure_quanta q_res *
  page346_i70
#ISCELL
  standard offpage *
  page346_i71
#CELL
  pure_quanta q_res *
  page346_i72
#ISCELL
  standard offpage *
  page346_i73
#ISCELL
  standard offpage *
  page346_i74
#CELL
  pure_quanta q_res *
  page346_i76
#CELL
  pure_quanta q_res *
  page346_i77
#CELL
  pure_quanta q_res *
  page346_i78
#CELL
  pure_quanta q_res *
  page346_i80
#CELL
  pure_quanta q_cap *
  page346_i82
#ISCELL
  pure_quanta_power universal_gnd *
  page346_i84
#ISCELL
  pure_quanta_power universal_power *
  page346_i87
#CELL
  pure_quanta q_cap *
  page346_i89
#ISCELL
  pure_quanta_power universal_gnd *
  page346_i90
#ISCELL
  standard offpage *
  page346_i91
#ISCELL
  standard offpage *
  page346_i92
#CELL
  pure_quanta pca9617adp *
  page346_i93
#ISCELL
  standard offpage *
  page346_i94
#ISCELL
  pure_quanta_power universal_gnd *
  page346_i95
#CELL
  pure_quanta q_res *
  page346_i96
#ISCELL
  pure_quanta_power universal_power *
  page346_i97
#ISCELL
  pure_quanta_power universal_power *
  page346_i98
#CELL
  pure_quanta q_res *
  page346_i99
#ISCELL
  pure_quanta quanta_title_block_c *
  *
#ISCELL
  mstr_misc dns *
  *
#ISCELL
  pure_quanta quanta_title_block_c *
  *
#ISCELL
  pure_quanta_power design_note *
  *
#ISCELL
  standard offpage *
  page348_i1
#ISCELL
  standard offpage *
  page348_i10
#CELL
  pure_quanta q_res *
  page348_i101
#CELL
  pure_quanta q_res *
  page348_i102
#CELL
  pure_quanta q_res *
  page348_i103
#CELL
  pure_quanta q_res *
  page348_i104
#CELL
  pure_quanta q_res *
  page348_i105
#ISCELL
  standard offpage *
  page348_i106
#ISCELL
  standard offpage *
  page348_i107
#ISCELL
  standard offpage *
  page348_i108
#ISCELL
  standard offpage *
  page348_i109
#ISCELL
  standard offpage *
  page348_i11
#ISCELL
  standard offpage *
  page348_i110
#ISCELL
  standard offpage *
  page348_i111
#ISCELL
  standard offpage *
  page348_i112
#ISCELL
  standard offpage *
  page348_i113
#ISCELL
  standard offpage *
  page348_i114
#ISCELL
  standard offpage *
  page348_i115
#ISCELL
  standard offpage *
  page348_i116
#CELL
  pure_quanta q_res *
  page348_i117
#CELL
  pure_quanta q_res *
  page348_i118
#CELL
  pure_quanta q_res *
  page348_i119
#ISCELL
  standard offpage *
  page348_i12
#CELL
  pure_quanta q_res *
  page348_i120
#CELL
  pure_quanta q_res *
  page348_i121
#CELL
  pure_quanta q_res *
  page348_i122
#CELL
  pure_quanta q_res *
  page348_i123
#CELL
  pure_quanta q_res *
  page348_i124
#ISCELL
  standard offpage *
  page348_i125
#ISCELL
  pure_quanta_power universal_power *
  page348_i126
#ISCELL
  pure_quanta_power universal_power *
  page348_i127
#CELL
  pure_quanta q_res *
  page348_i128
#CELL
  pure_quanta q_res *
  page348_i129
#CELL
  pure_quanta q_res *
  page348_i130
#CELL
  pure_quanta q_res *
  page348_i131
#CELL
  pure_quanta q_res *
  page348_i132
#CELL
  pure_quanta q_res *
  page348_i133
#CELL
  pure_quanta q_res *
  page348_i134
#CELL
  pure_quanta q_res *
  page348_i135
#ISCELL
  standard offpage *
  page348_i136
#ISCELL
  standard offpage *
  page348_i137
#ISCELL
  standard offpage *
  page348_i138
#ISCELL
  standard offpage *
  page348_i139
#ISCELL
  standard offpage *
  page348_i14
#ISCELL
  standard offpage *
  page348_i140
#ISCELL
  standard offpage *
  page348_i141
#ISCELL
  standard offpage *
  page348_i142
#ISCELL
  standard offpage *
  page348_i143
#ISCELL
  standard offpage *
  page348_i144
#ISCELL
  standard offpage *
  page348_i145
#ISCELL
  standard offpage *
  page348_i146
#ISCELL
  standard offpage *
  page348_i147
#ISCELL
  standard offpage *
  page348_i148
#ISCELL
  standard offpage *
  page348_i149
#ISCELL
  standard offpage *
  page348_i150
#ISCELL
  standard offpage *
  page348_i151
#ISCELL
  standard offpage *
  page348_i152
#ISCELL
  standard offpage *
  page348_i153
#ISCELL
  standard offpage *
  page348_i154
#ISCELL
  standard offpage *
  page348_i155
#ISCELL
  standard offpage *
  page348_i156
#ISCELL
  standard offpage *
  page348_i157
#ISCELL
  standard offpage *
  page348_i158
#ISCELL
  standard offpage *
  page348_i159
#ISCELL
  pure_quanta_power universal_gnd *
  page348_i16
#ISCELL
  standard offpage *
  page348_i160
#ISCELL
  standard offpage *
  page348_i161
#ISCELL
  standard offpage *
  page348_i162
#ISCELL
  standard offpage *
  page348_i163
#ISCELL
  standard offpage *
  page348_i164
#ISCELL
  standard offpage *
  page348_i166
#ISCELL
  standard offpage *
  page348_i167
#ISCELL
  standard offpage *
  page348_i168
#CELL
  pure_quanta q_res *
  page348_i169
#CELL
  pure_quanta q_res *
  page348_i17
#ISCELL
  pure_quanta_power universal_gnd *
  page348_i170
#CELL
  pure_quanta q_res *
  page348_i171
#ISCELL
  pure_quanta_power vcc_core *
  page348_i172
#ISCELL
  pure_quanta_power universal_gnd *
  page348_i173
#CELL
  pure_quanta q_res *
  page348_i174
#ISCELL
  standard offpage *
  page348_i175
#CELL
  pure_quanta sconn168_me1016810202011 *
  page348_i176
#CELL
  pure_quanta q_res *
  page348_i177
#CELL
  pure_quanta q_res *
  page348_i178
#ISCELL
  standard offpage *
  page348_i179
#CELL
  pure_quanta q_res *
  page348_i18
#ISCELL
  standard offpage *
  page348_i180
#ISCELL
  pure_quanta_power vcc_core *
  page348_i182
#ISCELL
  standard offpage *
  page348_i185
#ISCELL
  pure_quanta_power universal_power *
  page348_i19
#CELL
  pure_quanta q_res *
  page348_i190
#CELL
  pure_quanta q_res *
  page348_i191
#ISCELL
  standard offpage *
  page348_i192
#CELL
  pure_quanta q_res *
  page348_i195
#CELL
  pure_quanta q_res *
  page348_i196
#ISCELL
  standard offpage *
  page348_i197
#ISCELL
  standard offpage *
  page348_i198
#ISCELL
  standard offpage *
  page348_i199
#ISCELL
  standard offpage *
  page348_i2
#ISCELL
  standard offpage *
  page348_i20
#ISCELL
  standard offpage *
  page348_i200
#ISCELL
  standard offpage *
  page348_i201
#ISCELL
  standard offpage *
  page348_i202
#ISCELL
  standard offpage *
  page348_i203
#ISCELL
  standard offpage *
  page348_i204
#ISCELL
  standard offpage *
  page348_i205
#ISCELL
  standard offpage *
  page348_i206
#ISCELL
  standard offpage *
  page348_i207
#ISCELL
  standard offpage *
  page348_i208
#ISCELL
  standard offpage *
  page348_i209
#ISCELL
  standard offpage *
  page348_i21
#ISCELL
  standard offpage *
  page348_i210
#ISCELL
  standard offpage *
  page348_i211
#ISCELL
  standard offpage *
  page348_i212
#ISCELL
  standard offpage *
  page348_i213
#CELL
  pure_quanta q_res *
  page348_i214
#CELL
  pure_quanta q_res *
  page348_i215
#ISCELL
  standard offpage *
  page348_i216
#ISCELL
  standard offpage *
  page348_i217
#CELL
  pure_quanta q_cap *
  page348_i219
#ISCELL
  standard offpage *
  page348_i22
#CELL
  pure_quanta q_res *
  page348_i220
#ISCELL
  pure_quanta_power universal_gnd *
  page348_i221
#ISCELL
  standard offpage *
  page348_i23
#CELL
  pure_quanta q_res *
  page348_i24
#CELL
  pure_quanta q_res *
  page348_i25
#CELL
  pure_quanta q_res *
  page348_i26
#CELL
  pure_quanta q_res *
  page348_i27
#CELL
  pure_quanta q_res *
  page348_i28
#CELL
  pure_quanta q_res *
  page348_i29
#ISCELL
  standard offpage *
  page348_i3
#CELL
  pure_quanta q_res *
  page348_i30
#CELL
  pure_quanta q_res *
  page348_i31
#CELL
  pure_quanta q_res *
  page348_i32
#CELL
  pure_quanta q_res *
  page348_i33
#CELL
  pure_quanta q_res *
  page348_i34
#CELL
  pure_quanta q_res *
  page348_i35
#ISCELL
  standard offpage *
  page348_i36
#ISCELL
  standard offpage *
  page348_i37
#ISCELL
  standard offpage *
  page348_i38
#ISCELL
  standard offpage *
  page348_i39
#ISCELL
  standard offpage *
  page348_i4
#ISCELL
  pure_quanta_power universal_gnd *
  page348_i40
#ISCELL
  pure_quanta_power universal_gnd *
  page348_i41
#CELL
  pure_quanta q_res *
  page348_i42
#CELL
  pure_quanta q_res *
  page348_i43
#ISCELL
  standard offpage *
  page348_i46
#ISCELL
  standard offpage *
  page348_i47
#ISCELL
  standard offpage *
  page348_i48
#ISCELL
  standard offpage *
  page348_i49
#ISCELL
  standard offpage *
  page348_i5
#CELL
  pure_quanta q_res *
  page348_i50
#ISCELL
  standard offpage *
  page348_i51
#ISCELL
  standard offpage *
  page348_i52
#ISCELL
  standard offpage *
  page348_i53
#ISCELL
  standard offpage *
  page348_i54
#ISCELL
  standard offpage *
  page348_i55
#ISCELL
  standard offpage *
  page348_i56
#ISCELL
  standard offpage *
  page348_i57
#ISCELL
  pure_quanta_power universal_gnd *
  page348_i58
#ISCELL
  standard offpage *
  page348_i6
#CELL
  pure_quanta q_res *
  page348_i60
#ISCELL
  standard offpage *
  page348_i62
#ISCELL
  standard offpage *
  page348_i63
#ISCELL
  standard offpage *
  page348_i67
#ISCELL
  standard offpage *
  page348_i68
#ISCELL
  standard offpage *
  page348_i7
#ISCELL
  standard offpage *
  page348_i72
#ISCELL
  standard offpage *
  page348_i73
#ISCELL
  standard offpage *
  page348_i75
#ISCELL
  standard offpage *
  page348_i77
#ISCELL
  standard offpage *
  page348_i78
#ISCELL
  standard offpage *
  page348_i8
#ISCELL
  standard offpage *
  page348_i80
#ISCELL
  standard offpage *
  page348_i83
#CELL
  pure_quanta q_res *
  page348_i85
#CELL
  pure_quanta q_res *
  page348_i86
#CELL
  pure_quanta q_res *
  page348_i87
#CELL
  pure_quanta q_res *
  page348_i88
#ISCELL
  standard offpage *
  page348_i9
#ISCELL
  standard offpage *
  page348_i91
#ISCELL
  standard offpage *
  page348_i92
#ISCELL
  standard offpage *
  page348_i93
#ISCELL
  standard offpage *
  page348_i94
#ISCELL
  standard offpage *
  page348_i95
#CELL
  pure_quanta q_res *
  page348_i96
#CELL
  pure_quanta q_res *
  page348_i97
#CELL
  pure_quanta q_res *
  page348_i98
#ISCELL
  mstr_misc dns *
  *
#ISCELL
  pure_quanta quanta_title_block_c *
  *
#ISCELL
  pure_quanta_power cad_note *
  *
#CELL
  pure_quanta q_res *
  page349_i10
#ISCELL
  standard offpage *
  page349_i100
#ISCELL
  standard offpage *
  page349_i101
#ISCELL
  standard offpage *
  page349_i102
#ISCELL
  standard offpage *
  page349_i103
#ISCELL
  standard offpage *
  page349_i104
#ISCELL
  standard offpage *
  page349_i105
#ISCELL
  standard offpage *
  page349_i106
#ISCELL
  standard offpage *
  page349_i107
#ISCELL
  standard offpage *
  page349_i108
#ISCELL
  standard offpage *
  page349_i109
#ISCELL
  standard offpage *
  page349_i110
#ISCELL
  pure_quanta_power universal_gnd *
  page349_i111
#CELL
  pure_quanta q_cap *
  page349_i112
#CELL
  pure_quanta q_res *
  page349_i113
#ISCELL
  pure_quanta_power p1v0 *
  page349_i114
#CELL
  pure_quanta q_res *
  page349_i115
#CELL
  pure_quanta q_res *
  page349_i116
#ISCELL
  pure_quanta_power universal_gnd *
  page349_i117
#ISCELL
  pure_quanta_power universal_power *
  page349_i118
#CELL
  pure_quanta q_res *
  page349_i119
#CELL
  pure_quanta q_res *
  page349_i120
#CELL
  pure_quanta q_res *
  page349_i121
#CELL
  pure_quanta q_res *
  page349_i122
#CELL
  pure_quanta q_res *
  page349_i123
#CELL
  pure_quanta q_res *
  page349_i124
#CELL
  pure_quanta q_res *
  page349_i125
#CELL
  pure_quanta q_res *
  page349_i126
#CELL
  pure_quanta q_res *
  page349_i127
#CELL
  pure_quanta q_res *
  page349_i128
#CELL
  pure_quanta q_res *
  page349_i129
#ISCELL
  standard offpage *
  page349_i13
#CELL
  pure_quanta q_res *
  page349_i130
#CELL
  pure_quanta q_res *
  page349_i131
#CELL
  pure_quanta q_res *
  page349_i132
#CELL
  pure_quanta q_res *
  page349_i133
#CELL
  pure_quanta q_res *
  page349_i134
#CELL
  pure_quanta q_res *
  page349_i135
#CELL
  pure_quanta q_res *
  page349_i136
#CELL
  pure_quanta q_res *
  page349_i137
#CELL
  pure_quanta q_res *
  page349_i138
#ISCELL
  pure_quanta_power universal_power *
  page349_i139
#ISCELL
  standard offpage *
  page349_i14
#ISCELL
  standard offpage *
  page349_i140
#ISCELL
  standard offpage *
  page349_i141
#CELL
  pure_quanta q_res *
  page349_i142
#ISCELL
  pure_quanta_power gnd *
  page349_i143
#CELL
  pure_quanta q_res *
  page349_i144
#CELL
  pure_quanta q_res *
  page349_i145
#ISCELL
  pure_quanta_power vcc_core *
  page349_i146
#CELL
  pure_quanta q_res *
  page349_i147
#CELL
  pure_quanta conn4_hfk1040l0p1l7h *
  page349_i148
#CELL
  pure_quanta q_res *
  page349_i149
#ISCELL
  standard offpage *
  page349_i15
#CELL
  pure_quanta q_res *
  page349_i150
#CELL
  pure_quanta q_res *
  page349_i151
#ISCELL
  standard offpage *
  page349_i152
#ISCELL
  standard offpage *
  page349_i153
#ISCELL
  standard offpage *
  page349_i156
#ISCELL
  standard offpage *
  page349_i157
#CELL
  pure_quanta q_res *
  page349_i158
#CELL
  pure_quanta q_res *
  page349_i159
#ISCELL
  standard offpage *
  page349_i16
#ISCELL
  standard offpage *
  page349_i160
#CELL
  pure_quanta q_res *
  page349_i161
#CELL
  pure_quanta q_res *
  page349_i17
#CELL
  pure_quanta q_res *
  page349_i172
#CELL
  pure_quanta q_res *
  page349_i173
#ISCELL
  standard offpage *
  page349_i174
#ISCELL
  standard offpage *
  page349_i175
#CELL
  pure_quanta q_res *
  page349_i176
#ISCELL
  standard offpage *
  page349_i177
#ISCELL
  standard offpage *
  page349_i178
#ISCELL
  standard offpage *
  page349_i179
#CELL
  pure_quanta q_res *
  page349_i18
#ISCELL
  standard offpage *
  page349_i180
#CELL
  pure_quanta q_res *
  page349_i181
#CELL
  pure_quanta q_res *
  page349_i182
#CELL
  pure_quanta q_res *
  page349_i183
#CELL
  pure_quanta q_res *
  page349_i184
#CELL
  pure_quanta q_res *
  page349_i185
#CELL
  pure_quanta q_res *
  page349_i186
#CELL
  pure_quanta q_res *
  page349_i187
#ISCELL
  standard offpage *
  page349_i188
#ISCELL
  standard offpage *
  page349_i189
#ISCELL
  standard offpage *
  page349_i19
#ISCELL
  standard offpage *
  page349_i190
#ISCELL
  standard offpage *
  page349_i191
#ISCELL
  standard offpage *
  page349_i194
#ISCELL
  standard offpage *
  page349_i195
#CELL
  pure_quanta q_res *
  page349_i198
#CELL
  pure_quanta q_res *
  page349_i199
#CELL
  pure_quanta q_res *
  page349_i20
#ISCELL
  standard offpage *
  page349_i200
#ISCELL
  standard offpage *
  page349_i201
#ISCELL
  standard offpage *
  page349_i204
#ISCELL
  standard offpage *
  page349_i205
#CELL
  pure_quanta q_res *
  page349_i206
#CELL
  pure_quanta q_res *
  page349_i207
#ISCELL
  standard offpage *
  page349_i208
#ISCELL
  standard offpage *
  page349_i209
#CELL
  pure_quanta q_res *
  page349_i21
#ISCELL
  standard offpage *
  page349_i212
#ISCELL
  standard offpage *
  page349_i213
#ISCELL
  standard offpage *
  page349_i214
#ISCELL
  standard offpage *
  page349_i215
#CELL
  pure_quanta q_res *
  page349_i218
#CELL
  pure_quanta q_res *
  page349_i219
#CELL
  pure_quanta q_res *
  page349_i22
#CELL
  pure_quanta q_res *
  page349_i220
#CELL
  pure_quanta q_res *
  page349_i221
#CELL
  pure_quanta q_res *
  page349_i222
#CELL
  pure_quanta q_res *
  page349_i223
#CELL
  pure_quanta q_res *
  page349_i224
#CELL
  pure_quanta q_res *
  page349_i225
#CELL
  pure_quanta q_res *
  page349_i226
#CELL
  pure_quanta q_res *
  page349_i227
#CELL
  pure_quanta q_res *
  page349_i228
#CELL
  pure_quanta q_res *
  page349_i229
#CELL
  pure_quanta q_res *
  page349_i23
#CELL
  pure_quanta q_res *
  page349_i231
#CELL
  pure_quanta q_res *
  page349_i24
#CELL
  pure_quanta q_res *
  page349_i25
#ISCELL
  pure_quanta_power universal_power *
  page349_i26
#CELL
  pure_quanta q_res *
  page349_i27
#CELL
  pure_quanta q_res *
  page349_i28
#CELL
  pure_quanta q_res *
  page349_i29
#ISCELL
  standard offpage *
  page349_i3
#CELL
  pure_quanta q_res *
  page349_i30
#ISCELL
  pure_quanta_power universal_power *
  page349_i31
#CELL
  pure_quanta q_res *
  page349_i32
#ISCELL
  standard offpage *
  page349_i33
#ISCELL
  standard offpage *
  page349_i34
#ISCELL
  standard offpage *
  page349_i35
#ISCELL
  standard offpage *
  page349_i36
#ISCELL
  standard offpage *
  page349_i37
#ISCELL
  standard offpage *
  page349_i38
#ISCELL
  standard offpage *
  page349_i39
#ISCELL
  standard offpage *
  page349_i4
#ISCELL
  standard offpage *
  page349_i40
#ISCELL
  standard offpage *
  page349_i41
#ISCELL
  standard offpage *
  page349_i42
#ISCELL
  pure_quanta_power universal_power *
  page349_i43
#ISCELL
  pure_quanta_power universal_gnd *
  page349_i44
#ISCELL
  pure_quanta_power vcc_core *
  page349_i46
#ISCELL
  standard offpage *
  page349_i47
#CELL
  pure_quanta q_res *
  page349_i48
#CELL
  pure_quanta q_res *
  page349_i49
#ISCELL
  standard offpage *
  page349_i50
#ISCELL
  standard offpage *
  page349_i51
#ISCELL
  standard offpage *
  page349_i54
#ISCELL
  standard offpage *
  page349_i55
#CELL
  pure_quanta q_res *
  page349_i56
#CELL
  pure_quanta q_res *
  page349_i57
#ISCELL
  standard offpage *
  page349_i58
#ISCELL
  standard offpage *
  page349_i59
#ISCELL
  standard offpage *
  page349_i60
#ISCELL
  standard offpage *
  page349_i61
#ISCELL
  standard offpage *
  page349_i64
#ISCELL
  standard offpage *
  page349_i65
#ISCELL
  pure_quanta_power universal_gnd *
  page349_i66
#ISCELL
  standard offpage *
  page349_i67
#ISCELL
  standard offpage *
  page349_i68
#CELL
  pure_quanta q_cap *
  page349_i69
#ISCELL
  standard offpage *
  page349_i70
#ISCELL
  standard offpage *
  page349_i71
#ISCELL
  standard offpage *
  page349_i72
#ISCELL
  standard offpage *
  page349_i73
#ISCELL
  standard offpage *
  page349_i74
#ISCELL
  standard offpage *
  page349_i75
#ISCELL
  standard offpage *
  page349_i76
#ISCELL
  standard offpage *
  page349_i77
#ISCELL
  standard offpage *
  page349_i78
#ISCELL
  standard offpage *
  page349_i79
#ISCELL
  standard offpage *
  page349_i80
#CELL
  pure_quanta q_res *
  page349_i81
#CELL
  pure_quanta q_res *
  page349_i82
#CELL
  pure_quanta q_res *
  page349_i83
#CELL
  pure_quanta q_res *
  page349_i84
#ISCELL
  standard offpage *
  page349_i85
#ISCELL
  standard offpage *
  page349_i86
#ISCELL
  standard offpage *
  page349_i87
#ISCELL
  standard offpage *
  page349_i88
#CELL
  pure_quanta q_res *
  page349_i89
#CELL
  pure_quanta q_res *
  page349_i9
#CELL
  pure_quanta q_res *
  page349_i90
#CELL
  pure_quanta q_res *
  page349_i91
#CELL
  pure_quanta q_res *
  page349_i92
#ISCELL
  standard offpage *
  page349_i93
#ISCELL
  standard offpage *
  page349_i94
#ISCELL
  standard offpage *
  page349_i95
#ISCELL
  standard offpage *
  page349_i96
#ISCELL
  standard offpage *
  page349_i97
#ISCELL
  standard offpage *
  page349_i98
#ISCELL
  standard offpage *
  page349_i99
#ISCELL
  mstr_misc dns *
  *
#ISCELL
  pure_quanta quanta_title_block_c *
  *
#ISCELL
  standard offpage *
  page350_i1
#ISCELL
  pure_quanta_power universal_gnd *
  page350_i10
#CELL
  pure_quanta q_res *
  page350_i11
#CELL
  pure_quanta q_res *
  page350_i12
#ISCELL
  pure_quanta_power gnd *
  page350_i13
#CELL
  pure_quanta q_res *
  page350_i14
#ISCELL
  standard offpage *
  page350_i15
#ISCELL
  pure_quanta_power universal_power *
  page350_i16
#CELL
  pure_quanta q_res *
  page350_i17
#CELL
  pure_quanta q_res *
  page350_i18
#ISCELL
  pure_quanta_power universal_power *
  page350_i19
#CELL
  pure_quanta q_res *
  page350_i2
#CELL
  pure_quanta q_res *
  page350_i20
#ISCELL
  pure_quanta_power gnd *
  page350_i21
#CELL
  pure_quanta mosfet_nch_dual *
  page350_i22
#ISCELL
  pure_quanta_power gnd *
  page350_i23
#CELL
  pure_quanta mosfet_nch_dual *
  page350_i24
#CELL
  pure_quanta q_res *
  page350_i25
#ISCELL
  pure_quanta_power universal_power *
  page350_i26
#CELL
  pure_quanta q_res *
  page350_i27
#CELL
  pure_quanta diode_tvs *
  page350_i28
#ISCELL
  pure_quanta_power gnd *
  page350_i29
#CELL
  pure_quanta q_res *
  page350_i3
#ISCELL
  pure_quanta_power universal_power *
  page350_i30
#CELL
  pure_quanta q_cap *
  page350_i31
#ISCELL
  pure_quanta_power gnd *
  page350_i32
#CELL
  pure_quanta q_cap *
  page350_i33
#ISCELL
  pure_quanta_power gnd *
  page350_i34
#CELL
  pure_quanta q_res *
  page350_i35
#ISCELL
  pure_quanta_power gnd *
  page350_i36
#CELL
  pure_quanta q_cap *
  page350_i37
#ISCELL
  pure_quanta_power universal_power *
  page350_i39
#ISCELL
  pure_quanta_power gnd *
  page350_i4
#CELL
  pure_quanta q_res *
  page350_i40
#CELL
  pure_quanta q_res *
  page350_i41
#ISCELL
  pure_quanta_power vccaux15 *
  page350_i42
#CELL
  pure_quanta q_res *
  page350_i43
#ISCELL
  pure_quanta_power gnd *
  page350_i44
#CELL
  pure_quanta q_cap *
  page350_i45
#ISCELL
  pure_quanta_power gnd *
  page350_i46
#ISCELL
  standard offpage *
  page350_i47
#ISCELL
  pure_quanta_power vccaux15 *
  page350_i48
#CELL
  pure_quanta q_res *
  page350_i49
#ISCELL
  pure_quanta_power gnd *
  page350_i5
#CELL
  pure_quanta q_res *
  page350_i50
#CELL
  pure_quanta q_res *
  page350_i51
#CELL
  pure_quanta q_cap *
  page350_i52
#CELL
  pure_quanta q_res *
  page350_i53
#ISCELL
  pure_quanta_power universal_power *
  page350_i54
#ISCELL
  pure_quanta_power gnd *
  page350_i55
#CELL
  pure_quanta q_cap *
  page350_i56
#ISCELL
  pure_quanta_power universal_power *
  page350_i57
#ISCELL
  standard offpage *
  page350_i58
#ISCELL
  pure_quanta_power gnd *
  page350_i59
#CELL
  pure_quanta q_cap *
  page350_i6
#CELL
  pure_quanta q_res *
  page350_i60
#ISCELL
  pure_quanta_power gnd *
  page350_i61
#CELL
  pure_quanta q_res *
  page350_i62
#CELL
  pure_quanta q_res *
  page350_i63
#ISCELL
  pure_quanta_power gnd *
  page350_i64
#CELL
  pure_quanta q_res *
  page350_i65
#CELL
  pure_quanta q_cap *
  page350_i66
#CELL
  pure_quanta q_cap *
  page350_i67
#CELL
  pure_quanta q_res *
  page350_i68
#ISCELL
  pure_quanta_power gnd *
  page350_i69
#ISCELL
  pure_quanta_power gnd *
  page350_i7
#CELL
  pure_quanta q_res *
  page350_i70
#CELL
  pure_quanta q_cap *
  page350_i71
#CELL
  pure_quanta q_cap *
  page350_i72
#CELL
  pure_quanta q_res *
  page350_i73
#CELL
  pure_quanta q_res *
  page350_i74
#ISCELL
  pure_quanta_power gnd *
  page350_i75
#CELL
  pure_quanta q_res *
  page350_i76
#ISCELL
  pure_quanta_power vccaux15 *
  page350_i77
#CELL
  pure_quanta q_res *
  page350_i78
#CELL
  pure_quanta schottky_ac *
  page350_i79
#CELL
  pure_quanta q_cap *
  page350_i8
#CELL
  pure_quanta q_cap *
  page350_i80
#CELL
  pure_quanta q_cap *
  page350_i81
#ISCELL
  standard offpage *
  page350_i82
#ISCELL
  pure_quanta_power gnd *
  page350_i83
#CELL
  pure_quanta q_cap *
  page350_i84
#ISCELL
  pure_quanta_power universal_power *
  page350_i85
#CELL
  pure_quanta max15090bewit *
  page350_i86
#CELL
  pure_quanta q_res *
  page350_i89
#CELL
  pure_quanta mosfet_nch_gds_esd_protected *
  page350_i9
#ISCELL
  standard offpage *
  page350_i90
#CELL
  pure_quanta q_res *
  page350_i91
#ISCELL
  standard offpage *
  page350_i92
#CELL
  pure_quanta q_res *
  page350_i93
#ISCELL
  standard offpage *
  page350_i94
#CELL
  pure_quanta rs31312r *
  page350_i95
#ISCELL
  mstr_misc dns *
  *
#ISCELL
  pure_quanta quanta_title_block_c *
  *
#CELL
  pure_quanta nc7sb3157p6x *
  page130_i1
#ISCELL
  standard offpage *
  page130_i10
#CELL
  pure_quanta q_res *
  page130_i11
#CELL
  pure_quanta q_res *
  page130_i12
#ISCELL
  standard offpage *
  page130_i13
#ISCELL
  standard offpage *
  page130_i14
#ISCELL
  pure_quanta_power universal_power *
  page130_i16
#ISCELL
  pure_quanta_power universal_power *
  page130_i17
#ISCELL
  pure_quanta_power gnd *
  page130_i2
#ISCELL
  standard offpage *
  page130_i21
#ISCELL
  standard offpage *
  page130_i22
#CELL
  pure_quanta q_res *
  page130_i23
#CELL
  pure_quanta q_res *
  page130_i24
#ISCELL
  pure_quanta_power universal_power *
  page130_i3
#CELL
  pure_quanta q_cap *
  page130_i4
#ISCELL
  pure_quanta_power gnd *
  page130_i5
#ISCELL
  standard offpage *
  page130_i8
#ISCELL
  pure_quanta quanta_title_block_c *
  *
#ISCELL
  pure_quanta quanta_title_block_c *
  *
#ISCELL
  mstr_standard offpage *
  page132_i1
#CELL
  pure_quanta q_res *
  page132_i10
#ISCELL
  pure_quanta_power universal_gnd *
  page132_i11
#CELL
  pure_quanta mosfet_dual_6p *
  page132_i12
#ISCELL
  pure_quanta_power universal_power *
  page132_i13
#ISCELL
  pure_quanta_power universal_gnd *
  page132_i14
#ISCELL
  standard offpage *
  page132_i15
#CELL
  pure_quanta q_res *
  page132_i16
#ISCELL
  standard offpage *
  page132_i17
#CELL
  pure_quanta q_res *
  page132_i18
#ISCELL
  pure_quanta_power universal_power *
  page132_i19
#ISCELL
  mstr_standard offpage *
  page132_i2
#ISCELL
  mstr_standard offpage *
  page132_i3
#CELL
  pure_quanta q_res *
  page132_i4
#CELL
  pure_quanta q_res *
  page132_i5
#CELL
  pure_quanta q_res *
  page132_i6
#CELL
  pure_quanta q_res *
  page132_i7
#ISCELL
  pure_quanta_power universal_power *
  page132_i8
#ISCELL
  standard offpage *
  page132_i9
#ISCELL
  pure_quanta quanta_title_block_c *
  *
#ISCELL
  pure_quanta quanta_title_block_c *
  *
#ISCELL
  pure_quanta quanta_title_block_c *
  *
#ISCELL
  mstr_misc dns *
  *
#ISCELL
  pure_quanta quanta_title_block_c *
  *
#ISCELL
  pure_quanta_power cad_note *
  *
#CELL
  pure_quanta q_res *
  page136_i100
#ISCELL
  standard offpage *
  page136_i101
#ISCELL
  standard offpage *
  page136_i102
#CELL
  pure_quanta q_res *
  page136_i103
#CELL
  pure_quanta q_res *
  page136_i104
#ISCELL
  standard offpage *
  page136_i105
#ISCELL
  standard offpage *
  page136_i106
#CELL
  pure_quanta q_res *
  page136_i107
#CELL
  pure_quanta q_res *
  page136_i108
#ISCELL
  standard offpage *
  page136_i109
#ISCELL
  standard offpage *
  page136_i110
#CELL
  pure_quanta q_res *
  page136_i111
#CELL
  pure_quanta q_res *
  page136_i112
#ISCELL
  standard offpage *
  page136_i113
#ISCELL
  standard offpage *
  page136_i114
#CELL
  pure_quanta q_res *
  page136_i123
#CELL
  pure_quanta q_res *
  page136_i124
#CELL
  pure_quanta q_res *
  page136_i131
#CELL
  pure_quanta q_res *
  page136_i132
#CELL
  pure_quanta q_res *
  page136_i133
#CELL
  pure_quanta q_res *
  page136_i134
#CELL
  pure_quanta q_res *
  page136_i135
#CELL
  pure_quanta q_res *
  page136_i136
#CELL
  pure_quanta q_res *
  page136_i137
#CELL
  pure_quanta q_res *
  page136_i138
#CELL
  pure_quanta q_res *
  page136_i139
#ISCELL
  standard offpage *
  page136_i14
#CELL
  pure_quanta q_res *
  page136_i140
#CELL
  pure_quanta q_res *
  page136_i141
#CELL
  pure_quanta q_res *
  page136_i142
#CELL
  pure_quanta q_res *
  page136_i143
#CELL
  pure_quanta q_res *
  page136_i144
#CELL
  pure_quanta q_res *
  page136_i145
#ISCELL
  pure_quanta_power vcc_core *
  page136_i146
#CELL
  pure_quanta q_res *
  page136_i147
#CELL
  pure_quanta q_res *
  page136_i148
#ISCELL
  pure_quanta_power vcc_core *
  page136_i149
#ISCELL
  standard offpage *
  page136_i15
#CELL
  pure_quanta q_res *
  page136_i150
#CELL
  pure_quanta q_res *
  page136_i151
#CELL
  pure_quanta q_res *
  page136_i152
#ISCELL
  pure_quanta_power vcc_core *
  page136_i153
#CELL
  pure_quanta q_res *
  page136_i154
#ISCELL
  pure_quanta_power vcc_core *
  page136_i155
#CELL
  pure_quanta q_res *
  page136_i156
#CELL
  pure_quanta q_res *
  page136_i157
#ISCELL
  pure_quanta_power vcc_core *
  page136_i158
#CELL
  pure_quanta q_res *
  page136_i159
#ISCELL
  pure_quanta_power vcc_core *
  page136_i160
#CELL
  pure_quanta q_res *
  page136_i161
#CELL
  pure_quanta q_res *
  page136_i162
#CELL
  pure_quanta q_res *
  page136_i163
#CELL
  pure_quanta q_res *
  page136_i164
#ISCELL
  pure_quanta_power vcc_core *
  page136_i165
#CELL
  pure_quanta q_res *
  page136_i166
#CELL
  pure_quanta q_res *
  page136_i167
#ISCELL
  pure_quanta_power vcc_core *
  page136_i168
#ISCELL
  standard offpage *
  page136_i19
#ISCELL
  standard offpage *
  page136_i20
#ISCELL
  standard offpage *
  page136_i26
#ISCELL
  standard offpage *
  page136_i28
#ISCELL
  standard offpage *
  page136_i29
#ISCELL
  standard offpage *
  page136_i30
#CELL
  pure_quanta q_res *
  page136_i31
#CELL
  pure_quanta q_res *
  page136_i32
#CELL
  pure_quanta q_res *
  page136_i33
#CELL
  pure_quanta q_res *
  page136_i34
#CELL
  pure_quanta q_res *
  page136_i35
#CELL
  pure_quanta q_res *
  page136_i36
#CELL
  pure_quanta q_res *
  page136_i37
#CELL
  pure_quanta q_res *
  page136_i38
#ISCELL
  standard offpage *
  page136_i39
#ISCELL
  standard offpage *
  page136_i40
#ISCELL
  standard offpage *
  page136_i41
#ISCELL
  standard offpage *
  page136_i42
#ISCELL
  standard offpage *
  page136_i43
#ISCELL
  standard offpage *
  page136_i44
#ISCELL
  standard offpage *
  page136_i45
#ISCELL
  standard offpage *
  page136_i46
#CELL
  pure_quanta pi3csw12zuaex *
  page136_i47
#ISCELL
  pure_quanta_power universal_gnd *
  page136_i48
#ISCELL
  pure_quanta_power universal_gnd *
  page136_i49
#CELL
  pure_quanta q_cap *
  page136_i50
#ISCELL
  pure_quanta_power universal_power *
  page136_i51
#ISCELL
  standard offpage *
  page136_i52
#ISCELL
  standard offpage *
  page136_i53
#CELL
  pure_quanta pi3csw12zuaex *
  page136_i54
#ISCELL
  pure_quanta_power universal_power *
  page136_i55
#CELL
  pure_quanta q_cap *
  page136_i56
#ISCELL
  pure_quanta_power universal_gnd *
  page136_i57
#ISCELL
  pure_quanta_power universal_gnd *
  page136_i58
#ISCELL
  pure_quanta_power universal_gnd *
  page136_i59
#ISCELL
  pure_quanta_power universal_gnd *
  page136_i60
#CELL
  pure_quanta q_cap *
  page136_i61
#ISCELL
  pure_quanta_power universal_power *
  page136_i62
#CELL
  pure_quanta pi3csw12zuaex *
  page136_i63
#ISCELL
  pure_quanta_power universal_gnd *
  page136_i64
#ISCELL
  pure_quanta_power universal_gnd *
  page136_i65
#CELL
  pure_quanta q_cap *
  page136_i66
#ISCELL
  pure_quanta_power universal_power *
  page136_i67
#CELL
  pure_quanta pi3csw12zuaex *
  page136_i68
#ISCELL
  standard offpage *
  page136_i69
#ISCELL
  standard offpage *
  page136_i70
#ISCELL
  standard offpage *
  page136_i71
#ISCELL
  standard offpage *
  page136_i72
#ISCELL
  standard offpage *
  page136_i73
#ISCELL
  standard offpage *
  page136_i74
#CELL
  pure_quanta q_res *
  page136_i99
#ISCELL
  mstr_misc dns *
  *
#ISCELL
  pure_quanta quanta_title_block_c *
  *
#ISCELL
  pure_quanta_power cad_note *
  *
#ISCELL
  standard offpage *
  page137_i1
#CELL
  pure_quanta q_res *
  page137_i13
#CELL
  pure_quanta q_res *
  page137_i15
#CELL
  pure_quanta q_res *
  page137_i16
#ISCELL
  standard offpage *
  page137_i17
#ISCELL
  standard offpage *
  page137_i18
#ISCELL
  standard offpage *
  page137_i19
#ISCELL
  standard offpage *
  page137_i2
#ISCELL
  standard offpage *
  page137_i20
#ISCELL
  standard offpage *
  page137_i21
#ISCELL
  pure_quanta_power universal_gnd *
  page137_i24
#ISCELL
  pure_quanta_power universal_gnd *
  page137_i25
#CELL
  pure_quanta q_cap *
  page137_i26
#ISCELL
  pure_quanta_power universal_power *
  page137_i27
#ISCELL
  pure_quanta_power universal_gnd *
  page137_i28
#CELL
  pure_quanta q_cap *
  page137_i29
#ISCELL
  pure_quanta_power universal_gnd *
  page137_i3
#ISCELL
  pure_quanta_power vcc_core *
  page137_i30
#CELL
  pure_quanta q_res *
  page137_i31
#ISCELL
  pure_quanta_power vcc_core *
  page137_i32
#ISCELL
  standard offpage *
  page137_i37
#CELL
  pure_quanta q_res *
  page137_i40
#CELL
  pure_quanta q_res *
  page137_i41
#ISCELL
  pure_quanta_power vcc_core *
  page137_i42
#ISCELL
  pure_quanta_power vcc_core *
  page137_i43
#CELL
  pure_quanta q_res *
  page137_i44
#ISCELL
  pure_quanta_power vcc_core *
  page137_i45
#CELL
  pure_quanta q_res *
  page137_i46
#CELL
  pure_quanta pca9617adp *
  page137_i48
#ISCELL
  pure_quanta_power vcc_core *
  page137_i49
#ISCELL
  pure_quanta_power universal_gnd *
  page137_i5
#ISCELL
  pure_quanta_power vcc_core *
  page137_i50
#CELL
  pure_quanta pca9617adp *
  page137_i51
#ISCELL
  pure_quanta_power universal_power *
  page137_i52
#ISCELL
  pure_quanta_power vcc_core *
  page137_i54
#ISCELL
  pure_quanta_power universal_gnd *
  page137_i55
#CELL
  pure_quanta q_cap *
  page137_i56
#ISCELL
  pure_quanta_power universal_power *
  page137_i57
#ISCELL
  pure_quanta_power universal_gnd *
  page137_i58
#CELL
  pure_quanta q_cap *
  page137_i59
#CELL
  pure_quanta q_cap *
  page137_i6
#ISCELL
  pure_quanta_power universal_gnd *
  page137_i60
#ISCELL
  pure_quanta_power universal_power *
  page137_i61
#CELL
  pure_quanta q_res *
  page137_i62
#ISCELL
  standard offpage *
  page137_i63
#ISCELL
  standard offpage *
  page137_i64
#CELL
  pure_quanta q_res *
  page137_i67
#CELL
  pure_quanta q_res *
  page137_i68
#ISCELL
  standard offpage *
  page137_i69
#ISCELL
  pure_quanta_power universal_power *
  page137_i7
#ISCELL
  standard offpage *
  page137_i70
#CELL
  pure_quanta q_res *
  page137_i71
#CELL
  pure_quanta q_res *
  page137_i72
#CELL
  pure_quanta q_res *
  page137_i73
#ISCELL
  pure_quanta_power vcc_core *
  page137_i74
#ISCELL
  standard offpage *
  page137_i75
#ISCELL
  standard offpage *
  page137_i76
#ISCELL
  pure_quanta_power vcc_core *
  page137_i77
#CELL
  pure_quanta q_res *
  page137_i78
#CELL
  pure_quanta q_res *
  page137_i79
#CELL
  pure_quanta q_cap *
  page137_i8
#CELL
  pure_quanta q_res *
  page137_i80
#ISCELL
  standard offpage *
  page137_i81
#ISCELL
  standard offpage *
  page137_i82
#ISCELL
  standard offpage *
  page137_i83
#ISCELL
  standard offpage *
  page137_i84
#ISCELL
  standard offpage *
  page137_i87
#ISCELL
  standard offpage *
  page137_i88
#ISCELL
  standard offpage *
  page137_i89
#ISCELL
  pure_quanta_power universal_gnd *
  page137_i9
#ISCELL
  standard offpage *
  page137_i90
#CELL
  pure_quanta q_res *
  page137_i91
#CELL
  pure_quanta q_res *
  page137_i92
#CELL
  pure_quanta q_res *
  page137_i93
#CELL
  pure_quanta q_res *
  page137_i94
#CELL
  pure_quanta q_res *
  page137_i95
#CELL
  pure_quanta q_res *
  page137_i96
#CELL
  pure_quanta q_res *
  page137_i97
#CELL
  pure_quanta q_res *
  page137_i98
#CELL
  pure_quanta pca9617adp *
  page137_i99
#ISCELL
  mstr_misc dns *
  *
#ISCELL
  pure_quanta quanta_title_block_c *
  *
#ISCELL
  pure_quanta_power cad_note *
  *
#CELL
  pure_quanta q_res *
  page138_i100
#ISCELL
  standard offpage *
  page138_i101
#ISCELL
  standard offpage *
  page138_i102
#ISCELL
  standard offpage *
  page138_i103
#ISCELL
  standard offpage *
  page138_i104
#CELL
  pure_quanta q_res *
  page138_i109
#CELL
  pure_quanta q_res *
  page138_i110
#CELL
  pure_quanta iml3112y2b000ncg8 *
  page138_i111
#CELL
  pure_quanta q_cap *
  page138_i112
#CELL
  pure_quanta q_cap *
  page138_i113
#CELL
  pure_quanta pi3csw12zuaex *
  page138_i114
#ISCELL
  pure_quanta_power p1v0 *
  page138_i13
#CELL
  pure_quanta q_res *
  page138_i14
#CELL
  pure_quanta q_res *
  page138_i15
#CELL
  pure_quanta q_res *
  page138_i16
#CELL
  pure_quanta q_res *
  page138_i17
#ISCELL
  pure_quanta_power universal_gnd *
  page138_i18
#ISCELL
  standard offpage *
  page138_i2
#ISCELL
  pure_quanta_power universal_gnd *
  page138_i21
#CELL
  pure_quanta q_res *
  page138_i22
#CELL
  pure_quanta q_res *
  page138_i23
#ISCELL
  pure_quanta_power universal_gnd *
  page138_i26
#CELL
  pure_quanta q_res *
  page138_i27
#ISCELL
  pure_quanta_power universal_gnd *
  page138_i28
#CELL
  pure_quanta q_res *
  page138_i30
#ISCELL
  pure_quanta_power universal_gnd *
  page138_i31
#ISCELL
  pure_quanta_power p1v0 *
  page138_i33
#CELL
  pure_quanta q_res *
  page138_i34
#CELL
  pure_quanta q_res *
  page138_i35
#CELL
  pure_quanta q_res *
  page138_i38
#CELL
  pure_quanta q_res *
  page138_i39
#ISCELL
  standard offpage *
  page138_i40
#ISCELL
  standard offpage *
  page138_i42
#ISCELL
  standard offpage *
  page138_i44
#ISCELL
  standard offpage *
  page138_i45
#ISCELL
  standard offpage *
  page138_i46
#ISCELL
  standard offpage *
  page138_i47
#ISCELL
  standard offpage *
  page138_i48
#ISCELL
  standard offpage *
  page138_i49
#CELL
  pure_quanta q_res *
  page138_i5
#ISCELL
  standard offpage *
  page138_i50
#ISCELL
  standard offpage *
  page138_i51
#CELL
  pure_quanta q_res *
  page138_i52
#CELL
  pure_quanta q_res *
  page138_i53
#CELL
  pure_quanta q_res *
  page138_i54
#CELL
  pure_quanta q_res *
  page138_i55
#CELL
  pure_quanta q_res *
  page138_i56
#CELL
  pure_quanta q_res *
  page138_i57
#CELL
  pure_quanta q_res *
  page138_i58
#ISCELL
  pure_quanta_power vcc_core *
  page138_i59
#CELL
  pure_quanta q_res *
  page138_i6
#CELL
  pure_quanta q_res *
  page138_i60
#ISCELL
  standard offpage *
  page138_i61
#ISCELL
  standard offpage *
  page138_i62
#ISCELL
  standard offpage *
  page138_i63
#ISCELL
  standard offpage *
  page138_i64
#ISCELL
  pure_quanta_power vcc_core *
  page138_i65
#CELL
  pure_quanta pi3csw12zuaex *
  page138_i67
#CELL
  pure_quanta q_cap *
  page138_i69
#ISCELL
  pure_quanta_power universal_gnd *
  page138_i70
#ISCELL
  standard offpage *
  page138_i71
#ISCELL
  standard offpage *
  page138_i72
#CELL
  pure_quanta q_res *
  page138_i73
#CELL
  pure_quanta q_res *
  page138_i74
#CELL
  pure_quanta q_res *
  page138_i75
#CELL
  pure_quanta q_res *
  page138_i76
#ISCELL
  standard offpage *
  page138_i77
#ISCELL
  standard offpage *
  page138_i78
#ISCELL
  standard offpage *
  page138_i79
#ISCELL
  pure_quanta_power p1v0 *
  page138_i81
#ISCELL
  pure_quanta_power p1v0 *
  page138_i82
#ISCELL
  standard offpage *
  page138_i84
#ISCELL
  standard offpage *
  page138_i85
#ISCELL
  pure_quanta_power universal_gnd *
  page138_i86
#ISCELL
  pure_quanta_power p1v0 *
  page138_i87
#ISCELL
  pure_quanta_power universal_gnd *
  page138_i88
#CELL
  pure_quanta q_cap *
  page138_i89
#CELL
  pure_quanta q_res *
  page138_i91
#CELL
  pure_quanta q_res *
  page138_i92
#CELL
  pure_quanta q_res *
  page138_i93
#CELL
  pure_quanta q_res *
  page138_i94
#ISCELL
  standard offpage *
  page138_i95
#ISCELL
  standard offpage *
  page138_i96
#ISCELL
  standard offpage *
  page138_i97
#ISCELL
  standard offpage *
  page138_i98
#CELL
  pure_quanta q_res *
  page138_i99
#ISCELL
  pure_quanta quanta_title_block_c *
  *
#ISCELL
  pure_quanta quanta_title_block_c *
  *
#ISCELL
  mstr_misc dns *
  *
#ISCELL
  pure_quanta quanta_title_block_c *
  *
#CELL
  pure_quanta sn74avc4t774pwr *
  page141_i117
#ISCELL
  pure_quanta_power universal_power *
  page141_i120
#ISCELL
  standard offpage *
  page141_i126
#ISCELL
  pure_quanta_power universal_power *
  page141_i128
#CELL
  pure_quanta q_cap *
  page141_i133
#ISCELL
  pure_quanta_power universal_gnd *
  page141_i134
#ISCELL
  pure_quanta_power universal_power *
  page141_i135
#ISCELL
  pure_quanta_power universal_gnd *
  page141_i136
#CELL
  pure_quanta q_cap *
  page141_i137
#ISCELL
  standard offpage *
  page141_i138
#ISCELL
  pure_quanta_power universal_power *
  page141_i145
#ISCELL
  pure_quanta_power universal_power *
  page141_i148
#ISCELL
  pure_quanta_power universal_gnd *
  page141_i180
#ISCELL
  pure_quanta_power universal_power *
  page141_i181
#ISCELL
  pure_quanta_power p1v0 *
  page141_i182
#ISCELL
  standard offpage *
  page141_i184
#CELL
  pure_quanta q_res *
  page141_i185
#CELL
  pure_quanta q_res *
  page141_i186
#CELL
  pure_quanta q_cap *
  page141_i187
#ISCELL
  pure_quanta_power universal_gnd *
  page141_i188
#ISCELL
  pure_quanta_power universal_gnd *
  page141_i189
#CELL
  pure_quanta q_cap *
  page141_i190
#CELL
  pure_quanta conn4_hfk1040l0p1l7h *
  page141_i195
#CELL
  pure_quanta q_res *
  page141_i196
#CELL
  pure_quanta q_res *
  page141_i197
#CELL
  pure_quanta q_res *
  page141_i198
#CELL
  pure_quanta q_res *
  page141_i199
#ISCELL
  standard offpage *
  page141_i200
#ISCELL
  standard offpage *
  page141_i201
#ISCELL
  standard offpage *
  page141_i202
#CELL
  pure_quanta q_res *
  page141_i203
#CELL
  pure_quanta q_res *
  page141_i204
#CELL
  pure_quanta q_res *
  page141_i205
#CELL
  pure_quanta q_res *
  page141_i206
#ISCELL
  standard offpage *
  page141_i207
#ISCELL
  standard offpage *
  page141_i208
#ISCELL
  standard offpage *
  page141_i209
#ISCELL
  standard offpage *
  page141_i210
#CELL
  pure_quanta q_res *
  page141_i211
#CELL
  pure_quanta q_res *
  page141_i212
#ISCELL
  standard offpage *
  page141_i213
#CELL
  pure_quanta q_res *
  page141_i220
#CELL
  pure_quanta q_res *
  page141_i221
#ISCELL
  standard offpage *
  page141_i222
#ISCELL
  standard offpage *
  page141_i223
#ISCELL
  standard offpage *
  page141_i224
#ISCELL
  standard offpage *
  page141_i225
#ISCELL
  pure_quanta_power universal_gnd *
  page141_i226
#ISCELL
  standard offpage *
  page141_i227
#ISCELL
  standard offpage *
  page141_i228
#ISCELL
  standard offpage *
  page141_i229
#ISCELL
  standard offpage *
  page141_i230
#CELL
  pure_quanta q_res *
  page141_i231
#CELL
  pure_quanta q_res *
  page141_i232
#ISCELL
  standard offpage *
  page141_i233
#ISCELL
  pure_quanta_power universal_gnd *
  page141_i234
#ISCELL
  pure_quanta_power universal_gnd *
  page141_i235
#ISCELL
  pure_quanta_power universal_power *
  page141_i236
#ISCELL
  standard offpage *
  page141_i88
#CELL
  pure_quanta mosfet_n_gsd *
  page141_i89
#ISCELL
  pure_quanta_power universal_gnd *
  page141_i90
#CELL
  pure_quanta q_res *
  page141_i91
#ISCELL
  pure_quanta quanta_title_block_c *
  *
#CELL
  pure_quanta q_led *
  page142_i79
#CELL
  pure_quanta mosfet_n_gsd *
  page142_i80
#CELL
  pure_quanta mosfet_n_gsd *
  page142_i81
#CELL
  pure_quanta q_res *
  page142_i82
#ISCELL
  pure_quanta_power universal_power *
  page142_i83
#ISCELL
  pure_quanta_power universal_gnd *
  page142_i85
#ISCELL
  pure_quanta_power universal_power *
  page142_i86
#CELL
  pure_quanta q_res *
  page142_i87
#ISCELL
  standard offpage *
  page142_i88
#ISCELL
  mstr_misc dns *
  *
#ISCELL
  pure_quanta quanta_title_block_c *
  *
#ISCELL
  pure_quanta_power universal_power *
  page143_i1
#ISCELL
  pure_quanta_power universal_power *
  page143_i10
#CELL
  pure_quanta q_res *
  page143_i11
#ISCELL
  pure_quanta_power gnd *
  page143_i12
#ISCELL
  pure_quanta_power gnd *
  page143_i13
#ISCELL
  pure_quanta_power universal_power *
  page143_i14
#CELL
  pure_quanta q_res *
  page143_i15
#CELL
  pure_quanta mosfet_dual_6p *
  page143_i16
#ISCELL
  pure_quanta_power universal_power *
  page143_i17
#CELL
  pure_quanta q_res *
  page143_i18
#CELL
  pure_quanta mosfet_dual_6p *
  page143_i19
#ISCELL
  pure_quanta_power universal_power *
  page143_i2
#ISCELL
  pure_quanta_power gnd *
  page143_i20
#CELL
  pure_quanta q_res *
  page143_i21
#CELL
  pure_quanta q_res *
  page143_i22
#CELL
  pure_quanta q_cap *
  page143_i24
#ISCELL
  pure_quanta_power universal_gnd *
  page143_i25
#CELL
  pure_quanta sn74lvc1g07dbvr *
  page143_i26
#ISCELL
  pure_quanta_power universal_gnd *
  page143_i27
#ISCELL
  pure_quanta_power p1v0 *
  page143_i28
#CELL
  pure_quanta q_cap *
  page143_i29
#CELL
  pure_quanta q_res *
  page143_i3
#ISCELL
  pure_quanta_power universal_gnd *
  page143_i30
#CELL
  pure_quanta sn74lvc1g07dbvr *
  page143_i31
#ISCELL
  pure_quanta_power universal_gnd *
  page143_i32
#CELL
  pure_quanta q_res *
  page143_i33
#CELL
  pure_quanta q_res *
  page143_i34
#ISCELL
  standard offpage *
  page143_i35
#ISCELL
  standard offpage *
  page143_i36
#ISCELL
  standard offpage *
  page143_i37
#CELL
  pure_quanta q_led *
  page143_i38
#ISCELL
  pure_quanta_power universal_gnd *
  page143_i39
#ISCELL
  pure_quanta_power universal_power *
  page143_i4
#ISCELL
  pure_quanta_power p1v0 *
  page143_i40
#CELL
  pure_quanta q_res *
  page143_i41
#CELL
  pure_quanta q_res *
  page143_i42
#CELL
  pure_quanta q_led *
  page143_i43
#CELL
  pure_quanta mosfet_n_gsd *
  page143_i44
#ISCELL
  pure_quanta_power p1v0 *
  page143_i45
#ISCELL
  pure_quanta_power universal_gnd *
  page143_i46
#ISCELL
  standard offpage *
  page143_i47
#ISCELL
  pure_quanta_power p1v0 *
  page143_i48
#CELL
  pure_quanta q_res *
  page143_i5
#ISCELL
  pure_quanta_power gnd *
  page143_i6
#CELL
  pure_quanta q_res *
  page143_i7
#CELL
  pure_quanta q_led *
  page143_i8
#CELL
  pure_quanta q_led *
  page143_i9
#ISCELL
  mstr_misc dns *
  *
#ISCELL
  pure_quanta quanta_title_block_c *
  *
#ISCELL
  standard offpage *
  page144_i1
#ISCELL
  pure_quanta_power universal_gnd *
  page144_i10
#ISCELL
  standard offpage *
  page144_i11
#ISCELL
  standard offpage *
  page144_i12
#ISCELL
  standard offpage *
  page144_i13
#ISCELL
  standard offpage *
  page144_i14
#CELL
  pure_quanta q_res *
  page144_i15
#ISCELL
  pure_quanta_power universal_power *
  page144_i16
#CELL
  pure_quanta q_res *
  page144_i17
#CELL
  pure_quanta q_res *
  page144_i19
#ISCELL
  standard offpage *
  page144_i2
#ISCELL
  standard offpage *
  page144_i20
#ISCELL
  standard offpage *
  page144_i21
#ISCELL
  standard offpage *
  page144_i22
#ISCELL
  standard offpage *
  page144_i23
#ISCELL
  standard offpage *
  page144_i24
#ISCELL
  standard offpage *
  page144_i25
#ISCELL
  standard offpage *
  page144_i26
#ISCELL
  standard offpage *
  page144_i27
#ISCELL
  standard offpage *
  page144_i28
#ISCELL
  standard offpage *
  page144_i29
#ISCELL
  standard offpage *
  page144_i3
#CELL
  pure_quanta q_res *
  page144_i30
#ISCELL
  pure_quanta_power universal_power *
  page144_i31
#ISCELL
  pure_quanta_power universal_gnd *
  page144_i32
#CELL
  pure_quanta q_res *
  page144_i33
#CELL
  pure_quanta q_res *
  page144_i34
#ISCELL
  standard offpage *
  page144_i35
#ISCELL
  pure_quanta_power universal_gnd *
  page144_i36
#ISCELL
  pure_quanta_power universal_gnd *
  page144_i37
#CELL
  pure_quanta sn74lvc1g07dbvr *
  page144_i38
#CELL
  pure_quanta q_cap *
  page144_i39
#ISCELL
  pure_quanta_power universal_gnd *
  page144_i4
#ISCELL
  pure_quanta_power universal_power *
  page144_i40
#ISCELL
  standard offpage *
  page144_i41
#ISCELL
  standard offpage *
  page144_i42
#ISCELL
  standard offpage *
  page144_i43
#CELL
  pure_quanta q_res *
  page144_i44
#ISCELL
  pure_quanta_power universal_power *
  page144_i45
#ISCELL
  pure_quanta_power universal_gnd *
  page144_i46
#CELL
  pure_quanta q_res *
  page144_i47
#ISCELL
  pure_quanta_power universal_power *
  page144_i48
#ISCELL
  standard offpage *
  page144_i49
#ISCELL
  pure_quanta_power universal_gnd *
  page144_i5
#CELL
  pure_quanta q_res *
  page144_i50
#ISCELL
  pure_quanta_power universal_power *
  page144_i51
#CELL
  pure_quanta q_res *
  page144_i52
#ISCELL
  pure_quanta_power universal_gnd *
  page144_i53
#CELL
  pure_quanta q_res *
  page144_i54
#ISCELL
  pure_quanta_power universal_power *
  page144_i55
#ISCELL
  standard offpage *
  page144_i56
#ISCELL
  standard offpage *
  page144_i57
#ISCELL
  standard offpage *
  page144_i58
#ISCELL
  standard offpage *
  page144_i59
#CELL
  pure_quanta q_res *
  page144_i6
#ISCELL
  pure_quanta_power universal_gnd *
  page144_i60
#CELL
  pure_quanta q_res *
  page144_i61
#CELL
  pure_quanta q_res *
  page144_i62
#ISCELL
  pure_quanta_power universal_power *
  page144_i63
#ISCELL
  standard offpage *
  page144_i64
#ISCELL
  standard offpage *
  page144_i65
#ISCELL
  pure_quanta_power universal_gnd *
  page144_i66
#ISCELL
  standard offpage *
  page144_i67
#ISCELL
  standard offpage *
  page144_i68
#CELL
  pure_quanta q_res *
  page144_i69
#ISCELL
  standard offpage *
  page144_i7
#CELL
  pure_quanta q_res *
  page144_i70
#ISCELL
  pure_quanta_power universal_power *
  page144_i71
#CELL
  pure_quanta q_res *
  page144_i72
#ISCELL
  pure_quanta_power universal_power *
  page144_i73
#CELL
  pure_quanta q_res *
  page144_i74
#ISCELL
  standard offpage *
  page144_i75
#ISCELL
  pure_quanta_power universal_power *
  page144_i76
#CELL
  pure_quanta q_res *
  page144_i77
#ISCELL
  pure_quanta_power universal_power *
  page144_i78
#ISCELL
  pure_quanta_power universal_gnd *
  page144_i79
#ISCELL
  standard offpage *
  page144_i8
#ISCELL
  pure_quanta_power universal_power *
  page144_i80
#CELL
  pure_quanta q_res *
  page144_i81
#ISCELL
  pure_quanta_power universal_power *
  page144_i82
#CELL
  pure_quanta q_res *
  page144_i83
#CELL
  pure_quanta q_res *
  page144_i84
#CELL
  pure_quanta q_res *
  page144_i85
#ISCELL
  pure_quanta_power universal_power *
  page144_i86
#ISCELL
  pure_quanta_power universal_power *
  page144_i87
#CELL
  pure_quanta q_res *
  page144_i89
#ISCELL
  standard offpage *
  page144_i9
#CELL
  pure_quanta sw20s_dhnf10fqtr *
  page144_i90
#ISCELL
  pure_quanta quanta_title_block_c *
  *
#ISCELL
  mstr_misc dns *
  *
#ISCELL
  pure_quanta quanta_title_block_c *
  *
#ISCELL
  pure_quanta_power p1v0_aux *
  page146_i1
#CELL
  pure_quanta mosfet_pch_gds_esd_protected *
  page146_i10
#CELL
  pure_quanta q_res *
  page146_i11
#CELL
  pure_quanta q_res *
  page146_i12
#ISCELL
  pure_quanta_power universal_gnd *
  page146_i13
#CELL
  pure_quanta q_res *
  page146_i14
#ISCELL
  pure_quanta_power universal_gnd *
  page146_i15
#CELL
  pure_quanta mosfet_nch_1d3s *
  page146_i16
#ISCELL
  pure_quanta_power universal_gnd *
  page146_i17
#ISCELL
  pure_quanta_power p1v0_aux *
  page146_i18
#CELL
  pure_quanta q_res *
  page146_i19
#CELL
  pure_quanta q_res *
  page146_i2
#CELL
  pure_quanta q_res *
  page146_i21
#CELL
  pure_quanta mosfet_nch_1d3s *
  page146_i22
#CELL
  pure_quanta mosfet_pch_gds_esd_protected *
  page146_i23
#ISCELL
  pure_quanta_power p1v0_aux *
  page146_i24
#CELL
  pure_quanta schottky_dual_12a_3c *
  page146_i25
#ISCELL
  pure_quanta_power universal_gnd *
  page146_i27
#CELL
  pure_quanta q_res *
  page146_i28
#ISCELL
  pure_quanta_power universal_gnd *
  page146_i29
#CELL
  pure_quanta q_res *
  page146_i3
#CELL
  pure_quanta q_cap *
  page146_i30
#ISCELL
  pure_quanta_power universal_gnd *
  page146_i31
#ISCELL
  pure_quanta_power universal_gnd *
  page146_i33
#ISCELL
  pure_quanta_power p1v0_aux *
  page146_i34
#CELL
  pure_quanta q_res *
  page146_i35
#CELL
  pure_quanta q_res *
  page146_i36
#ISCELL
  pure_quanta_power universal_gnd *
  page146_i37
#CELL
  pure_quanta q_res *
  page146_i38
#CELL
  pure_quanta q_res *
  page146_i39
#ISCELL
  pure_quanta_power universal_gnd *
  page146_i4
#ISCELL
  pure_quanta_power p1v0_aux *
  page146_i40
#CELL
  pure_quanta schottky_dual_12a_3c *
  page146_i5
#CELL
  pure_quanta q_cap *
  page146_i6
#ISCELL
  pure_quanta_power universal_gnd *
  page146_i7
#ISCELL
  pure_quanta_power p1v0_aux *
  page146_i9
#ISCELL
  pure_quanta quanta_title_block_c *
  *
#ISCELL
  mstr_misc dns *
  *
#ISCELL
  pure_quanta quanta_title_block_c *
  *
#ISCELL
  pure_quanta_power cad_note *
  *
#CELL
  pure_quanta q_res *
  page148_i244
#CELL
  pure_quanta q_res *
  page148_i245
#CELL
  pure_quanta q_res *
  page148_i246
#ISCELL
  pure_quanta_power universal_gnd *
  page148_i247
#ISCELL
  pure_quanta_power universal_power *
  page148_i248
#CELL
  pure_quanta q_res *
  page148_i249
#CELL
  pure_quanta q_res *
  page148_i250
#ISCELL
  standard offpage *
  page148_i251
#ISCELL
  standard offpage *
  page148_i252
#ISCELL
  standard offpage *
  page148_i253
#ISCELL
  standard offpage *
  page148_i254
#CELL
  pure_quanta q_res *
  page148_i255
#CELL
  pure_quanta q_res *
  page148_i256
#CELL
  pure_quanta q_res *
  page148_i257
#CELL
  pure_quanta q_res *
  page148_i258
#ISCELL
  pure_quanta_power universal_gnd *
  page148_i259
#ISCELL
  pure_quanta_power universal_power *
  page148_i260
#CELL
  pure_quanta q_res *
  page148_i261
#ISCELL
  standard offpage *
  page148_i262
#ISCELL
  standard offpage *
  page148_i263
#ISCELL
  standard offpage *
  page148_i264
#ISCELL
  standard offpage *
  page148_i265
#CELL
  pure_quanta 74lv4052pw *
  page148_i266
#ISCELL
  pure_quanta_power universal_gnd *
  page148_i267
#ISCELL
  pure_quanta_power universal_power *
  page148_i292
#CELL
  pure_quanta q_cap *
  page148_i293
#ISCELL
  pure_quanta_power universal_gnd *
  page148_i294
#ISCELL
  pure_quanta_power universal_power *
  page148_i295
#ISCELL
  standard offpage *
  page148_i296
#ISCELL
  standard offpage *
  page148_i297
#ISCELL
  pure_quanta_power universal_power *
  page148_i298
#CELL
  pure_quanta q_cap *
  page148_i299
#ISCELL
  pure_quanta_power universal_gnd *
  page148_i300
#ISCELL
  pure_quanta_power universal_gnd *
  page148_i301
#CELL
  pure_quanta 74lv4052pw *
  page148_i302
#CELL
  pure_quanta q_res *
  page148_i305
#CELL
  pure_quanta q_res *
  page148_i306
#ISCELL
  pure_quanta_power universal_gnd *
  page148_i307
#ISCELL
  pure_quanta_power universal_power *
  page148_i308
#CELL
  pure_quanta q_res *
  page148_i309
#CELL
  pure_quanta q_res *
  page148_i310
#ISCELL
  pure_quanta_power universal_gnd *
  page148_i311
#ISCELL
  standard offpage *
  page148_i312
#ISCELL
  standard offpage *
  page148_i313
#ISCELL
  standard offpage *
  page148_i314
#ISCELL
  standard offpage *
  page148_i315
#ISCELL
  standard offpage *
  page148_i327
#ISCELL
  standard offpage *
  page148_i331
#CELL
  pure_quanta q_res *
  page148_i332
#ISCELL
  standard offpage *
  page148_i336
#ISCELL
  pure_quanta_power universal_power *
  page148_i337
#CELL
  pure_quanta q_res *
  page148_i339
#CELL
  pure_quanta sn74lvc1g07dbvr *
  page148_i340
#ISCELL
  pure_quanta_power universal_power *
  page148_i341
#CELL
  pure_quanta q_cap *
  page148_i342
#ISCELL
  pure_quanta_power universal_gnd *
  page148_i343
#ISCELL
  pure_quanta_power universal_gnd *
  page148_i344
#ISCELL
  standard offpage *
  page148_i347
#CELL
  pure_quanta q_res *
  page148_i349
#ISCELL
  standard offpage *
  page148_i351
#CELL
  pure_quanta q_res *
  page148_i352
#ISCELL
  standard offpage *
  page148_i355
#CELL
  pure_quanta q_res *
  page148_i357
#ISCELL
  standard offpage *
  page148_i362
#CELL
  pure_quanta q_res *
  page148_i363
#ISCELL
  standard offpage *
  page148_i365
#CELL
  pure_quanta q_res *
  page148_i366
#ISCELL
  standard offpage *
  page148_i367
#CELL
  pure_quanta q_res *
  page148_i368
#CELL
  pure_quanta q_res *
  page148_i369
#ISCELL
  pure_quanta_power universal_gnd *
  page148_i370
#ISCELL
  pure_quanta_power universal_gnd *
  page148_i372
#CELL
  pure_quanta q_res *
  page148_i375
#CELL
  pure_quanta q_res *
  page148_i376
#CELL
  pure_quanta q_res *
  page148_i378
#ISCELL
  pure_quanta_power universal_gnd *
  page148_i379
#ISCELL
  pure_quanta_power universal_power *
  page148_i380
#CELL
  pure_quanta q_res *
  page148_i381
#CELL
  pure_quanta q_res *
  page148_i383
#CELL
  pure_quanta q_res *
  page148_i384
#ISCELL
  pure_quanta_power universal_power *
  page148_i385
#CELL
  pure_quanta conn3_210hp1030br1 *
  page148_i386
#CELL
  pure_quanta conn3_210hp1030br1 *
  page148_i387
#CELL
  pure_quanta q_res *
  page148_i388
#ISCELL
  mstr_misc dns *
  *
#ISCELL
  pure_quanta quanta_title_block_c *
  *
#ISCELL
  pure_quanta_power cad_note *
  *
#CELL
  pure_quanta sn74avc2t245rswr *
  page149_i1
#CELL
  pure_quanta q_cap *
  page149_i10
#CELL
  pure_quanta q_res *
  page149_i101
#CELL
  pure_quanta mosfet_n *
  page149_i102
#CELL
  pure_quanta q_res *
  page149_i109
#ISCELL
  pure_quanta_power gnd *
  page149_i11
#ISCELL
  pure_quanta_power gnd *
  page149_i110
#CELL
  pure_quanta q_res *
  page149_i111
#CELL
  pure_quanta q_res *
  page149_i112
#CELL
  pure_quanta q_res *
  page149_i113
#CELL
  pure_quanta q_res *
  page149_i114
#CELL
  pure_quanta q_res *
  page149_i115
#CELL
  pure_quanta q_res *
  page149_i116
#CELL
  pure_quanta q_res *
  page149_i117
#CELL
  pure_quanta q_res *
  page149_i118
#ISCELL
  pure_quanta_power universal_power *
  page149_i119
#ISCELL
  pure_quanta_power universal_power *
  page149_i12
#ISCELL
  pure_quanta_power gnd *
  page149_i120
#ISCELL
  pure_quanta_power gnd *
  page149_i121
#CELL
  pure_quanta q_cap *
  page149_i123
#ISCELL
  standard offpage *
  page149_i124
#ISCELL
  standard offpage *
  page149_i125
#ISCELL
  standard offpage *
  page149_i126
#ISCELL
  standard offpage *
  page149_i127
#ISCELL
  standard offpage *
  page149_i128
#ISCELL
  standard offpage *
  page149_i129
#ISCELL
  standard offpage *
  page149_i130
#ISCELL
  standard offpage *
  page149_i131
#CELL
  pure_quanta q_res *
  page149_i132
#CELL
  pure_quanta q_res *
  page149_i133
#CELL
  pure_quanta q_cap *
  page149_i134
#CELL
  pure_quanta q_cap *
  page149_i137
#ISCELL
  pure_quanta_power gnd *
  page149_i138
#CELL
  pure_quanta q_cap *
  page149_i140
#ISCELL
  pure_quanta_power gnd *
  page149_i141
#CELL
  pure_quanta sconn20_hsu2101l00007h *
  page149_i142
#ISCELL
  pure_quanta_power gnd *
  page149_i143
#ISCELL
  pure_quanta_power universal_power *
  page149_i144
#ISCELL
  pure_quanta_power universal_power *
  page149_i145
#CELL
  pure_quanta q_res *
  page149_i146
#CELL
  pure_quanta q_res *
  page149_i147
#CELL
  pure_quanta q_res *
  page149_i148
#CELL
  pure_quanta q_res *
  page149_i149
#CELL
  pure_quanta q_res *
  page149_i150
#ISCELL
  pure_quanta_power gnd *
  page149_i151
#CELL
  pure_quanta q_cap *
  page149_i152
#ISCELL
  standard offpage *
  page149_i153
#ISCELL
  standard offpage *
  page149_i154
#ISCELL
  standard offpage *
  page149_i155
#ISCELL
  standard offpage *
  page149_i156
#CELL
  pure_quanta q_res *
  page149_i157
#ISCELL
  standard offpage *
  page149_i158
#CELL
  pure_quanta q_res *
  page149_i159
#CELL
  pure_quanta q_res *
  page149_i160
#CELL
  pure_quanta q_cap *
  page149_i161
#ISCELL
  pure_quanta_power gnd *
  page149_i162
#CELL
  pure_quanta q_cap *
  page149_i163
#ISCELL
  pure_quanta_power gnd *
  page149_i164
#ISCELL
  pure_quanta_power universal_power *
  page149_i20
#CELL
  pure_quanta q_cap *
  page149_i21
#ISCELL
  pure_quanta_power gnd *
  page149_i22
#CELL
  pure_quanta q_cap *
  page149_i23
#ISCELL
  pure_quanta_power gnd *
  page149_i24
#CELL
  pure_quanta q_cap *
  page149_i25
#ISCELL
  pure_quanta_power gnd *
  page149_i26
#ISCELL
  pure_quanta_power gnd *
  page149_i27
#ISCELL
  pure_quanta_power universal_power *
  page149_i28
#CELL
  pure_quanta q_cap *
  page149_i29
#ISCELL
  standard offpage *
  page149_i3
#ISCELL
  pure_quanta_power gnd *
  page149_i30
#CELL
  pure_quanta sn74avc4t774pwr *
  page149_i31
#ISCELL
  pure_quanta_power universal_power *
  page149_i32
#ISCELL
  pure_quanta_power gnd *
  page149_i33
#CELL
  pure_quanta sn74avc4t774pwr *
  page149_i34
#ISCELL
  standard offpage *
  page149_i4
#CELL
  pure_quanta q_cap *
  page149_i41
#ISCELL
  pure_quanta_power gnd *
  page149_i42
#ISCELL
  standard offpage *
  page149_i43
#ISCELL
  standard offpage *
  page149_i44
#ISCELL
  standard offpage *
  page149_i45
#ISCELL
  standard offpage *
  page149_i46
#ISCELL
  standard offpage *
  page149_i5
#ISCELL
  standard offpage *
  page149_i51
#CELL
  pure_quanta q_res *
  page149_i53
#ISCELL
  pure_quanta_power universal_power *
  page149_i54
#ISCELL
  pure_quanta_power gnd *
  page149_i55
#CELL
  pure_quanta q_cap *
  page149_i56
#ISCELL
  standard offpage *
  page149_i6
#CELL
  pure_quanta q_cap *
  page149_i62
#ISCELL
  pure_quanta_power gnd *
  page149_i63
#ISCELL
  standard offpage *
  page149_i64
#ISCELL
  standard offpage *
  page149_i65
#ISCELL
  standard offpage *
  page149_i68
#ISCELL
  standard offpage *
  page149_i69
#CELL
  pure_quanta q_res *
  page149_i7
#ISCELL
  standard offpage *
  page149_i70
#ISCELL
  pure_quanta_power universal_power *
  page149_i71
#ISCELL
  pure_quanta_power universal_power *
  page149_i73
#CELL
  pure_quanta q_cap *
  page149_i74
#ISCELL
  pure_quanta_power gnd *
  page149_i75
#CELL
  pure_quanta sn74avc2t245rswr *
  page149_i76
#ISCELL
  pure_quanta_power gnd *
  page149_i77
#ISCELL
  pure_quanta_power universal_power *
  page149_i78
#CELL
  pure_quanta q_res *
  page149_i8
#CELL
  pure_quanta q_cap *
  page149_i80
#ISCELL
  pure_quanta_power gnd *
  page149_i81
#ISCELL
  pure_quanta_power universal_power *
  page149_i82
#CELL
  pure_quanta q_res *
  page149_i83
#ISCELL
  pure_quanta_power gnd *
  page149_i84
#ISCELL
  pure_quanta_power gnd *
  page149_i85
#CELL
  pure_quanta q_res *
  page149_i9
#ISCELL
  standard offpage *
  page149_i90
#ISCELL
  standard offpage *
  page149_i91
#CELL
  pure_quanta q_res *
  page149_i92
#ISCELL
  standard offpage *
  page149_i93
#ISCELL
  standard offpage *
  page149_i94
#ISCELL
  standard offpage *
  page149_i95
#CELL
  pure_quanta q_res *
  page149_i96
#ISCELL
  pure_quanta quanta_title_block_c *
  *
#ISCELL
  pure_quanta_power cad_note *
  *
#ISCELL
  standard offpage *
  page150_i10
#ISCELL
  standard offpage *
  page150_i11
#ISCELL
  standard offpage *
  page150_i12
#ISCELL
  pure_quanta_power gnd *
  page150_i13
#CELL
  pure_quanta q_cap *
  page150_i14
#ISCELL
  pure_quanta_power universal_power *
  page150_i15
#ISCELL
  pure_quanta_power gnd *
  page150_i16
#ISCELL
  pure_quanta_power gnd *
  page150_i17
#ISCELL
  pure_quanta_power universal_power *
  page150_i18
#CELL
  pure_quanta q_cap *
  page150_i19
#ISCELL
  standard offpage *
  page150_i20
#ISCELL
  standard offpage *
  page150_i21
#ISCELL
  standard offpage *
  page150_i22
#ISCELL
  standard offpage *
  page150_i23
#CELL
  pure_quanta q_res *
  page150_i24
#CELL
  pure_quanta q_res *
  page150_i25
#CELL
  pure_quanta q_res *
  page150_i26
#CELL
  pure_quanta q_res *
  page150_i27
#CELL
  pure_quanta sn74avc4t774pwr *
  page150_i28
#ISCELL
  standard offpage *
  page150_i29
#ISCELL
  standard offpage *
  page150_i30
#ISCELL
  standard offpage *
  page150_i31
#ISCELL
  standard offpage *
  page150_i32
#CELL
  pure_quanta q_res *
  page150_i33
#CELL
  pure_quanta q_res *
  page150_i34
#CELL
  pure_quanta q_res *
  page150_i35
#CELL
  pure_quanta q_res *
  page150_i36
#ISCELL
  pure_quanta_power universal_power *
  page150_i37
#ISCELL
  pure_quanta_power universal_power *
  page150_i38
#ISCELL
  pure_quanta_power gnd *
  page150_i39
#CELL
  pure_quanta q_cap *
  page150_i40
#ISCELL
  pure_quanta_power gnd *
  page150_i41
#ISCELL
  pure_quanta_power gnd *
  page150_i42
#CELL
  pure_quanta q_cap *
  page150_i43
#CELL
  pure_quanta sn74avc2t245rswr *
  page150_i60
#ISCELL
  standard offpage *
  page150_i61
#ISCELL
  standard offpage *
  page150_i62
#ISCELL
  pure_quanta_power gnd *
  page150_i63
#ISCELL
  pure_quanta_power universal_power *
  page150_i64
#ISCELL
  pure_quanta_power gnd *
  page150_i65
#CELL
  pure_quanta q_cap *
  page150_i66
#ISCELL
  pure_quanta_power universal_power *
  page150_i67
#ISCELL
  pure_quanta_power gnd *
  page150_i68
#CELL
  pure_quanta q_cap *
  page150_i69
#ISCELL
  pure_quanta_power gnd *
  page150_i70
#CELL
  pure_quanta q_res *
  page150_i71
#ISCELL
  standard offpage *
  page150_i72
#ISCELL
  standard offpage *
  page150_i73
#ISCELL
  standard offpage *
  page150_i74
#ISCELL
  standard offpage *
  page150_i75
#CELL
  pure_quanta q_res *
  page150_i76
#CELL
  pure_quanta q_res *
  page150_i78
#CELL
  pure_quanta sn74avc4t774pwr *
  page150_i8
#ISCELL
  standard offpage *
  page150_i9
#ISCELL
  mstr_misc dns *
  *
#ISCELL
  pure_quanta quanta_title_block_c *
  *
#ISCELL
  pure_quanta_power cad_note *
  *
#CELL
  pure_quanta sn74auc2g66dctr *
  page151_i1
#CELL
  pure_quanta q_res *
  page151_i10
#CELL
  pure_quanta q_res *
  page151_i11
#ISCELL
  pure_quanta_power universal_power *
  page151_i12
#ISCELL
  pure_quanta_power gnd *
  page151_i13
#ISCELL
  pure_quanta_power gnd *
  page151_i14
#CELL
  pure_quanta q_cap *
  page151_i15
#ISCELL
  pure_quanta_power universal_power *
  page151_i16
#CELL
  pure_quanta sn74auc2g66dctr *
  page151_i17
#ISCELL
  standard offpage *
  page151_i18
#ISCELL
  pure_quanta_power gnd *
  page151_i19
#CELL
  pure_quanta q_res *
  page151_i2
#ISCELL
  pure_quanta_power universal_power *
  page151_i20
#ISCELL
  pure_quanta_power gnd *
  page151_i21
#CELL
  pure_quanta q_cap *
  page151_i22
#CELL
  pure_quanta sn74auc2g66dctr *
  page151_i23
#CELL
  pure_quanta q_res *
  page151_i25
#ISCELL
  pure_quanta_power universal_power *
  page151_i26
#CELL
  pure_quanta q_res *
  page151_i27
#ISCELL
  pure_quanta_power universal_power *
  page151_i28
#ISCELL
  pure_quanta_power gnd *
  page151_i29
#ISCELL
  pure_quanta_power gnd *
  page151_i3
#ISCELL
  standard offpage *
  page151_i30
#CELL
  pure_quanta sn74auc2g66dctr *
  page151_i31
#ISCELL
  standard offpage *
  page151_i32
#ISCELL
  standard offpage *
  page151_i33
#CELL
  pure_quanta q_res *
  page151_i34
#ISCELL
  pure_quanta_power universal_power *
  page151_i35
#CELL
  pure_quanta q_cap *
  page151_i36
#ISCELL
  pure_quanta_power gnd *
  page151_i37
#ISCELL
  pure_quanta_power gnd *
  page151_i38
#ISCELL
  pure_quanta_power gnd *
  page151_i39
#CELL
  pure_quanta q_cap *
  page151_i4
#ISCELL
  pure_quanta_power gnd *
  page151_i40
#ISCELL
  standard offpage *
  page151_i41
#CELL
  pure_quanta q_cap *
  page151_i42
#ISCELL
  pure_quanta_power gnd *
  page151_i43
#ISCELL
  pure_quanta_power universal_power *
  page151_i44
#CELL
  pure_quanta mosfet_n *
  page151_i45
#CELL
  pure_quanta mosfet_n *
  page151_i46
#ISCELL
  standard offpage *
  page151_i47
#CELL
  pure_quanta q_res *
  page151_i48
#CELL
  pure_quanta q_res *
  page151_i49
#ISCELL
  standard offpage *
  page151_i5
#CELL
  pure_quanta q_res *
  page151_i50
#ISCELL
  standard offpage *
  page151_i6
#ISCELL
  pure_quanta_power universal_power *
  page151_i9
#ISCELL
  pure_quanta quanta_title_block_c *
  *
#ISCELL
  mstr_misc dns *
  *
#ISCELL
  pure_quanta quanta_title_block_c *
  *
#CELL
  pure_quanta cyusb330468ltxi *
  page153_i1
#ISCELL
  standard offpage *
  page153_i10
#ISCELL
  standard offpage *
  page153_i11
#ISCELL
  standard offpage *
  page153_i12
#ISCELL
  standard offpage *
  page153_i13
#CELL
  pure_quanta q_xtal_4p_13bi_24gnd *
  page153_i14
#ISCELL
  pure_quanta_power gnd *
  page153_i15
#ISCELL
  pure_quanta_power gnd *
  page153_i16
#ISCELL
  standard offpage *
  page153_i19
#ISCELL
  standard offpage *
  page153_i2
#CELL
  pure_quanta q_res *
  page153_i20
#ISCELL
  pure_quanta_power universal_power *
  page153_i22
#CELL
  pure_quanta q_res *
  page153_i23
#ISCELL
  pure_quanta_power gnd *
  page153_i24
#CELL
  pure_quanta q_cap *
  page153_i25
#ISCELL
  pure_quanta_power p1v0_aux *
  page153_i26
#CELL
  pure_quanta q_res *
  page153_i27
#CELL
  pure_quanta q_cap *
  page153_i28
#CELL
  pure_quanta q_cap *
  page153_i29
#ISCELL
  standard offpage *
  page153_i3
#ISCELL
  pure_quanta_power gnd *
  page153_i30
#ISCELL
  pure_quanta_power p1v0_aux *
  page153_i31
#ISCELL
  pure_quanta_power gnd *
  page153_i36
#CELL
  pure_quanta q_res *
  page153_i37
#CELL
  pure_quanta q_res *
  page153_i39
#ISCELL
  standard offpage *
  page153_i4
#ISCELL
  pure_quanta_power gnd *
  page153_i40
#CELL
  pure_quanta q_res *
  page153_i41
#ISCELL
  pure_quanta_power universal_power *
  page153_i42
#CELL
  pure_quanta q_res *
  page153_i43
#CELL
  pure_quanta q_res *
  page153_i44
#CELL
  pure_quanta q_res *
  page153_i45
#ISCELL
  pure_quanta_power p1v0_aux *
  page153_i46
#CELL
  pure_quanta q_res *
  page153_i47
#CELL
  pure_quanta q_res *
  page153_i48
#ISCELL
  pure_quanta_power gnd *
  page153_i49
#ISCELL
  standard offpage *
  page153_i5
#ISCELL
  standard offpage *
  page153_i55
#ISCELL
  standard offpage *
  page153_i56
#ISCELL
  standard offpage *
  page153_i6
#ISCELL
  pure_quanta_power gnd *
  page153_i61
#ISCELL
  pure_quanta_power gnd *
  page153_i62
#ISCELL
  pure_quanta_power universal_power *
  page153_i63
#CELL
  pure_quanta m24128bwmn6tp *
  page153_i64
#CELL
  pure_quanta q_res *
  page153_i65
#CELL
  pure_quanta q_res *
  page153_i66
#CELL
  pure_quanta q_res *
  page153_i67
#CELL
  pure_quanta q_res *
  page153_i68
#CELL
  pure_quanta q_res *
  page153_i69
#ISCELL
  standard offpage *
  page153_i7
#CELL
  pure_quanta q_res *
  page153_i70
#ISCELL
  pure_quanta_power gnd *
  page153_i71
#ISCELL
  pure_quanta_power universal_power *
  page153_i72
#ISCELL
  pure_quanta_power gnd *
  page153_i73
#ISCELL
  pure_quanta_power universal_power *
  page153_i74
#CELL
  pure_quanta q_cap *
  page153_i75
#ISCELL
  pure_quanta_power gnd *
  page153_i76
#CELL
  pure_quanta q_res *
  page153_i77
#ISCELL
  pure_quanta_power gnd *
  page153_i78
#ISCELL
  standard offpage *
  page153_i8
#ISCELL
  standard offpage *
  page153_i81
#ISCELL
  standard offpage *
  page153_i82
#CELL
  pure_quanta q_res *
  page153_i83
#CELL
  pure_quanta q_res *
  page153_i84
#CELL
  pure_quanta q_res *
  page153_i85
#CELL
  pure_quanta q_res *
  page153_i86
#CELL
  pure_quanta q_res *
  page153_i87
#CELL
  pure_quanta q_res *
  page153_i88
#CELL
  pure_quanta q_res *
  page153_i89
#ISCELL
  standard offpage *
  page153_i9
#CELL
  pure_quanta q_res *
  page153_i90
#CELL
  pure_quanta q_cap *
  page153_i91
#CELL
  pure_quanta q_cap *
  page153_i92
#CELL
  pure_quanta q_res *
  page153_i93
#ISCELL
  pure_quanta quanta_title_block_c *
  *
#CELL
  pure_quanta cyusb330468ltxi *
  page154_i1
#CELL
  pure_quanta q_cap *
  page154_i10
#ISCELL
  pure_quanta_power gnd *
  page154_i11
#CELL
  pure_quanta q_cap *
  page154_i12
#CELL
  pure_quanta q_cap *
  page154_i13
#CELL
  pure_quanta q_cap *
  page154_i14
#CELL
  pure_quanta q_cap *
  page154_i15
#ISCELL
  pure_quanta_power gnd *
  page154_i16
#CELL
  pure_quanta q_cap *
  page154_i17
#ISCELL
  pure_quanta_power gnd *
  page154_i18
#CELL
  pure_quanta q_cap *
  page154_i19
#ISCELL
  pure_quanta_power universal_power *
  page154_i2
#CELL
  pure_quanta q_cap *
  page154_i20
#CELL
  pure_quanta q_cap *
  page154_i21
#CELL
  pure_quanta q_cap *
  page154_i22
#CELL
  pure_quanta q_cap *
  page154_i23
#ISCELL
  pure_quanta_power gnd *
  page154_i24
#ISCELL
  pure_quanta_power gnd *
  page154_i25
#CELL
  pure_quanta q_inductor *
  page154_i26
#CELL
  pure_quanta q_cap *
  page154_i27
#ISCELL
  pure_quanta_power gnd *
  page154_i28
#CELL
  pure_quanta q_cap *
  page154_i29
#CELL
  pure_quanta q_inductor *
  page154_i3
#ISCELL
  pure_quanta_power universal_power *
  page154_i30
#CELL
  pure_quanta q_cap *
  page154_i31
#CELL
  pure_quanta q_cap *
  page154_i32
#ISCELL
  pure_quanta_power gnd *
  page154_i33
#CELL
  pure_quanta q_cap *
  page154_i34
#CELL
  pure_quanta q_cap *
  page154_i35
#ISCELL
  pure_quanta_power gnd *
  page154_i36
#CELL
  pure_quanta q_cap *
  page154_i37
#CELL
  pure_quanta q_cap *
  page154_i38
#ISCELL
  pure_quanta_power gnd *
  page154_i39
#ISCELL
  pure_quanta_power universal_power *
  page154_i4
#CELL
  pure_quanta q_cap *
  page154_i40
#CELL
  pure_quanta q_cap *
  page154_i41
#ISCELL
  pure_quanta_power gnd *
  page154_i42
#CELL
  pure_quanta q_cap *
  page154_i43
#CELL
  pure_quanta q_cap *
  page154_i44
#ISCELL
  pure_quanta_power gnd *
  page154_i45
#CELL
  pure_quanta q_cap *
  page154_i46
#CELL
  pure_quanta q_cap *
  page154_i47
#ISCELL
  pure_quanta_power gnd *
  page154_i48
#CELL
  pure_quanta q_cap *
  page154_i49
#CELL
  pure_quanta q_cap *
  page154_i5
#CELL
  pure_quanta q_cap *
  page154_i50
#ISCELL
  pure_quanta_power gnd *
  page154_i51
#CELL
  pure_quanta q_cap *
  page154_i52
#CELL
  pure_quanta q_cap *
  page154_i53
#ISCELL
  pure_quanta_power gnd *
  page154_i54
#CELL
  pure_quanta q_cap *
  page154_i55
#CELL
  pure_quanta q_cap *
  page154_i56
#ISCELL
  pure_quanta_power gnd *
  page154_i57
#CELL
  pure_quanta q_cap *
  page154_i58
#CELL
  pure_quanta q_cap *
  page154_i59
#CELL
  pure_quanta q_cap *
  page154_i60
#ISCELL
  pure_quanta_power gnd *
  page154_i61
#ISCELL
  pure_quanta_power gnd *
  page154_i62
#CELL
  pure_quanta q_cap *
  page154_i63
#CELL
  pure_quanta q_cap *
  page154_i64
#CELL
  pure_quanta q_cap *
  page154_i65
#CELL
  pure_quanta q_cap *
  page154_i66
#ISCELL
  pure_quanta_power gnd *
  page154_i67
#CELL
  pure_quanta q_cap *
  page154_i68
#CELL
  pure_quanta q_cap *
  page154_i69
#CELL
  pure_quanta q_cap *
  page154_i7
#ISCELL
  pure_quanta_power gnd *
  page154_i70
#CELL
  pure_quanta q_cap *
  page154_i71
#ISCELL
  pure_quanta_power gnd *
  page154_i72
#CELL
  pure_quanta q_cap *
  page154_i73
#CELL
  pure_quanta q_cap *
  page154_i74
#CELL
  pure_quanta q_cap *
  page154_i75
#CELL
  pure_quanta q_cap *
  page154_i76
#ISCELL
  pure_quanta_power gnd *
  page154_i77
#CELL
  pure_quanta q_cap *
  page154_i78
#CELL
  pure_quanta q_cap *
  page154_i79
#ISCELL
  pure_quanta_power gnd *
  page154_i8
#ISCELL
  pure_quanta_power gnd *
  page154_i80
#CELL
  pure_quanta q_cap *
  page154_i81
#CELL
  pure_quanta q_cap *
  page154_i82
#CELL
  pure_quanta q_cap *
  page154_i83
#ISCELL
  pure_quanta_power gnd *
  page154_i84
#ISCELL
  pure_quanta_power universal_power *
  page154_i85
#ISCELL
  pure_quanta_power universal_power *
  page154_i86
#ISCELL
  pure_quanta_power universal_power *
  page154_i87
#ISCELL
  pure_quanta_power universal_power *
  page154_i88
#CELL
  pure_quanta q_cap *
  page154_i9
#ISCELL
  mstr_misc dns *
  *
#ISCELL
  pure_quanta quanta_title_block_c *
  *
#CELL
  pure_quanta tusb8042airgcr *
  page155_i101
#CELL
  pure_quanta q_res *
  page155_i102
#ISCELL
  pure_quanta_power universal_power *
  page155_i103
#CELL
  pure_quanta q_res *
  page155_i104
#CELL
  pure_quanta q_res *
  page155_i105
#ISCELL
  pure_quanta_power gnd *
  page155_i106
#ISCELL
  pure_quanta_power universal_power *
  page155_i108
#ISCELL
  pure_quanta_power gnd *
  page155_i110
#CELL
  pure_quanta q_res *
  page155_i111
#ISCELL
  pure_quanta_power gnd *
  page155_i112
#ISCELL
  standard offpage *
  page155_i113
#CELL
  pure_quanta q_res *
  page155_i114
#CELL
  pure_quanta q_res *
  page155_i115
#CELL
  pure_quanta q_res *
  page155_i116
#ISCELL
  pure_quanta_power gnd *
  page155_i117
#CELL
  pure_quanta q_res *
  page155_i118
#CELL
  pure_quanta q_res *
  page155_i119
#ISCELL
  pure_quanta_power gnd *
  page155_i120
#CELL
  pure_quanta q_res *
  page155_i121
#ISCELL
  pure_quanta_power p1v0_aux *
  page155_i122
#CELL
  pure_quanta q_res *
  page155_i123
#CELL
  pure_quanta q_res *
  page155_i124
#ISCELL
  pure_quanta_power universal_power *
  page155_i126
#CELL
  pure_quanta q_cap *
  page155_i127
#ISCELL
  pure_quanta_power gnd *
  page155_i128
#CELL
  pure_quanta q_res *
  page155_i129
#ISCELL
  pure_quanta_power gnd *
  page155_i130
#CELL
  pure_quanta q_res *
  page155_i131
#ISCELL
  standard offpage *
  page155_i132
#ISCELL
  pure_quanta_power universal_power *
  page155_i133
#CELL
  pure_quanta q_res *
  page155_i134
#ISCELL
  pure_quanta_power universal_power *
  page155_i135
#CELL
  pure_quanta q_res *
  page155_i136
#CELL
  pure_quanta q_res *
  page155_i137
#CELL
  pure_quanta q_res *
  page155_i138
#ISCELL
  pure_quanta_power universal_power *
  page155_i139
#CELL
  pure_quanta q_res *
  page155_i140
#ISCELL
  standard offpage *
  page155_i141
#ISCELL
  standard offpage *
  page155_i142
#CELL
  pure_quanta q_res *
  page155_i143
#ISCELL
  pure_quanta_power universal_power *
  page155_i144
#CELL
  pure_quanta q_cap *
  page155_i145
#ISCELL
  standard offpage *
  page155_i146
#ISCELL
  standard offpage *
  page155_i147
#ISCELL
  pure_quanta_power universal_power *
  page155_i148
#CELL
  pure_quanta q_res *
  page155_i149
#ISCELL
  pure_quanta_power universal_power *
  page155_i150
#CELL
  pure_quanta q_res *
  page155_i151
#ISCELL
  standard offpage *
  page155_i152
#ISCELL
  standard offpage *
  page155_i153
#ISCELL
  pure_quanta_power universal_power *
  page155_i154
#CELL
  pure_quanta q_res *
  page155_i155
#ISCELL
  standard offpage *
  page155_i156
#ISCELL
  standard offpage *
  page155_i157
#ISCELL
  standard offpage *
  page155_i158
#ISCELL
  standard offpage *
  page155_i159
#ISCELL
  pure_quanta_power universal_power *
  page155_i163
#CELL
  pure_quanta q_res *
  page155_i164
#ISCELL
  pure_quanta_power universal_power *
  page155_i165
#CELL
  pure_quanta q_res *
  page155_i166
#ISCELL
  standard offpage *
  page155_i167
#ISCELL
  standard offpage *
  page155_i168
#CELL
  pure_quanta q_res *
  page155_i169
#ISCELL
  pure_quanta_power universal_power *
  page155_i170
#CELL
  pure_quanta q_res *
  page155_i175
#ISCELL
  pure_quanta_power gnd *
  page155_i176
#ISCELL
  pure_quanta_power universal_power *
  page155_i178
#CELL
  pure_quanta q_res *
  page155_i179
#CELL
  pure_quanta q_res *
  page155_i180
#CELL
  pure_quanta q_res *
  page155_i181
#CELL
  pure_quanta q_res *
  page155_i182
#CELL
  pure_quanta q_res *
  page155_i183
#ISCELL
  pure_quanta_power universal_power *
  page155_i184
#CELL
  pure_quanta q_res *
  page155_i185
#ISCELL
  pure_quanta_power universal_power *
  page155_i186
#CELL
  pure_quanta q_res *
  page155_i187
#CELL
  pure_quanta q_res *
  page155_i188
#ISCELL
  pure_quanta_power gnd *
  page155_i189
#ISCELL
  standard offpage *
  page155_i190
#ISCELL
  standard offpage *
  page155_i191
#CELL
  pure_quanta q_res *
  page155_i192
#CELL
  pure_quanta q_res *
  page155_i193
#ISCELL
  pure_quanta_power universal_power *
  page155_i194
#CELL
  pure_quanta q_res *
  page155_i195
#ISCELL
  pure_quanta_power universal_power *
  page155_i196
#CELL
  pure_quanta q_res *
  page155_i197
#CELL
  pure_quanta q_res *
  page155_i198
#ISCELL
  pure_quanta_power gnd *
  page155_i199
#CELL
  pure_quanta q_res *
  page155_i200
#ISCELL
  standard offpage *
  page155_i201
#CELL
  pure_quanta q_res *
  page155_i202
#ISCELL
  pure_quanta_power universal_power *
  page155_i204
#CELL
  pure_quanta q_res *
  page155_i205
#ISCELL
  standard offpage *
  page155_i206
#CELL
  pure_quanta q_res *
  page155_i207
#CELL
  pure_quanta q_res *
  page155_i208
#ISCELL
  pure_quanta_power gnd *
  page155_i209
#ISCELL
  pure_quanta_power gnd *
  page155_i210
#ISCELL
  pure_quanta_power gnd *
  page155_i211
#CELL
  pure_quanta q_res *
  page155_i212
#CELL
  pure_quanta q_res *
  page155_i213
#CELL
  pure_quanta q_res *
  page155_i89
#ISCELL
  pure_quanta_power gnd *
  page155_i90
#CELL
  pure_quanta q_res *
  page155_i91
#ISCELL
  pure_quanta_power universal_power *
  page155_i92
#ISCELL
  mstr_misc dns *
  *
#ISCELL
  pure_quanta quanta_title_block_c *
  *
#CELL
  pure_quanta tusb8042airgcr *
  page157_i119
#CELL
  pure_quanta q_res *
  page157_i122
#CELL
  pure_quanta q_res *
  page157_i124
#CELL
  pure_quanta q_res *
  page157_i125
#ISCELL
  pure_quanta_power universal_power *
  page157_i128
#ISCELL
  pure_quanta_power gnd *
  page157_i129
#CELL
  pure_quanta q_res *
  page157_i130
#CELL
  pure_quanta q_res *
  page157_i131
#ISCELL
  pure_quanta_power universal_power *
  page157_i132
#ISCELL
  pure_quanta_power universal_power *
  page157_i133
#CELL
  pure_quanta q_res *
  page157_i134
#CELL
  pure_quanta q_res *
  page157_i136
#ISCELL
  pure_quanta_power universal_power *
  page157_i137
#CELL
  pure_quanta q_res *
  page157_i138
#CELL
  pure_quanta q_res *
  page157_i139
#ISCELL
  pure_quanta_power gnd *
  page157_i140
#CELL
  pure_quanta q_res *
  page157_i142
#CELL
  pure_quanta q_res *
  page157_i145
#CELL
  pure_quanta q_res *
  page157_i146
#ISCELL
  standard offpage *
  page157_i147
#CELL
  pure_quanta q_res *
  page157_i148
#ISCELL
  standard offpage *
  page157_i149
#CELL
  pure_quanta q_res *
  page157_i150
#CELL
  pure_quanta q_res *
  page157_i151
#ISCELL
  pure_quanta_power universal_power *
  page157_i152
#CELL
  pure_quanta q_res *
  page157_i153
#ISCELL
  pure_quanta_power universal_power *
  page157_i154
#CELL
  pure_quanta q_res *
  page157_i155
#CELL
  pure_quanta q_res *
  page157_i156
#ISCELL
  pure_quanta_power gnd *
  page157_i157
#CELL
  pure_quanta q_res *
  page157_i158
#ISCELL
  pure_quanta_power gnd *
  page157_i159
#CELL
  pure_quanta q_res *
  page157_i160
#ISCELL
  pure_quanta_power gnd *
  page157_i162
#ISCELL
  pure_quanta_power gnd *
  page157_i163
#CELL
  pure_quanta q_xtal_4p_13bi_24gnd *
  page157_i164
#ISCELL
  pure_quanta_power gnd *
  page157_i166
#ISCELL
  pure_quanta_power gnd *
  page157_i167
#ISCELL
  standard offpage *
  page157_i168
#ISCELL
  pure_quanta_power universal_power *
  page157_i169
#CELL
  pure_quanta q_inductor *
  page157_i17
#CELL
  pure_quanta q_res *
  page157_i170
#CELL
  pure_quanta q_res *
  page157_i171
#CELL
  pure_quanta q_cap *
  page157_i174
#CELL
  pure_quanta q_cap *
  page157_i175
#ISCELL
  pure_quanta_power universal_power *
  page157_i18
#ISCELL
  pure_quanta_power universal_power *
  page157_i19
#CELL
  pure_quanta q_inductor *
  page157_i20
#CELL
  pure_quanta q_cap *
  page157_i21
#CELL
  pure_quanta q_cap *
  page157_i22
#CELL
  pure_quanta q_cap *
  page157_i23
#CELL
  pure_quanta q_cap *
  page157_i24
#CELL
  pure_quanta q_cap *
  page157_i25
#CELL
  pure_quanta q_cap *
  page157_i26
#CELL
  pure_quanta q_cap *
  page157_i27
#CELL
  pure_quanta q_cap *
  page157_i28
#CELL
  pure_quanta q_cap *
  page157_i29
#CELL
  pure_quanta q_cap *
  page157_i30
#CELL
  pure_quanta q_cap *
  page157_i31
#CELL
  pure_quanta q_cap *
  page157_i32
#CELL
  pure_quanta q_cap *
  page157_i33
#ISCELL
  pure_quanta_power gnd *
  page157_i34
#ISCELL
  pure_quanta_power universal_power *
  page157_i35
#CELL
  pure_quanta q_cap *
  page157_i36
#ISCELL
  pure_quanta_power universal_power *
  page157_i37
#ISCELL
  pure_quanta_power gnd *
  page157_i38
#CELL
  pure_quanta q_cap *
  page157_i39
#CELL
  pure_quanta q_cap *
  page157_i40
#CELL
  pure_quanta q_cap *
  page157_i41
#CELL
  pure_quanta q_cap *
  page157_i42
#CELL
  pure_quanta q_cap *
  page157_i43
#CELL
  pure_quanta q_cap *
  page157_i44
#CELL
  pure_quanta q_cap *
  page157_i45
#CELL
  pure_quanta q_cap *
  page157_i46
#CELL
  pure_quanta q_cap *
  page157_i47
#CELL
  pure_quanta q_cap *
  page157_i48
#CELL
  pure_quanta q_cap *
  page157_i49
#CELL
  pure_quanta q_cap *
  page157_i50
#CELL
  pure_quanta q_cap *
  page157_i51
#CELL
  pure_quanta q_cap *
  page157_i52
#CELL
  pure_quanta q_cap *
  page157_i53
#CELL
  pure_quanta q_cap *
  page157_i54
#ISCELL
  pure_quanta_power gnd *
  page157_i61
#CELL
  pure_quanta q_res *
  page157_i63
#ISCELL
  pure_quanta_power universal_power *
  page157_i64
#ISCELL
  standard offpage *
  page157_i74
#CELL
  pure_quanta q_res *
  page157_i75
#CELL
  pure_quanta q_res *
  page157_i76
#CELL
  pure_quanta q_res *
  page157_i77
#ISCELL
  pure_quanta_power universal_power *
  page157_i78
#CELL
  pure_quanta q_res *
  page157_i79
#ISCELL
  pure_quanta_power gnd *
  page157_i80
#CELL
  pure_quanta q_res *
  page157_i81
#ISCELL
  pure_quanta_power universal_power *
  page157_i82
#ISCELL
  mstr_misc dns *
  *
#ISCELL
  pure_quanta quanta_title_block_c *
  *
#ISCELL
  pure_quanta_power cad_note *
  *
#ISCELL
  pure_quanta_power gnd *
  page158_i105
#ISCELL
  pure_quanta_power gnd *
  page158_i106
#ISCELL
  pure_quanta_power gnd *
  page158_i107
#ISCELL
  standard offpage *
  page158_i11
#ISCELL
  pure_quanta_power gnd *
  page158_i110
#ISCELL
  pure_quanta_power gnd *
  page158_i113
#ISCELL
  pure_quanta_power gnd *
  page158_i114
#ISCELL
  pure_quanta_power gnd *
  page158_i117
#ISCELL
  pure_quanta_power gnd *
  page158_i118
#ISCELL
  standard offpage *
  page158_i12
#CELL
  pure_quanta q_res *
  page158_i120
#CELL
  pure_quanta q_res *
  page158_i121
#CELL
  pure_quanta q_res *
  page158_i124
#CELL
  pure_quanta q_res *
  page158_i125
#CELL
  pure_quanta q_res *
  page158_i126
#CELL
  pure_quanta q_res *
  page158_i127
#ISCELL
  standard offpage *
  page158_i13
#CELL
  pure_quanta q_cap *
  page158_i137
#CELL
  pure_quanta q_cap *
  page158_i138
#CELL
  pure_quanta q_cap *
  page158_i139
#ISCELL
  standard offpage *
  page158_i14
#CELL
  pure_quanta q_cap *
  page158_i140
#CELL
  pure_quanta q_cap *
  page158_i141
#CELL
  pure_quanta q_cap *
  page158_i142
#CELL
  pure_quanta q_cap *
  page158_i143
#CELL
  pure_quanta q_cap *
  page158_i144
#CELL
  pure_quanta q_res *
  page158_i145
#CELL
  pure_quanta q_res *
  page158_i146
#CELL
  pure_quanta q_cap *
  page158_i147
#CELL
  pure_quanta q_cap *
  page158_i148
#ISCELL
  standard offpage *
  page158_i15
#ISCELL
  standard offpage *
  page158_i16
#CELL
  pure_quanta q_res *
  page158_i3
#ISCELL
  standard offpage *
  page158_i39
#CELL
  pure_quanta q_res *
  page158_i4
#ISCELL
  standard offpage *
  page158_i40
#ISCELL
  standard offpage *
  page158_i41
#ISCELL
  standard offpage *
  page158_i42
#ISCELL
  standard offpage *
  page158_i43
#ISCELL
  standard offpage *
  page158_i44
#ISCELL
  standard offpage *
  page158_i45
#ISCELL
  standard offpage *
  page158_i46
#ISCELL
  standard offpage *
  page158_i47
#ISCELL
  standard offpage *
  page158_i48
#CELL
  pure_quanta q_cap_diffbus *
  page158_i49
#CELL
  pure_quanta q_res *
  page158_i5
#CELL
  pure_quanta q_cap_diffbus *
  page158_i50
#ISCELL
  standard offpage *
  page158_i53
#ISCELL
  standard offpage *
  page158_i54
#CELL
  pure_quanta q_res *
  page158_i6
#ISCELL
  standard offpage *
  page158_i65
#ISCELL
  standard offpage *
  page158_i66
#ISCELL
  standard offpage *
  page158_i67
#ISCELL
  standard offpage *
  page158_i68
#ISCELL
  standard offpage *
  page158_i69
#ISCELL
  standard offpage *
  page158_i70
#CELL
  pure_quanta q_res *
  page158_i71
#CELL
  pure_quanta q_res *
  page158_i72
#CELL
  pure_quanta q_res *
  page158_i73
#CELL
  pure_quanta q_res *
  page158_i74
#ISCELL
  standard offpage *
  page158_i75
#ISCELL
  standard offpage *
  page158_i76
#ISCELL
  standard offpage *
  page158_i77
#ISCELL
  standard offpage *
  page158_i78
#ISCELL
  standard offpage *
  page158_i83
#ISCELL
  standard offpage *
  page158_i84
#CELL
  pure_quanta q_cap_diffbus *
  page158_i85
#CELL
  pure_quanta q_cap_diffbus *
  page158_i86
#CELL
  pure_quanta q_cap_diffbus *
  page158_i87
#CELL
  pure_quanta q_cap_diffbus *
  page158_i88
#ISCELL
  standard offpage *
  page158_i89
#ISCELL
  standard offpage *
  page158_i90
#ISCELL
  standard offpage *
  page158_i95
#ISCELL
  standard offpage *
  page158_i96
#ISCELL
  standard offpage *
  page158_i97
#ISCELL
  standard offpage *
  page158_i98
#ISCELL
  pure_quanta quanta_title_block_c *
  *
#ISCELL
  mstr_misc dns *
  *
#ISCELL
  pure_quanta quanta_title_block_c *
  *
#ISCELL
  pure_quanta_power universal_gnd *
  page160_i1
#ISCELL
  standard offpage *
  page160_i10
#ISCELL
  standard offpage *
  page160_i11
#ISCELL
  standard offpage *
  page160_i12
#ISCELL
  standard offpage *
  page160_i13
#ISCELL
  pure_quanta_power universal_power *
  page160_i14
#ISCELL
  standard offpage *
  page160_i15
#ISCELL
  pure_quanta_power universal_gnd *
  page160_i16
#ISCELL
  pure_quanta_power universal_power *
  page160_i17
#CELL
  pure_quanta q_cap *
  page160_i18
#ISCELL
  pure_quanta_power universal_gnd *
  page160_i19
#CELL
  pure_quanta q_res *
  page160_i2
#CELL
  pure_quanta q_cap *
  page160_i20
#ISCELL
  pure_quanta_power universal_power *
  page160_i21
#ISCELL
  pure_quanta_power universal_power *
  page160_i22
#ISCELL
  pure_quanta_power universal_power *
  page160_i23
#CELL
  pure_quanta q_inductor *
  page160_i24
#ISCELL
  pure_quanta_power universal_power *
  page160_i25
#CELL
  pure_quanta q_inductor *
  page160_i26
#CELL
  pure_quanta q_res *
  page160_i27
#ISCELL
  pure_quanta_power universal_power *
  page160_i28
#CELL
  pure_quanta q_res *
  page160_i29
#CELL
  pure_quanta q_res *
  page160_i3
#ISCELL
  pure_quanta_power universal_gnd *
  page160_i30
#CELL
  pure_quanta q_res *
  page160_i31
#ISCELL
  standard offpage *
  page160_i32
#ISCELL
  pure_quanta_power universal_power *
  page160_i33
#ISCELL
  pure_quanta_power universal_gnd *
  page160_i34
#ISCELL
  standard offpage *
  page160_i4
#CELL
  pure_quanta q_cap *
  page160_i40
#CELL
  pure_quanta q_cap *
  page160_i41
#ISCELL
  pure_quanta_power universal_power *
  page160_i42
#ISCELL
  standard offpage *
  page160_i43
#CELL
  pure_quanta q_cap *
  page160_i44
#CELL
  pure_quanta q_cap *
  page160_i45
#ISCELL
  pure_quanta_power universal_gnd *
  page160_i46
#CELL
  pure_quanta q_cap *
  page160_i47
#ISCELL
  pure_quanta_power universal_power *
  page160_i48
#ISCELL
  standard offpage *
  page160_i49
#ISCELL
  standard offpage *
  page160_i50
#ISCELL
  standard offpage *
  page160_i51
#CELL
  pure_quanta q_res *
  page160_i52
#CELL
  pure_quanta q_res *
  page160_i53
#CELL
  pure_quanta q_res *
  page160_i55
#ISCELL
  standard offpage *
  page160_i58
#ISCELL
  standard offpage *
  page160_i59
#CELL
  pure_quanta q_res *
  page160_i6
#ISCELL
  standard offpage *
  page160_i60
#CELL
  pure_quanta 9zxl0451ekilft *
  page160_i63
#ISCELL
  standard offpage *
  page160_i64
#ISCELL
  standard offpage *
  page160_i65
#CELL
  pure_quanta q_res *
  page160_i68
#CELL
  pure_quanta q_cap *
  page160_i69
#CELL
  pure_quanta q_cap *
  page160_i70
#CELL
  pure_quanta q_cap *
  page160_i71
#ISCELL
  pure_quanta_power universal_gnd *
  page160_i72
#CELL
  pure_quanta q_res *
  page160_i73
#ISCELL
  pure_quanta_power universal_power *
  page160_i74
#ISCELL
  mstr_misc dns *
  *
#ISCELL
  pure_quanta quanta_title_block_c *
  *
#ISCELL
  pure_quanta_power universal_power *
  page379_i1
#ISCELL
  standard offpage *
  page379_i10
#ISCELL
  standard offpage *
  page379_i11
#ISCELL
  standard offpage *
  page379_i12
#ISCELL
  standard offpage *
  page379_i13
#ISCELL
  standard offpage *
  page379_i14
#CELL
  pure_quanta q_res *
  page379_i15
#ISCELL
  pure_quanta_power universal_gnd *
  page379_i16
#CELL
  pure_quanta q_res *
  page379_i17
#ISCELL
  pure_quanta_power universal_power *
  page379_i18
#CELL
  pure_quanta q_inductor *
  page379_i2
#CELL
  pure_quanta q_res *
  page379_i20
#CELL
  pure_quanta q_res *
  page379_i21
#ISCELL
  pure_quanta_power universal_gnd *
  page379_i23
#CELL
  pure_quanta q_cap *
  page379_i24
#ISCELL
  pure_quanta_power universal_gnd *
  page379_i25
#CELL
  pure_quanta q_cap *
  page379_i26
#ISCELL
  pure_quanta_power universal_power *
  page379_i27
#ISCELL
  pure_quanta_power universal_power *
  page379_i28
#ISCELL
  pure_quanta_power universal_power *
  page379_i29
#ISCELL
  pure_quanta_power universal_gnd *
  page379_i3
#ISCELL
  pure_quanta_power universal_power *
  page379_i30
#ISCELL
  pure_quanta_power universal_power *
  page379_i31
#CELL
  pure_quanta q_inductor *
  page379_i32
#CELL
  pure_quanta q_cap *
  page379_i34
#CELL
  pure_quanta q_cap *
  page379_i35
#CELL
  pure_quanta q_cap *
  page379_i36
#ISCELL
  standard offpage *
  page379_i37
#ISCELL
  pure_quanta_power universal_gnd *
  page379_i38
#CELL
  pure_quanta q_res *
  page379_i49
#CELL
  pure_quanta q_res *
  page379_i50
#CELL
  pure_quanta q_res *
  page379_i51
#ISCELL
  pure_quanta_power universal_power *
  page379_i56
#ISCELL
  standard offpage *
  page379_i57
#CELL
  pure_quanta q_cap *
  page379_i58
#ISCELL
  pure_quanta_power universal_gnd *
  page379_i59
#CELL
  pure_quanta q_cap *
  page379_i60
#ISCELL
  pure_quanta_power universal_power *
  page379_i61
#CELL
  pure_quanta 9zxl0451ekilft *
  page379_i63
#CELL
  pure_quanta q_res *
  page379_i64
#CELL
  pure_quanta q_res *
  page379_i65
#ISCELL
  standard offpage *
  page379_i66
#ISCELL
  standard offpage *
  page379_i67
#ISCELL
  standard offpage *
  page379_i68
#ISCELL
  standard offpage *
  page379_i69
#ISCELL
  pure_quanta_power universal_power *
  page379_i7
#ISCELL
  standard offpage *
  page379_i70
#ISCELL
  standard offpage *
  page379_i71
#ISCELL
  standard offpage *
  page379_i72
#ISCELL
  standard offpage *
  page379_i73
#CELL
  pure_quanta q_res *
  page379_i76
#CELL
  pure_quanta q_cap *
  page379_i77
#CELL
  pure_quanta q_cap *
  page379_i78
#CELL
  pure_quanta q_cap *
  page379_i79
#ISCELL
  pure_quanta_power universal_gnd *
  page379_i80
#CELL
  pure_quanta q_res *
  page379_i81
#ISCELL
  pure_quanta_power universal_power *
  page379_i82
#ISCELL
  standard offpage *
  page379_i9
#ISCELL
  mstr_misc dns *
  *
#ISCELL
  pure_quanta quanta_title_block_c *
  *
#CELL
  pure_quanta tca9548apwr *
  page378_i1
#ISCELL
  standard offpage *
  page378_i10
#CELL
  pure_quanta q_res *
  page378_i100
#ISCELL
  standard offpage *
  page378_i101
#ISCELL
  standard offpage *
  page378_i102
#ISCELL
  standard offpage *
  page378_i103
#CELL
  pure_quanta q_res *
  page378_i104
#ISCELL
  standard offpage *
  page378_i105
#ISCELL
  standard offpage *
  page378_i106
#CELL
  pure_quanta q_res *
  page378_i107
#ISCELL
  pure_quanta_power universal_gnd *
  page378_i108
#CELL
  pure_quanta q_res *
  page378_i11
#ISCELL
  standard offpage *
  page378_i111
#ISCELL
  standard offpage *
  page378_i112
#ISCELL
  pure_quanta_power p1v0_aux *
  page378_i113
#ISCELL
  pure_quanta_power universal_gnd *
  page378_i115
#CELL
  pure_quanta conn3_210hp1030br1 *
  page378_i116
#CELL
  pure_quanta q_res *
  page378_i117
#CELL
  pure_quanta q_res *
  page378_i118
#CELL
  pure_quanta q_res *
  page378_i119
#ISCELL
  standard offpage *
  page378_i12
#CELL
  pure_quanta q_res *
  page378_i120
#CELL
  pure_quanta q_res *
  page378_i13
#CELL
  pure_quanta q_res *
  page378_i14
#ISCELL
  standard offpage *
  page378_i15
#ISCELL
  standard offpage *
  page378_i16
#CELL
  pure_quanta q_res *
  page378_i17
#CELL
  pure_quanta q_res *
  page378_i18
#ISCELL
  standard offpage *
  page378_i19
#ISCELL
  standard offpage *
  page378_i20
#CELL
  pure_quanta q_res *
  page378_i21
#CELL
  pure_quanta q_res *
  page378_i22
#ISCELL
  standard offpage *
  page378_i23
#ISCELL
  standard offpage *
  page378_i24
#CELL
  pure_quanta q_res *
  page378_i25
#CELL
  pure_quanta q_res *
  page378_i26
#ISCELL
  standard offpage *
  page378_i27
#ISCELL
  standard offpage *
  page378_i28
#ISCELL
  standard offpage *
  page378_i29
#ISCELL
  standard offpage *
  page378_i30
#CELL
  pure_quanta q_res *
  page378_i31
#CELL
  pure_quanta q_res *
  page378_i32
#ISCELL
  standard offpage *
  page378_i33
#ISCELL
  standard offpage *
  page378_i34
#CELL
  pure_quanta q_res *
  page378_i35
#CELL
  pure_quanta q_res *
  page378_i36
#ISCELL
  standard offpage *
  page378_i4
#ISCELL
  standard offpage *
  page378_i5
#CELL
  pure_quanta q_res *
  page378_i53
#CELL
  pure_quanta q_res *
  page378_i54
#CELL
  pure_quanta q_res *
  page378_i55
#CELL
  pure_quanta q_res *
  page378_i56
#CELL
  pure_quanta q_res *
  page378_i57
#CELL
  pure_quanta q_res *
  page378_i58
#CELL
  pure_quanta q_res *
  page378_i59
#CELL
  pure_quanta q_res *
  page378_i6
#CELL
  pure_quanta q_res *
  page378_i60
#ISCELL
  standard offpage *
  page378_i61
#ISCELL
  standard offpage *
  page378_i62
#ISCELL
  standard offpage *
  page378_i63
#ISCELL
  standard offpage *
  page378_i64
#ISCELL
  standard offpage *
  page378_i65
#ISCELL
  standard offpage *
  page378_i66
#ISCELL
  standard offpage *
  page378_i67
#ISCELL
  standard offpage *
  page378_i68
#ISCELL
  standard offpage *
  page378_i69
#CELL
  pure_quanta q_res *
  page378_i7
#ISCELL
  standard offpage *
  page378_i70
#ISCELL
  standard offpage *
  page378_i71
#ISCELL
  standard offpage *
  page378_i72
#ISCELL
  standard offpage *
  page378_i73
#ISCELL
  standard offpage *
  page378_i74
#ISCELL
  standard offpage *
  page378_i75
#ISCELL
  standard offpage *
  page378_i76
#CELL
  pure_quanta q_res *
  page378_i77
#CELL
  pure_quanta q_res *
  page378_i78
#CELL
  pure_quanta q_res *
  page378_i79
#ISCELL
  pure_quanta_power p1v0 *
  page378_i8
#CELL
  pure_quanta q_res *
  page378_i80
#ISCELL
  pure_quanta_power p1v0 *
  page378_i81
#CELL
  pure_quanta q_res *
  page378_i82
#CELL
  pure_quanta q_res *
  page378_i83
#CELL
  pure_quanta q_res *
  page378_i84
#CELL
  pure_quanta q_res *
  page378_i85
#ISCELL
  pure_quanta_power universal_gnd *
  page378_i86
#ISCELL
  pure_quanta_power p1v0_aux *
  page378_i87
#CELL
  pure_quanta q_cap *
  page378_i88
#ISCELL
  pure_quanta_power universal_gnd *
  page378_i89
#CELL
  pure_quanta q_res *
  page378_i9
#ISCELL
  standard offpage *
  page378_i90
#ISCELL
  standard offpage *
  page378_i91
#ISCELL
  standard offpage *
  page378_i92
#ISCELL
  pure_quanta_power universal_gnd *
  page378_i93
#CELL
  pure_quanta q_res *
  page378_i94
#CELL
  pure_quanta q_res *
  page378_i95
#CELL
  pure_quanta q_res *
  page378_i96
#CELL
  pure_quanta q_res *
  page378_i97
#CELL
  pure_quanta q_res *
  page378_i98
#ISCELL
  mstr_misc dns *
  *
#ISCELL
  pure_quanta quanta_title_block_c *
  *
#ISCELL
  pure_quanta_power universal_gnd *
  page377_i1
#ISCELL
  standard offpage *
  page377_i10
#ISCELL
  standard offpage *
  page377_i100
#ISCELL
  standard offpage *
  page377_i101
#ISCELL
  standard offpage *
  page377_i102
#ISCELL
  standard offpage *
  page377_i103
#CELL
  pure_quanta q_res *
  page377_i104
#CELL
  pure_quanta q_res *
  page377_i105
#CELL
  pure_quanta q_res *
  page377_i106
#CELL
  pure_quanta q_res *
  page377_i107
#CELL
  pure_quanta q_res *
  page377_i108
#CELL
  pure_quanta q_res *
  page377_i109
#ISCELL
  standard offpage *
  page377_i11
#CELL
  pure_quanta q_res *
  page377_i110
#CELL
  pure_quanta q_res *
  page377_i111
#ISCELL
  pure_quanta_power p1v0 *
  page377_i112
#ISCELL
  standard offpage *
  page377_i113
#ISCELL
  standard offpage *
  page377_i114
#ISCELL
  standard offpage *
  page377_i115
#ISCELL
  standard offpage *
  page377_i116
#ISCELL
  standard offpage *
  page377_i117
#ISCELL
  standard offpage *
  page377_i118
#ISCELL
  standard offpage *
  page377_i119
#ISCELL
  standard offpage *
  page377_i12
#ISCELL
  standard offpage *
  page377_i120
#CELL
  pure_quanta q_res *
  page377_i121
#CELL
  pure_quanta q_res *
  page377_i122
#CELL
  pure_quanta q_res *
  page377_i123
#CELL
  pure_quanta q_res *
  page377_i124
#CELL
  pure_quanta q_res *
  page377_i125
#CELL
  pure_quanta q_res *
  page377_i126
#CELL
  pure_quanta q_res *
  page377_i127
#CELL
  pure_quanta q_res *
  page377_i128
#ISCELL
  pure_quanta_power p1v0 *
  page377_i129
#ISCELL
  pure_quanta_power p1v0 *
  page377_i13
#ISCELL
  standard offpage *
  page377_i131
#ISCELL
  standard offpage *
  page377_i132
#ISCELL
  standard offpage *
  page377_i134
#ISCELL
  standard offpage *
  page377_i135
#ISCELL
  standard offpage *
  page377_i136
#ISCELL
  standard offpage *
  page377_i137
#ISCELL
  standard offpage *
  page377_i138
#ISCELL
  standard offpage *
  page377_i139
#ISCELL
  standard offpage *
  page377_i14
#ISCELL
  standard offpage *
  page377_i140
#ISCELL
  standard offpage *
  page377_i141
#ISCELL
  pure_quanta_power p1v0 *
  page377_i148
#ISCELL
  standard offpage *
  page377_i149
#ISCELL
  pure_quanta_power universal_gnd *
  page377_i15
#ISCELL
  standard offpage *
  page377_i150
#ISCELL
  standard offpage *
  page377_i151
#ISCELL
  standard offpage *
  page377_i152
#ISCELL
  standard offpage *
  page377_i153
#ISCELL
  standard offpage *
  page377_i154
#CELL
  pure_quanta q_res *
  page377_i16
#ISCELL
  pure_quanta_power p1v0 *
  page377_i163
#CELL
  pure_quanta q_res *
  page377_i164
#CELL
  pure_quanta q_res *
  page377_i165
#CELL
  pure_quanta q_res *
  page377_i166
#CELL
  pure_quanta q_res *
  page377_i167
#CELL
  pure_quanta q_res *
  page377_i168
#CELL
  pure_quanta q_res *
  page377_i169
#CELL
  pure_quanta q_res *
  page377_i17
#CELL
  pure_quanta q_res *
  page377_i170
#CELL
  pure_quanta q_res *
  page377_i171
#CELL
  pure_quanta q_res *
  page377_i172
#CELL
  pure_quanta q_res *
  page377_i173
#CELL
  pure_quanta q_res *
  page377_i174
#CELL
  pure_quanta q_res *
  page377_i175
#CELL
  pure_quanta q_res *
  page377_i176
#CELL
  pure_quanta q_res *
  page377_i177
#CELL
  pure_quanta q_res *
  page377_i178
#CELL
  pure_quanta q_res *
  page377_i179
#CELL
  pure_quanta q_res *
  page377_i18
#CELL
  pure_quanta q_res *
  page377_i19
#CELL
  pure_quanta q_res *
  page377_i2
#CELL
  pure_quanta q_res *
  page377_i20
#CELL
  pure_quanta q_res *
  page377_i21
#CELL
  pure_quanta q_res *
  page377_i22
#CELL
  pure_quanta q_res *
  page377_i23
#CELL
  pure_quanta q_res *
  page377_i24
#ISCELL
  standard offpage *
  page377_i25
#ISCELL
  standard offpage *
  page377_i26
#ISCELL
  standard offpage *
  page377_i27
#ISCELL
  standard offpage *
  page377_i28
#ISCELL
  standard offpage *
  page377_i29
#CELL
  pure_quanta q_res *
  page377_i3
#ISCELL
  standard offpage *
  page377_i30
#ISCELL
  standard offpage *
  page377_i31
#ISCELL
  standard offpage *
  page377_i32
#ISCELL
  pure_quanta_power universal_gnd *
  page377_i33
#ISCELL
  standard offpage *
  page377_i34
#ISCELL
  standard offpage *
  page377_i35
#ISCELL
  standard offpage *
  page377_i36
#ISCELL
  standard offpage *
  page377_i37
#ISCELL
  standard offpage *
  page377_i38
#ISCELL
  standard offpage *
  page377_i39
#CELL
  pure_quanta q_res *
  page377_i4
#ISCELL
  standard offpage *
  page377_i40
#ISCELL
  standard offpage *
  page377_i41
#CELL
  pure_quanta q_res *
  page377_i42
#CELL
  pure_quanta q_res *
  page377_i43
#CELL
  pure_quanta q_res *
  page377_i44
#CELL
  pure_quanta q_res *
  page377_i45
#CELL
  pure_quanta q_res *
  page377_i46
#CELL
  pure_quanta q_res *
  page377_i47
#CELL
  pure_quanta q_res *
  page377_i48
#CELL
  pure_quanta q_res *
  page377_i49
#CELL
  pure_quanta q_res *
  page377_i5
#CELL
  pure_quanta q_res *
  page377_i50
#ISCELL
  standard offpage *
  page377_i51
#ISCELL
  standard offpage *
  page377_i52
#ISCELL
  standard offpage *
  page377_i53
#ISCELL
  pure_quanta_power universal_gnd *
  page377_i54
#CELL
  pure_quanta q_cap *
  page377_i55
#ISCELL
  pure_quanta_power p1v0_aux *
  page377_i56
#ISCELL
  pure_quanta_power p1v0 *
  page377_i57
#CELL
  pure_quanta q_res *
  page377_i58
#CELL
  pure_quanta q_res *
  page377_i59
#CELL
  pure_quanta q_res *
  page377_i60
#CELL
  pure_quanta q_res *
  page377_i61
#CELL
  pure_quanta q_res *
  page377_i62
#CELL
  pure_quanta q_res *
  page377_i63
#CELL
  pure_quanta q_res *
  page377_i64
#CELL
  pure_quanta q_res *
  page377_i65
#ISCELL
  standard offpage *
  page377_i66
#ISCELL
  standard offpage *
  page377_i67
#ISCELL
  standard offpage *
  page377_i68
#ISCELL
  standard offpage *
  page377_i69
#ISCELL
  standard offpage *
  page377_i7
#ISCELL
  standard offpage *
  page377_i70
#ISCELL
  standard offpage *
  page377_i71
#ISCELL
  standard offpage *
  page377_i72
#CELL
  pure_quanta q_res *
  page377_i73
#CELL
  pure_quanta q_res *
  page377_i74
#CELL
  pure_quanta q_res *
  page377_i75
#CELL
  pure_quanta q_res *
  page377_i76
#CELL
  pure_quanta q_res *
  page377_i77
#CELL
  pure_quanta q_res *
  page377_i78
#CELL
  pure_quanta q_res *
  page377_i79
#CELL
  pure_quanta q_res *
  page377_i8
#CELL
  pure_quanta q_res *
  page377_i80
#CELL
  pure_quanta q_res *
  page377_i81
#CELL
  pure_quanta q_res *
  page377_i82
#ISCELL
  standard offpage *
  page377_i83
#ISCELL
  standard offpage *
  page377_i84
#ISCELL
  standard offpage *
  page377_i85
#ISCELL
  standard offpage *
  page377_i86
#ISCELL
  standard offpage *
  page377_i87
#ISCELL
  standard offpage *
  page377_i88
#ISCELL
  standard offpage *
  page377_i89
#CELL
  pure_quanta q_res *
  page377_i9
#ISCELL
  standard offpage *
  page377_i90
#ISCELL
  standard offpage *
  page377_i91
#ISCELL
  standard offpage *
  page377_i92
#ISCELL
  standard offpage *
  page377_i93
#CELL
  pure_quanta tca9548apwr *
  page377_i94
#ISCELL
  pure_quanta_power p1v0_aux *
  page377_i95
#ISCELL
  standard offpage *
  page377_i96
#ISCELL
  standard offpage *
  page377_i97
#ISCELL
  standard offpage *
  page377_i98
#ISCELL
  standard offpage *
  page377_i99
#ISCELL
  pure_quanta quanta_title_block_c *
  *
#ISCELL
  pure_quanta_power universal_gnd *
  page376_i10
#ISCELL
  pure_quanta_power universal_power *
  page376_i100
#ISCELL
  standard offpage *
  page376_i101
#ISCELL
  standard offpage *
  page376_i102
#ISCELL
  pure_quanta_power universal_power *
  page376_i103
#ISCELL
  pure_quanta_power universal_gnd *
  page376_i104
#CELL
  pure_quanta q_cap *
  page376_i105
#ISCELL
  pure_quanta_power universal_gnd *
  page376_i106
#ISCELL
  pure_quanta_power universal_gnd *
  page376_i107
#CELL
  pure_quanta pi3csw12zuaex *
  page376_i108
#CELL
  pure_quanta q_res *
  page376_i109
#CELL
  pure_quanta q_res *
  page376_i110
#ISCELL
  standard offpage *
  page376_i111
#ISCELL
  standard offpage *
  page376_i112
#ISCELL
  standard offpage *
  page376_i113
#ISCELL
  standard offpage *
  page376_i114
#CELL
  pure_quanta q_res *
  page376_i115
#CELL
  pure_quanta q_res *
  page376_i116
#ISCELL
  standard offpage *
  page376_i117
#ISCELL
  standard offpage *
  page376_i118
#ISCELL
  standard offpage *
  page376_i119
#ISCELL
  standard offpage *
  page376_i120
#CELL
  pure_quanta pi3csw12zuaex *
  page376_i121
#CELL
  pure_quanta q_res *
  page376_i122
#CELL
  pure_quanta q_res *
  page376_i123
#ISCELL
  standard offpage *
  page376_i124
#ISCELL
  standard offpage *
  page376_i125
#ISCELL
  standard offpage *
  page376_i126
#ISCELL
  standard offpage *
  page376_i127
#ISCELL
  pure_quanta_power universal_gnd *
  page376_i128
#ISCELL
  standard offpage *
  page376_i129
#ISCELL
  standard offpage *
  page376_i13
#ISCELL
  pure_quanta_power universal_gnd *
  page376_i130
#ISCELL
  standard offpage *
  page376_i131
#ISCELL
  pure_quanta_power universal_gnd *
  page376_i132
#ISCELL
  standard offpage *
  page376_i133
#ISCELL
  pure_quanta_power universal_gnd *
  page376_i134
#ISCELL
  standard offpage *
  page376_i135
#ISCELL
  standard offpage *
  page376_i16
#ISCELL
  standard offpage *
  page376_i17
#ISCELL
  standard offpage *
  page376_i19
#ISCELL
  standard offpage *
  page376_i20
#CELL
  pure_quanta pi3csw12zuaex *
  page376_i22
#ISCELL
  pure_quanta_power universal_power *
  page376_i23
#CELL
  pure_quanta q_cap *
  page376_i24
#ISCELL
  pure_quanta_power universal_gnd *
  page376_i25
#ISCELL
  standard offpage *
  page376_i26
#ISCELL
  standard offpage *
  page376_i27
#CELL
  pure_quanta q_res *
  page376_i28
#ISCELL
  pure_quanta_power universal_gnd *
  page376_i29
#CELL
  pure_quanta q_res *
  page376_i30
#CELL
  pure_quanta pi3csw12zuaex *
  page376_i31
#ISCELL
  standard offpage *
  page376_i32
#ISCELL
  standard offpage *
  page376_i33
#ISCELL
  standard offpage *
  page376_i34
#ISCELL
  standard offpage *
  page376_i35
#ISCELL
  pure_quanta_power universal_gnd *
  page376_i36
#CELL
  pure_quanta q_cap *
  page376_i37
#ISCELL
  pure_quanta_power universal_power *
  page376_i38
#ISCELL
  pure_quanta_power universal_gnd *
  page376_i39
#CELL
  pure_quanta q_res *
  page376_i40
#CELL
  pure_quanta q_res *
  page376_i41
#ISCELL
  standard offpage *
  page376_i42
#ISCELL
  standard offpage *
  page376_i43
#ISCELL
  pure_quanta_power universal_gnd *
  page376_i44
#ISCELL
  standard offpage *
  page376_i45
#CELL
  pure_quanta pi3csw12zuaex *
  page376_i46
#ISCELL
  pure_quanta_power universal_power *
  page376_i47
#CELL
  pure_quanta q_cap *
  page376_i48
#ISCELL
  standard offpage *
  page376_i49
#ISCELL
  standard offpage *
  page376_i50
#ISCELL
  pure_quanta_power universal_gnd *
  page376_i51
#ISCELL
  pure_quanta_power universal_gnd *
  page376_i52
#CELL
  pure_quanta q_res *
  page376_i53
#CELL
  pure_quanta q_res *
  page376_i54
#ISCELL
  standard offpage *
  page376_i55
#ISCELL
  standard offpage *
  page376_i56
#ISCELL
  standard offpage *
  page376_i57
#ISCELL
  standard offpage *
  page376_i58
#ISCELL
  pure_quanta_power universal_gnd *
  page376_i59
#ISCELL
  standard offpage *
  page376_i60
#CELL
  pure_quanta pi3csw12zuaex *
  page376_i61
#ISCELL
  standard offpage *
  page376_i62
#ISCELL
  standard offpage *
  page376_i63
#ISCELL
  pure_quanta_power universal_gnd *
  page376_i64
#CELL
  pure_quanta q_cap *
  page376_i65
#ISCELL
  pure_quanta_power universal_power *
  page376_i66
#ISCELL
  pure_quanta_power universal_gnd *
  page376_i67
#CELL
  pure_quanta q_res *
  page376_i68
#CELL
  pure_quanta q_res *
  page376_i69
#ISCELL
  standard offpage *
  page376_i70
#ISCELL
  standard offpage *
  page376_i71
#ISCELL
  standard offpage *
  page376_i72
#ISCELL
  standard offpage *
  page376_i73
#ISCELL
  pure_quanta_power universal_gnd *
  page376_i74
#ISCELL
  standard offpage *
  page376_i75
#CELL
  pure_quanta pi3csw12zuaex *
  page376_i76
#ISCELL
  standard offpage *
  page376_i77
#ISCELL
  standard offpage *
  page376_i78
#ISCELL
  pure_quanta_power universal_gnd *
  page376_i79
#CELL
  pure_quanta q_cap *
  page376_i80
#ISCELL
  pure_quanta_power universal_power *
  page376_i81
#ISCELL
  pure_quanta_power universal_gnd *
  page376_i82
#ISCELL
  pure_quanta_power universal_power *
  page376_i83
#CELL
  pure_quanta q_cap *
  page376_i84
#CELL
  pure_quanta pi3csw12zuaex *
  page376_i85
#CELL
  pure_quanta q_res *
  page376_i86
#CELL
  pure_quanta q_res *
  page376_i87
#ISCELL
  standard offpage *
  page376_i88
#ISCELL
  standard offpage *
  page376_i89
#ISCELL
  standard offpage *
  page376_i90
#ISCELL
  standard offpage *
  page376_i91
#ISCELL
  standard offpage *
  page376_i92
#ISCELL
  standard offpage *
  page376_i93
#ISCELL
  standard offpage *
  page376_i94
#ISCELL
  standard offpage *
  page376_i95
#ISCELL
  pure_quanta_power universal_gnd *
  page376_i96
#ISCELL
  pure_quanta_power universal_gnd *
  page376_i97
#ISCELL
  pure_quanta_power universal_gnd *
  page376_i98
#CELL
  pure_quanta q_cap *
  page376_i99
#ISCELL
  mstr_misc dns *
  *
#ISCELL
  pure_quanta quanta_title_block_c *
  *
#CELL
  pure_quanta q_res *
  page156_i100
#CELL
  pure_quanta q_res *
  page156_i101
#ISCELL
  pure_quanta_power universal_power *
  page156_i102
#ISCELL
  pure_quanta_power universal_gnd *
  page156_i103
#CELL
  pure_quanta mosfet_dual_6p *
  page156_i104
#ISCELL
  pure_quanta_power universal_gnd *
  page156_i105
#ISCELL
  pure_quanta_power universal_gnd *
  page156_i106
#CELL
  pure_quanta q_cap *
  page156_i107
#CELL
  pure_quanta q_cap *
  page156_i108
#ISCELL
  standard offpage *
  page156_i109
#ISCELL
  pure_quanta_power universal_gnd *
  page156_i110
#ISCELL
  pure_quanta_power universal_gnd *
  page156_i112
#CELL
  pure_quanta q_cap *
  page156_i113
#ISCELL
  standard offpage *
  page156_i114
#ISCELL
  standard offpage *
  page156_i115
#CELL
  pure_quanta q_res *
  page156_i116
#ISCELL
  pure_quanta_power universal_gnd *
  page156_i117
#CELL
  pure_quanta q_cap *
  page156_i118
#ISCELL
  standard offpage *
  page156_i119
#CELL
  pure_quanta q_res *
  page156_i120
#ISCELL
  pure_quanta_power universal_power *
  page156_i121
#CELL
  pure_quanta q_res *
  page156_i122
#ISCELL
  pure_quanta_power universal_gnd *
  page156_i123
#ISCELL
  pure_quanta_power universal_gnd *
  page156_i124
#CELL
  pure_quanta q_cap *
  page156_i125
#CELL
  pure_quanta q_cap *
  page156_i126
#ISCELL
  pure_quanta_power universal_gnd *
  page156_i127
#CELL
  pure_quanta conn3_210hp1030br1 *
  page156_i128
#CELL
  pure_quanta q_res *
  page156_i129
#CELL
  pure_quanta ncp698sq15t1g *
  page156_i130
#CELL
  pure_quanta q_res *
  page156_i131
#ISCELL
  pure_quanta_power gnd *
  page156_i85
#CELL
  pure_quanta conn2_aaabat029y19 *
  page156_i86
#ISCELL
  pure_quanta_power universal_power *
  page156_i87
#ISCELL
  standard offpage *
  page156_i88
#ISCELL
  standard offpage *
  page156_i89
#ISCELL
  pure_quanta_power universal_gnd *
  page156_i90
#CELL
  pure_quanta tps71715dckr *
  page156_i91
#ISCELL
  standard offpage *
  page156_i92
#ISCELL
  pure_quanta_power universal_gnd *
  page156_i93
#CELL
  pure_quanta q_res *
  page156_i94
#CELL
  pure_quanta q_cap *
  page156_i95
#CELL
  pure_quanta q_res *
  page156_i97
#ISCELL
  standard offpage *
  page156_i98
#CELL
  pure_quanta schottky_dual_12a_3c *
  page156_i99
#ISCELL
  mstr_misc dns *
  *
#ISCELL
  pure_quanta quanta_title_block_c *
  *
#CELL
  pure_quanta q_res *
  page273_i10
#ISCELL
  pure_quanta_power p1v0_aux *
  page273_i100
#ISCELL
  pure_quanta_power universal_gnd *
  page273_i101
#CELL
  pure_quanta q_res *
  page273_i102
#ISCELL
  pure_quanta_power universal_gnd *
  page273_i103
#CELL
  pure_quanta q_res *
  page273_i104
#ISCELL
  pure_quanta_power p1v0_aux *
  page273_i105
#ISCELL
  standard offpage *
  page273_i106
#CELL
  pure_quanta mosfet_nch_dual *
  page273_i107
#CELL
  pure_quanta mosfet_nch_dual *
  page273_i108
#ISCELL
  pure_quanta_power universal_gnd *
  page273_i109
#ISCELL
  pure_quanta_power universal_power *
  page273_i11
#ISCELL
  pure_quanta_power universal_gnd *
  page273_i110
#CELL
  pure_quanta q_res *
  page273_i111
#ISCELL
  pure_quanta_power universal_power *
  page273_i112
#CELL
  pure_quanta q_res *
  page273_i113
#CELL
  pure_quanta q_res *
  page273_i114
#ISCELL
  pure_quanta_power universal_power *
  page273_i115
#CELL
  pure_quanta q_cap *
  page273_i116
#ISCELL
  pure_quanta_power universal_gnd *
  page273_i117
#ISCELL
  standard offpage *
  page273_i12
#CELL
  pure_quanta q_res *
  page273_i120
#ISCELL
  pure_quanta_power universal_power *
  page273_i121
#ISCELL
  pure_quanta_power universal_gnd *
  page273_i122
#CELL
  pure_quanta bss138dw7f *
  page273_i123
#ISCELL
  pure_quanta_power universal_gnd *
  page273_i124
#CELL
  pure_quanta q_res *
  page273_i125
#ISCELL
  pure_quanta_power p1v0_aux *
  page273_i126
#ISCELL
  standard offpage *
  page273_i127
#ISCELL
  pure_quanta_power universal_gnd *
  page273_i13
#CELL
  pure_quanta q_res *
  page273_i130
#CELL
  pure_quanta apx80929sag7 *
  page273_i131
#ISCELL
  pure_quanta_power universal_power *
  page273_i132
#CELL
  pure_quanta q_cap *
  page273_i133
#ISCELL
  pure_quanta_power universal_gnd *
  page273_i134
#ISCELL
  pure_quanta_power universal_gnd *
  page273_i135
#CELL
  pure_quanta q_res *
  page273_i136
#ISCELL
  pure_quanta_power universal_power *
  page273_i138
#CELL
  pure_quanta q_res *
  page273_i139
#CELL
  pure_quanta mosfet_nch_dual *
  page273_i14
#ISCELL
  pure_quanta_power universal_gnd *
  page273_i140
#CELL
  pure_quanta q_res *
  page273_i141
#CELL
  pure_quanta q_res *
  page273_i15
#ISCELL
  pure_quanta_power universal_power *
  page273_i16
#ISCELL
  pure_quanta_power universal_gnd *
  page273_i17
#CELL
  pure_quanta q_cap *
  page273_i18
#CELL
  pure_quanta q_cap *
  page273_i19
#CELL
  pure_quanta q_cap *
  page273_i20
#ISCELL
  pure_quanta_power p1v0_aux *
  page273_i21
#CELL
  pure_quanta q_res *
  page273_i22
#CELL
  pure_quanta mosfet_nch_1d3s *
  page273_i23
#ISCELL
  pure_quanta_power universal_power *
  page273_i26
#CELL
  pure_quanta bat547f *
  page273_i27
#ISCELL
  pure_quanta_power universal_power *
  page273_i28
#ISCELL
  standard offpage *
  page273_i3
#ISCELL
  pure_quanta_power universal_gnd *
  page273_i37
#CELL
  pure_quanta q_cap *
  page273_i38
#ISCELL
  standard offpage *
  page273_i39
#CELL
  pure_quanta q_res *
  page273_i4
#ISCELL
  pure_quanta_power universal_gnd *
  page273_i40
#CELL
  pure_quanta q_cap *
  page273_i41
#ISCELL
  pure_quanta_power universal_power *
  page273_i42
#CELL
  pure_quanta q_cap *
  page273_i43
#ISCELL
  pure_quanta_power universal_gnd *
  page273_i44
#CELL
  pure_quanta q_res *
  page273_i45
#ISCELL
  pure_quanta_power universal_gnd *
  page273_i46
#CELL
  pure_quanta q_cap *
  page273_i48
#CELL
  pure_quanta q_cap *
  page273_i49
#CELL
  pure_quanta mosfet_nch_1d3s *
  page273_i50
#CELL
  pure_quanta q_cap *
  page273_i51
#ISCELL
  pure_quanta_power p1v0_aux *
  page273_i52
#ISCELL
  pure_quanta_power universal_gnd *
  page273_i58
#CELL
  pure_quanta q_cap *
  page273_i59
#ISCELL
  pure_quanta_power universal_gnd *
  page273_i6
#ISCELL
  pure_quanta_power universal_power *
  page273_i60
#CELL
  pure_quanta q_cap *
  page273_i61
#CELL
  pure_quanta mosfet_nch_gds_esd_protected *
  page273_i62
#CELL
  pure_quanta q_res *
  page273_i7
#CELL
  pure_quanta q_res *
  page273_i74
#CELL
  pure_quanta q_res *
  page273_i75
#CELL
  pure_quanta q_res *
  page273_i76
#CELL
  pure_quanta rt9818c44gv *
  page273_i77
#ISCELL
  pure_quanta_power universal_power *
  page273_i78
#CELL
  pure_quanta q_cap *
  page273_i79
#ISCELL
  pure_quanta_power universal_gnd *
  page273_i8
#ISCELL
  pure_quanta_power universal_gnd *
  page273_i80
#ISCELL
  pure_quanta_power universal_gnd *
  page273_i81
#CELL
  pure_quanta q_res *
  page273_i83
#CELL
  pure_quanta q_res *
  page273_i84
#ISCELL
  pure_quanta_power universal_power *
  page273_i85
#ISCELL
  pure_quanta_power universal_gnd *
  page273_i86
#CELL
  pure_quanta q_res *
  page273_i88
#CELL
  pure_quanta mosfet_nch_dual *
  page273_i9
#ISCELL
  standard offpage *
  page273_i90
#CELL
  pure_quanta q_res *
  page273_i91
#ISCELL
  pure_quanta_power universal_gnd *
  page273_i92
#CELL
  pure_quanta q_res *
  page273_i93
#ISCELL
  pure_quanta_power p1v0_aux *
  page273_i94
#CELL
  pure_quanta q_res *
  page273_i95
#CELL
  pure_quanta q_res *
  page273_i96
#CELL
  pure_quanta mosfet_nch_dual *
  page273_i97
#CELL
  pure_quanta mosfet_nch_dual *
  page273_i98
#CELL
  pure_quanta q_res *
  page273_i99
#ISCELL
  pure_quanta quanta_title_block_c *
  *
#ISCELL
  pure_quanta_power gnd *
  page244_i1
#CELL
  pure_quanta q_cap *
  page244_i10
#CELL
  pure_quanta q_cap *
  page244_i11
#CELL
  pure_quanta q_cap *
  page244_i13
#ISCELL
  pure_quanta_power gnd *
  page244_i14
#CELL
  pure_quanta q_res *
  page244_i15
#ISCELL
  pure_quanta_power gnd *
  page244_i16
#ISCELL
  pure_quanta_power gnd *
  page244_i17
#ISCELL
  pure_quanta_power gnd *
  page244_i18
#CELL
  pure_quanta q_cap *
  page244_i19
#CELL
  pure_quanta q_cap *
  page244_i2
#CELL
  pure_quanta q_cap *
  page244_i20
#ISCELL
  pure_quanta_power gnd *
  page244_i21
#ISCELL
  pure_quanta_power gnd *
  page244_i22
#CELL
  pure_quanta q_res *
  page244_i23
#CELL
  pure_quanta q_cap *
  page244_i24
#CELL
  pure_quanta q_res *
  page244_i25
#CELL
  pure_quanta q_res *
  page244_i26
#CELL
  pure_quanta q_res *
  page244_i27
#CELL
  pure_quanta q_inductor *
  page244_i28
#ISCELL
  standard offpage *
  page244_i29
#ISCELL
  pure_quanta_power p1v0_aux *
  page244_i3
#CELL
  pure_quanta q_capp *
  page244_i30
#CELL
  pure_quanta q_cap *
  page244_i31
#CELL
  pure_quanta q_cap *
  page244_i32
#ISCELL
  pure_quanta_power gnd *
  page244_i33
#CELL
  pure_quanta q_cap *
  page244_i34
#ISCELL
  pure_quanta_power universal_power *
  page244_i35
#ISCELL
  pure_quanta_power p1v0 *
  page244_i36
#CELL
  pure_quanta q_res *
  page244_i37
#CELL
  pure_quanta mpq8633aglec807z *
  page244_i38
#ISCELL
  standard offpage *
  page244_i39
#ISCELL
  pure_quanta_power gnd *
  page244_i4
#CELL
  pure_quanta q_res *
  page244_i40
#CELL
  pure_quanta q_inductor *
  page244_i5
#ISCELL
  pure_quanta_power gnd *
  page244_i6
#CELL
  pure_quanta q_cap *
  page244_i7
#CELL
  pure_quanta q_cap *
  page244_i8
#ISCELL
  pure_quanta_power universal_power *
  page244_i9
#ISCELL
  mstr_misc dns *
  *
#ISCELL
  pure_quanta quanta_title_block_c *
  *
#ISCELL
  pure_quanta_power gnd *
  page245_i1
#CELL
  pure_quanta q_res *
  page245_i10
#CELL
  pure_quanta q_res *
  page245_i11
#CELL
  pure_quanta q_cap *
  page245_i12
#ISCELL
  pure_quanta_power gnd *
  page245_i13
#ISCELL
  pure_quanta_power gnd *
  page245_i14
#CELL
  pure_quanta q_res *
  page245_i15
#ISCELL
  pure_quanta_power gnd *
  page245_i16
#CELL
  pure_quanta q_res *
  page245_i17
#ISCELL
  pure_quanta_power gnd *
  page245_i18
#CELL
  pure_quanta q_cap *
  page245_i19
#CELL
  pure_quanta q_res *
  page245_i2
#CELL
  pure_quanta q_res *
  page245_i20
#CELL
  pure_quanta ncp3284amntxg *
  page245_i21
#ISCELL
  pure_quanta_power gnd *
  page245_i22
#CELL
  pure_quanta q_cap *
  page245_i23
#CELL
  pure_quanta q_inductor *
  page245_i24
#ISCELL
  pure_quanta_power universal_power *
  page245_i25
#CELL
  pure_quanta q_cap *
  page245_i26
#CELL
  pure_quanta q_cap *
  page245_i27
#ISCELL
  pure_quanta_power gnd *
  page245_i28
#CELL
  pure_quanta q_capp *
  page245_i29
#ISCELL
  pure_quanta_power gnd *
  page245_i3
#CELL
  pure_quanta q_capp *
  page245_i30
#CELL
  pure_quanta q_cap *
  page245_i31
#CELL
  pure_quanta q_cap *
  page245_i32
#CELL
  pure_quanta q_cap *
  page245_i33
#CELL
  pure_quanta q_cap *
  page245_i34
#CELL
  pure_quanta q_cap *
  page245_i35
#CELL
  pure_quanta q_cap *
  page245_i36
#CELL
  pure_quanta q_cap *
  page245_i37
#CELL
  pure_quanta q_cap *
  page245_i38
#CELL
  pure_quanta q_cap *
  page245_i39
#CELL
  pure_quanta q_res *
  page245_i4
#CELL
  pure_quanta q_cap *
  page245_i40
#CELL
  pure_quanta q_cap *
  page245_i41
#ISCELL
  pure_quanta_power universal_power *
  page245_i42
#ISCELL
  pure_quanta_power gnd *
  page245_i43
#CELL
  pure_quanta q_cap *
  page245_i44
#ISCELL
  pure_quanta_power gnd *
  page245_i45
#CELL
  pure_quanta q_res *
  page245_i46
#ISCELL
  pure_quanta_power gnd *
  page245_i47
#CELL
  pure_quanta q_cap *
  page245_i48
#CELL
  pure_quanta q_res *
  page245_i49
#ISCELL
  standard offpage *
  page245_i5
#ISCELL
  pure_quanta_power gnd *
  page245_i50
#CELL
  pure_quanta q_res *
  page245_i51
#ISCELL
  pure_quanta_power universal_power *
  page245_i52
#CELL
  pure_quanta q_cap *
  page245_i53
#CELL
  pure_quanta q_res *
  page245_i54
#CELL
  pure_quanta q_inductor *
  page245_i55
#ISCELL
  standard offpage *
  page245_i56
#CELL
  pure_quanta q_capp *
  page245_i57
#CELL
  pure_quanta q_capp *
  page245_i58
#CELL
  pure_quanta q_cap *
  page245_i59
#ISCELL
  pure_quanta_power p1v0_aux *
  page245_i6
#CELL
  pure_quanta q_cap *
  page245_i60
#ISCELL
  pure_quanta_power gnd *
  page245_i61
#CELL
  pure_quanta q_cap *
  page245_i62
#CELL
  pure_quanta q_cap *
  page245_i63
#ISCELL
  pure_quanta_power universal_power *
  page245_i64
#CELL
  pure_quanta q_res *
  page245_i65
#ISCELL
  pure_quanta_power universal_power *
  page245_i66
#CELL
  pure_quanta q_res *
  page245_i67
#CELL
  pure_quanta q_cap *
  page245_i68
#ISCELL
  pure_quanta_power gnd *
  page245_i69
#ISCELL
  pure_quanta_power gnd *
  page245_i7
#CELL
  pure_quanta q_cap *
  page245_i70
#CELL
  pure_quanta q_cap *
  page245_i71
#CELL
  pure_quanta q_cap *
  page245_i8
#ISCELL
  pure_quanta_power gnd *
  page245_i9
#ISCELL
  pure_quanta quanta_title_block_c *
  *
#ISCELL
  mstr_misc dns *
  *
#ISCELL
  pure_quanta quanta_title_block_c *
  *
#ISCELL
  pure_quanta_power universal_gnd *
  page167_i1
#CELL
  pure_quanta q_inductor *
  page167_i10
#ISCELL
  pure_quanta_power universal_gnd *
  page167_i11
#CELL
  pure_quanta q_cap *
  page167_i12
#CELL
  pure_quanta q_cap *
  page167_i13
#ISCELL
  pure_quanta_power universal_gnd *
  page167_i14
#CELL
  pure_quanta q_res *
  page167_i15
#ISCELL
  pure_quanta_power universal_gnd *
  page167_i16
#CELL
  pure_quanta q_res *
  page167_i17
#ISCELL
  pure_quanta_power universal_gnd *
  page167_i18
#CELL
  pure_quanta q_cap *
  page167_i19
#CELL
  pure_quanta q_cap *
  page167_i2
#ISCELL
  pure_quanta_power universal_gnd *
  page167_i20
#ISCELL
  pure_quanta_power universal_gnd *
  page167_i21
#ISCELL
  pure_quanta_power universal_gnd *
  page167_i22
#CELL
  pure_quanta q_res *
  page167_i23
#CELL
  pure_quanta q_cap *
  page167_i24
#CELL
  pure_quanta q_res *
  page167_i25
#CELL
  pure_quanta q_cap *
  page167_i27
#CELL
  pure_quanta q_cap *
  page167_i28
#CELL
  pure_quanta q_cap *
  page167_i29
#ISCELL
  standard offpage *
  page167_i3
#CELL
  pure_quanta q_cap *
  page167_i30
#CELL
  pure_quanta q_res *
  page167_i31
#ISCELL
  pure_quanta_power universal_power *
  page167_i32
#CELL
  pure_quanta q_res *
  page167_i33
#ISCELL
  pure_quanta_power universal_gnd *
  page167_i34
#CELL
  pure_quanta q_cap *
  page167_i35
#CELL
  pure_quanta q_cap *
  page167_i36
#CELL
  pure_quanta q_cap *
  page167_i37
#ISCELL
  pure_quanta_power universal_power *
  page167_i38
#ISCELL
  standard offpage *
  page167_i39
#ISCELL
  pure_quanta_power universal_power *
  page167_i4
#CELL
  pure_quanta q_cap *
  page167_i40
#CELL
  pure_quanta mpq8633aglec807z *
  page167_i41
#ISCELL
  pure_quanta_power universal_gnd *
  page167_i42
#CELL
  pure_quanta q_cap *
  page167_i43
#CELL
  pure_quanta q_cap *
  page167_i44
#CELL
  pure_quanta q_cap *
  page167_i45
#CELL
  pure_quanta q_res *
  page167_i46
#CELL
  pure_quanta q_inductor *
  page167_i47
#CELL
  pure_quanta q_cap *
  page167_i5
#ISCELL
  pure_quanta_power universal_gnd *
  page167_i6
#ISCELL
  pure_quanta_power universal_gnd *
  page167_i7
#CELL
  pure_quanta q_cap *
  page167_i8
#ISCELL
  pure_quanta_power universal_power *
  page167_i9
#ISCELL
  mstr_misc dns *
  *
#ISCELL
  pure_quanta quanta_title_block_c *
  *
#ISCELL
  standard offpage *
  page168_i1
#CELL
  pure_quanta q_res *
  page168_i10
#ISCELL
  standard offpage *
  page168_i100
#ISCELL
  standard offpage *
  page168_i101
#ISCELL
  standard offpage *
  page168_i102
#ISCELL
  standard offpage *
  page168_i103
#ISCELL
  standard offpage *
  page168_i104
#ISCELL
  standard offpage *
  page168_i105
#ISCELL
  pure_quanta_power universal_gnd *
  page168_i106
#CELL
  pure_quanta q_res *
  page168_i107
#CELL
  pure_quanta q_res *
  page168_i108
#ISCELL
  pure_quanta_power universal_gnd *
  page168_i109
#ISCELL
  pure_quanta_power vcc_core *
  page168_i11
#ISCELL
  pure_quanta_power universal_gnd *
  page168_i110
#CELL
  pure_quanta q_res *
  page168_i111
#ISCELL
  standard offpage *
  page168_i112
#ISCELL
  standard offpage *
  page168_i113
#ISCELL
  standard offpage *
  page168_i114
#ISCELL
  standard offpage *
  page168_i115
#ISCELL
  standard offpage *
  page168_i116
#ISCELL
  pure_quanta_power universal_gnd *
  page168_i117
#CELL
  pure_quanta q_cap *
  page168_i118
#ISCELL
  pure_quanta_power universal_gnd *
  page168_i119
#ISCELL
  pure_quanta_power universal_gnd *
  page168_i12
#CELL
  pure_quanta q_cap *
  page168_i120
#ISCELL
  standard offpage *
  page168_i121
#ISCELL
  standard offpage *
  page168_i122
#ISCELL
  standard offpage *
  page168_i123
#ISCELL
  standard offpage *
  page168_i124
#ISCELL
  standard offpage *
  page168_i125
#ISCELL
  standard offpage *
  page168_i126
#ISCELL
  standard offpage *
  page168_i127
#ISCELL
  pure_quanta_power universal_gnd *
  page168_i128
#CELL
  pure_quanta q_cap *
  page168_i129
#CELL
  pure_quanta q_cap *
  page168_i13
#ISCELL
  pure_quanta_power universal_gnd *
  page168_i130
#CELL
  pure_quanta q_cap *
  page168_i131
#ISCELL
  standard offpage *
  page168_i132
#CELL
  pure_quanta q_res *
  page168_i133
#ISCELL
  pure_quanta_power vcc_core *
  page168_i134
#CELL
  pure_quanta raa229620gnpha0 *
  page168_i135
#CELL
  pure_quanta q_res *
  page168_i136
#ISCELL
  pure_quanta_power universal_gnd *
  page168_i137
#CELL
  pure_quanta q_cap *
  page168_i138
#CELL
  pure_quanta q_cap *
  page168_i139
#ISCELL
  pure_quanta_power vcc_core *
  page168_i14
#ISCELL
  pure_quanta_power universal_gnd *
  page168_i140
#ISCELL
  pure_quanta_power universal_gnd *
  page168_i141
#CELL
  pure_quanta q_cap *
  page168_i142
#CELL
  pure_quanta conn3_210hp1030br1 *
  page168_i143
#ISCELL
  standard offpage *
  page168_i144
#ISCELL
  pure_quanta_power universal_gnd *
  page168_i145
#ISCELL
  standard offpage *
  page168_i146
#CELL
  pure_quanta q_res *
  page168_i147
#CELL
  pure_quanta q_res *
  page168_i148
#CELL
  pure_quanta q_res *
  page168_i15
#ISCELL
  standard offpage *
  page168_i16
#CELL
  pure_quanta mosfet_n *
  page168_i17
#CELL
  pure_quanta q_res *
  page168_i18
#CELL
  pure_quanta mosfet_pch_gds_esd_protected *
  page168_i19
#CELL
  pure_quanta q_res *
  page168_i2
#ISCELL
  pure_quanta_power universal_gnd *
  page168_i20
#CELL
  pure_quanta q_res *
  page168_i21
#ISCELL
  pure_quanta_power universal_gnd *
  page168_i22
#CELL
  pure_quanta q_cap *
  page168_i23
#CELL
  pure_quanta q_res *
  page168_i24
#ISCELL
  pure_quanta_power vcc_core *
  page168_i25
#ISCELL
  pure_quanta_power universal_gnd *
  page168_i26
#CELL
  pure_quanta q_res *
  page168_i27
#CELL
  pure_quanta q_res *
  page168_i28
#ISCELL
  pure_quanta_power vcc_core *
  page168_i29
#ISCELL
  pure_quanta_power universal_gnd *
  page168_i3
#ISCELL
  pure_quanta_power vcc_core *
  page168_i30
#ISCELL
  pure_quanta_power vcc_core *
  page168_i31
#ISCELL
  standard offpage *
  page168_i32
#ISCELL
  standard offpage *
  page168_i33
#ISCELL
  standard offpage *
  page168_i34
#ISCELL
  standard offpage *
  page168_i35
#CELL
  pure_quanta q_res *
  page168_i36
#ISCELL
  pure_quanta_power universal_gnd *
  page168_i37
#ISCELL
  standard offpage *
  page168_i38
#ISCELL
  standard offpage *
  page168_i39
#CELL
  pure_quanta q_res *
  page168_i4
#CELL
  pure_quanta q_res *
  page168_i40
#ISCELL
  pure_quanta_power vcc_core *
  page168_i41
#CELL
  pure_quanta q_res *
  page168_i42
#ISCELL
  pure_quanta_power vcc_core *
  page168_i43
#CELL
  pure_quanta q_res *
  page168_i44
#ISCELL
  pure_quanta_power universal_gnd *
  page168_i45
#ISCELL
  pure_quanta_power universal_gnd *
  page168_i46
#CELL
  pure_quanta q_res *
  page168_i47
#CELL
  pure_quanta q_res *
  page168_i48
#ISCELL
  pure_quanta_power universal_gnd *
  page168_i49
#ISCELL
  pure_quanta_power universal_gnd *
  page168_i5
#CELL
  pure_quanta q_cap *
  page168_i50
#CELL
  pure_quanta q_cap *
  page168_i51
#CELL
  pure_quanta q_cap *
  page168_i52
#ISCELL
  pure_quanta_power universal_gnd *
  page168_i53
#CELL
  pure_quanta q_res *
  page168_i54
#ISCELL
  pure_quanta_power universal_gnd *
  page168_i55
#ISCELL
  pure_quanta_power universal_gnd *
  page168_i56
#CELL
  pure_quanta q_res *
  page168_i57
#CELL
  pure_quanta q_res *
  page168_i58
#CELL
  pure_quanta q_res *
  page168_i59
#CELL
  pure_quanta q_res *
  page168_i6
#CELL
  pure_quanta q_cap *
  page168_i60
#CELL
  pure_quanta q_res *
  page168_i61
#CELL
  pure_quanta q_cap *
  page168_i62
#ISCELL
  pure_quanta_power universal_gnd *
  page168_i63
#CELL
  pure_quanta q_cap *
  page168_i64
#ISCELL
  pure_quanta_power universal_gnd *
  page168_i65
#CELL
  pure_quanta q_cap *
  page168_i66
#ISCELL
  pure_quanta_power universal_gnd *
  page168_i67
#CELL
  pure_quanta q_cap *
  page168_i68
#CELL
  pure_quanta q_res *
  page168_i69
#ISCELL
  standard offpage *
  page168_i7
#CELL
  pure_quanta q_res *
  page168_i70
#CELL
  pure_quanta q_res *
  page168_i71
#CELL
  pure_quanta q_res *
  page168_i72
#ISCELL
  pure_quanta_power vcc_core *
  page168_i73
#ISCELL
  standard offpage *
  page168_i74
#ISCELL
  standard offpage *
  page168_i75
#ISCELL
  standard offpage *
  page168_i76
#ISCELL
  standard offpage *
  page168_i79
#ISCELL
  standard offpage *
  page168_i8
#ISCELL
  standard offpage *
  page168_i80
#ISCELL
  pure_quanta_power vcc_core *
  page168_i81
#CELL
  pure_quanta q_res *
  page168_i82
#CELL
  pure_quanta q_res *
  page168_i83
#CELL
  pure_quanta q_res *
  page168_i84
#CELL
  pure_quanta q_res *
  page168_i85
#CELL
  pure_quanta q_res *
  page168_i86
#CELL
  pure_quanta q_res *
  page168_i87
#CELL
  pure_quanta q_res *
  page168_i88
#CELL
  pure_quanta q_res *
  page168_i89
#ISCELL
  standard offpage *
  page168_i9
#CELL
  pure_quanta q_cap *
  page168_i90
#ISCELL
  pure_quanta_power universal_gnd *
  page168_i91
#CELL
  pure_quanta q_cap *
  page168_i92
#ISCELL
  pure_quanta_power universal_gnd *
  page168_i93
#ISCELL
  pure_quanta_power universal_gnd *
  page168_i94
#CELL
  pure_quanta q_cap *
  page168_i95
#ISCELL
  standard offpage *
  page168_i96
#ISCELL
  pure_quanta_power universal_gnd *
  page168_i97
#CELL
  pure_quanta q_cap *
  page168_i98
#ISCELL
  standard offpage *
  page168_i99
#ISCELL
  mstr_misc dns *
  *
#ISCELL
  pure_quanta quanta_title_block_c *
  *
#ISCELL
  standard offpage *
  page169_i1
#CELL
  pure_quanta q_res *
  page169_i10
#ISCELL
  standard offpage *
  page169_i11
#ISCELL
  standard offpage *
  page169_i12
#ISCELL
  standard offpage *
  page169_i13
#CELL
  pure_quanta q_cap *
  page169_i14
#ISCELL
  pure_quanta_power universal_gnd *
  page169_i15
#CELL
  pure_quanta isl99390frztr5935 *
  page169_i16
#CELL
  pure_quanta q_res *
  page169_i17
#ISCELL
  pure_quanta_power universal_gnd *
  page169_i18
#CELL
  pure_quanta q_cap *
  page169_i19
#ISCELL
  standard offpage *
  page169_i2
#ISCELL
  pure_quanta_power vcc_core *
  page169_i20
#ISCELL
  pure_quanta_power universal_gnd *
  page169_i21
#CELL
  pure_quanta q_cap *
  page169_i22
#ISCELL
  standard offpage *
  page169_i23
#ISCELL
  pure_quanta_power universal_gnd *
  page169_i24
#ISCELL
  standard offpage *
  page169_i25
#CELL
  pure_quanta isl99390frztr5935 *
  page169_i26
#ISCELL
  pure_quanta_power universal_gnd *
  page169_i27
#CELL
  pure_quanta q_res *
  page169_i28
#ISCELL
  pure_quanta_power universal_gnd *
  page169_i29
#CELL
  pure_quanta q_res *
  page169_i3
#CELL
  pure_quanta q_res *
  page169_i30
#CELL
  pure_quanta q_cap *
  page169_i31
#CELL
  pure_quanta q_res *
  page169_i32
#CELL
  pure_quanta q_cap *
  page169_i33
#CELL
  pure_quanta q_cap *
  page169_i34
#ISCELL
  pure_quanta_power universal_gnd *
  page169_i35
#CELL
  pure_quanta q_cap *
  page169_i36
#CELL
  pure_quanta q_cap *
  page169_i37
#ISCELL
  pure_quanta_power universal_gnd *
  page169_i38
#CELL
  pure_quanta q_cap *
  page169_i39
#CELL
  pure_quanta q_res *
  page169_i4
#ISCELL
  pure_quanta_power vcc_core *
  page169_i40
#ISCELL
  pure_quanta_power universal_gnd *
  page169_i41
#CELL
  pure_quanta q_res *
  page169_i42
#CELL
  pure_quanta q_res *
  page169_i43
#ISCELL
  pure_quanta_power universal_gnd *
  page169_i44
#CELL
  pure_quanta q_cap *
  page169_i45
#CELL
  pure_quanta q_res *
  page169_i46
#ISCELL
  standard offpage *
  page169_i47
#ISCELL
  pure_quanta_power universal_gnd *
  page169_i48
#CELL
  pure_quanta q_res *
  page169_i49
#ISCELL
  pure_quanta_power vcc_core *
  page169_i5
#ISCELL
  pure_quanta_power vcc_core *
  page169_i50
#CELL
  pure_quanta q_cap *
  page169_i51
#CELL
  pure_quanta q_cap *
  page169_i52
#CELL
  pure_quanta q_cap *
  page169_i53
#CELL
  pure_quanta q_cap *
  page169_i54
#CELL
  pure_quanta q_res *
  page169_i55
#ISCELL
  standard offpage *
  page169_i56
#CELL
  pure_quanta q_cap *
  page169_i57
#CELL
  pure_quanta q_cap *
  page169_i58
#CELL
  pure_quanta q_cap *
  page169_i59
#ISCELL
  pure_quanta_power vcc_core *
  page169_i6
#ISCELL
  standard offpage *
  page169_i60
#CELL
  pure_quanta q_cap *
  page169_i61
#CELL
  pure_quanta q_inductor4p_14 *
  page169_i62
#ISCELL
  standard offpage *
  page169_i63
#CELL
  pure_quanta q_capp *
  page169_i64
#CELL
  pure_quanta q_capp *
  page169_i65
#CELL
  pure_quanta q_capp *
  page169_i66
#CELL
  pure_quanta q_capp *
  page169_i67
#CELL
  pure_quanta q_cap *
  page169_i68
#ISCELL
  pure_quanta_power universal_gnd *
  page169_i69
#ISCELL
  pure_quanta_power universal_gnd *
  page169_i7
#CELL
  pure_quanta q_cap *
  page169_i70
#ISCELL
  pure_quanta_power vcc_core *
  page169_i71
#ISCELL
  pure_quanta_power universal_gnd *
  page169_i72
#CELL
  pure_quanta q_capp *
  page169_i73
#ISCELL
  pure_quanta_power vcc_core *
  page169_i74
#ISCELL
  pure_quanta_power universal_gnd *
  page169_i75
#CELL
  pure_quanta q_cap *
  page169_i76
#CELL
  pure_quanta q_inductor4p_14 *
  page169_i77
#ISCELL
  pure_quanta_power universal_gnd *
  page169_i78
#CELL
  pure_quanta q_capp *
  page169_i79
#CELL
  pure_quanta q_cap *
  page169_i8
#ISCELL
  pure_quanta_power vcc_core *
  page169_i80
#CELL
  pure_quanta q_capp *
  page169_i81
#CELL
  pure_quanta q_inductor *
  page169_i82
#ISCELL
  pure_quanta_power universal_gnd *
  page169_i83
#ISCELL
  standard offpage *
  page169_i84
#CELL
  pure_quanta q_cap *
  page169_i85
#ISCELL
  pure_quanta_power vcc_core *
  page169_i86
#CELL
  pure_quanta q_cap *
  page169_i87
#CELL
  pure_quanta q_cap *
  page169_i88
#CELL
  pure_quanta q_cap *
  page169_i89
#ISCELL
  pure_quanta_power universal_gnd *
  page169_i9
#CELL
  pure_quanta q_res *
  page169_i90
#ISCELL
  pure_quanta_power vcc_core *
  page169_i91
#ISCELL
  mstr_misc dns *
  *
#ISCELL
  pure_quanta quanta_title_block_c *
  *
#ISCELL
  standard offpage *
  page170_i1
#ISCELL
  standard offpage *
  page170_i10
#CELL
  pure_quanta q_res *
  page170_i11
#CELL
  pure_quanta q_res *
  page170_i12
#ISCELL
  pure_quanta_power vcc_core *
  page170_i13
#ISCELL
  pure_quanta_power universal_gnd *
  page170_i14
#CELL
  pure_quanta q_cap *
  page170_i15
#ISCELL
  pure_quanta_power universal_gnd *
  page170_i16
#ISCELL
  pure_quanta_power universal_gnd *
  page170_i17
#CELL
  pure_quanta q_res *
  page170_i18
#CELL
  pure_quanta q_cap *
  page170_i19
#CELL
  pure_quanta q_cap *
  page170_i2
#CELL
  pure_quanta q_res *
  page170_i20
#CELL
  pure_quanta q_cap *
  page170_i21
#CELL
  pure_quanta q_cap *
  page170_i22
#CELL
  pure_quanta q_cap *
  page170_i23
#CELL
  pure_quanta q_cap *
  page170_i24
#ISCELL
  pure_quanta_power universal_gnd *
  page170_i25
#CELL
  pure_quanta q_res *
  page170_i26
#CELL
  pure_quanta q_cap *
  page170_i27
#ISCELL
  pure_quanta_power universal_gnd *
  page170_i28
#ISCELL
  standard offpage *
  page170_i29
#ISCELL
  pure_quanta_power universal_gnd *
  page170_i3
#ISCELL
  pure_quanta_power universal_gnd *
  page170_i30
#ISCELL
  standard offpage *
  page170_i31
#ISCELL
  standard offpage *
  page170_i32
#CELL
  pure_quanta q_res *
  page170_i33
#ISCELL
  pure_quanta_power universal_gnd *
  page170_i34
#ISCELL
  standard offpage *
  page170_i35
#CELL
  pure_quanta q_cap *
  page170_i36
#CELL
  pure_quanta q_res *
  page170_i37
#CELL
  pure_quanta isl99390frztr5935 *
  page170_i38
#ISCELL
  pure_quanta_power universal_gnd *
  page170_i39
#ISCELL
  pure_quanta_power universal_gnd *
  page170_i4
#CELL
  pure_quanta q_cap *
  page170_i40
#ISCELL
  pure_quanta_power vcc_core *
  page170_i41
#ISCELL
  pure_quanta_power universal_gnd *
  page170_i42
#CELL
  pure_quanta q_cap *
  page170_i43
#CELL
  pure_quanta q_res *
  page170_i44
#CELL
  pure_quanta q_cap *
  page170_i45
#CELL
  pure_quanta q_res *
  page170_i46
#CELL
  pure_quanta q_cap *
  page170_i47
#CELL
  pure_quanta q_cap *
  page170_i48
#CELL
  pure_quanta q_cap *
  page170_i49
#ISCELL
  pure_quanta_power universal_gnd *
  page170_i5
#CELL
  pure_quanta q_res *
  page170_i50
#ISCELL
  standard offpage *
  page170_i51
#CELL
  pure_quanta q_inductor4p_14 *
  page170_i52
#CELL
  pure_quanta q_cap *
  page170_i53
#ISCELL
  pure_quanta_power universal_gnd *
  page170_i54
#CELL
  pure_quanta q_cap *
  page170_i55
#ISCELL
  pure_quanta_power vcc_core *
  page170_i56
#ISCELL
  pure_quanta_power universal_gnd *
  page170_i57
#CELL
  pure_quanta q_cap *
  page170_i58
#ISCELL
  pure_quanta_power universal_gnd *
  page170_i59
#CELL
  pure_quanta q_cap *
  page170_i6
#CELL
  pure_quanta q_cap *
  page170_i60
#ISCELL
  pure_quanta_power vcc_core *
  page170_i61
#ISCELL
  standard offpage *
  page170_i62
#CELL
  pure_quanta q_cap *
  page170_i63
#CELL
  pure_quanta q_inductor4p_14 *
  page170_i64
#ISCELL
  pure_quanta_power universal_gnd *
  page170_i65
#CELL
  pure_quanta q_cap *
  page170_i66
#ISCELL
  pure_quanta_power vcc_core *
  page170_i67
#ISCELL
  standard offpage *
  page170_i68
#ISCELL
  pure_quanta_power universal_gnd *
  page170_i69
#ISCELL
  standard offpage *
  page170_i7
#CELL
  pure_quanta q_cap *
  page170_i70
#CELL
  pure_quanta q_cap *
  page170_i71
#ISCELL
  pure_quanta_power vcc_core *
  page170_i72
#ISCELL
  standard offpage *
  page170_i8
#CELL
  pure_quanta isl99390frztr5935 *
  page170_i9
#ISCELL
  mstr_misc dns *
  *
#ISCELL
  pure_quanta quanta_title_block_c *
  *
#ISCELL
  standard offpage *
  page171_i1
#ISCELL
  pure_quanta_power universal_gnd *
  page171_i10
#CELL
  pure_quanta q_cap *
  page171_i11
#ISCELL
  pure_quanta_power universal_gnd *
  page171_i12
#CELL
  pure_quanta q_res *
  page171_i13
#CELL
  pure_quanta q_cap *
  page171_i14
#ISCELL
  pure_quanta_power universal_gnd *
  page171_i15
#ISCELL
  pure_quanta_power vcc_core *
  page171_i16
#ISCELL
  standard offpage *
  page171_i17
#CELL
  pure_quanta isl99390frztr5935 *
  page171_i18
#ISCELL
  pure_quanta_power universal_gnd *
  page171_i19
#ISCELL
  standard offpage *
  page171_i2
#ISCELL
  pure_quanta_power universal_gnd *
  page171_i20
#CELL
  pure_quanta q_res *
  page171_i21
#CELL
  pure_quanta q_res *
  page171_i22
#CELL
  pure_quanta q_cap *
  page171_i23
#CELL
  pure_quanta q_cap *
  page171_i24
#ISCELL
  pure_quanta_power universal_gnd *
  page171_i25
#CELL
  pure_quanta q_res *
  page171_i26
#CELL
  pure_quanta q_cap *
  page171_i27
#CELL
  pure_quanta q_cap *
  page171_i28
#CELL
  pure_quanta q_cap *
  page171_i29
#ISCELL
  pure_quanta_power universal_gnd *
  page171_i3
#ISCELL
  pure_quanta_power universal_gnd *
  page171_i30
#CELL
  pure_quanta q_res *
  page171_i31
#CELL
  pure_quanta q_res *
  page171_i32
#CELL
  pure_quanta q_cap *
  page171_i33
#ISCELL
  pure_quanta_power universal_gnd *
  page171_i34
#ISCELL
  standard offpage *
  page171_i35
#CELL
  pure_quanta q_res *
  page171_i36
#ISCELL
  pure_quanta_power universal_gnd *
  page171_i37
#CELL
  pure_quanta q_cap *
  page171_i38
#ISCELL
  standard offpage *
  page171_i39
#CELL
  pure_quanta q_cap *
  page171_i4
#CELL
  pure_quanta q_res *
  page171_i40
#ISCELL
  pure_quanta_power universal_gnd *
  page171_i41
#CELL
  pure_quanta q_cap *
  page171_i42
#ISCELL
  pure_quanta_power vcc_core *
  page171_i43
#CELL
  pure_quanta q_cap *
  page171_i44
#CELL
  pure_quanta q_res *
  page171_i45
#CELL
  pure_quanta q_cap *
  page171_i46
#CELL
  pure_quanta q_cap *
  page171_i47
#CELL
  pure_quanta q_cap *
  page171_i48
#CELL
  pure_quanta q_cap *
  page171_i49
#ISCELL
  pure_quanta_power universal_gnd *
  page171_i5
#ISCELL
  pure_quanta_power universal_gnd *
  page171_i50
#CELL
  pure_quanta q_inductor *
  page171_i51
#CELL
  pure_quanta q_inductor4p_14 *
  page171_i52
#ISCELL
  pure_quanta_power universal_gnd *
  page171_i53
#CELL
  pure_quanta q_cap *
  page171_i54
#CELL
  pure_quanta q_cap *
  page171_i55
#ISCELL
  pure_quanta_power vcc_core *
  page171_i56
#ISCELL
  standard offpage *
  page171_i57
#ISCELL
  pure_quanta_power universal_gnd *
  page171_i58
#CELL
  pure_quanta q_cap *
  page171_i59
#ISCELL
  standard offpage *
  page171_i6
#CELL
  pure_quanta q_cap *
  page171_i60
#ISCELL
  pure_quanta_power vcc_core *
  page171_i61
#ISCELL
  standard offpage *
  page171_i62
#CELL
  pure_quanta q_cap *
  page171_i63
#CELL
  pure_quanta q_inductor4p_14 *
  page171_i64
#ISCELL
  pure_quanta_power universal_gnd *
  page171_i65
#CELL
  pure_quanta q_cap *
  page171_i66
#ISCELL
  pure_quanta_power vcc_core *
  page171_i67
#ISCELL
  standard offpage *
  page171_i68
#CELL
  pure_quanta q_cap *
  page171_i69
#ISCELL
  standard offpage *
  page171_i7
#ISCELL
  pure_quanta_power universal_gnd *
  page171_i70
#CELL
  pure_quanta q_cap *
  page171_i71
#ISCELL
  pure_quanta_power vcc_core *
  page171_i72
#CELL
  pure_quanta isl99390frztr5935 *
  page171_i73
#CELL
  pure_quanta q_res *
  page171_i8
#ISCELL
  standard offpage *
  page171_i9
#ISCELL
  pure_quanta quanta_title_block_c *
  *
#ISCELL
  mstr_misc dns *
  *
#ISCELL
  pure_quanta quanta_title_block_c *
  *
#ISCELL
  standard offpage *
  page173_i1
#ISCELL
  standard offpage *
  page173_i10
#CELL
  pure_quanta q_cap *
  page173_i11
#CELL
  pure_quanta q_res *
  page173_i12
#ISCELL
  pure_quanta_power vcc_core *
  page173_i13
#CELL
  pure_quanta q_cap *
  page173_i14
#ISCELL
  pure_quanta_power universal_gnd *
  page173_i15
#ISCELL
  pure_quanta_power universal_gnd *
  page173_i16
#ISCELL
  pure_quanta_power universal_gnd *
  page173_i17
#CELL
  pure_quanta q_res *
  page173_i18
#CELL
  pure_quanta q_res *
  page173_i19
#ISCELL
  standard offpage *
  page173_i2
#ISCELL
  standard offpage *
  page173_i20
#CELL
  pure_quanta q_cap *
  page173_i21
#CELL
  pure_quanta q_res *
  page173_i22
#CELL
  pure_quanta q_cap *
  page173_i23
#CELL
  pure_quanta q_cap *
  page173_i24
#CELL
  pure_quanta q_cap *
  page173_i25
#ISCELL
  pure_quanta_power universal_gnd *
  page173_i26
#CELL
  pure_quanta q_res *
  page173_i27
#ISCELL
  pure_quanta_power universal_gnd *
  page173_i28
#CELL
  pure_quanta q_cap *
  page173_i29
#ISCELL
  pure_quanta_power universal_gnd *
  page173_i3
#ISCELL
  pure_quanta_power universal_gnd *
  page173_i30
#ISCELL
  standard offpage *
  page173_i31
#CELL
  pure_quanta q_res *
  page173_i32
#ISCELL
  standard offpage *
  page173_i33
#ISCELL
  pure_quanta_power universal_gnd *
  page173_i34
#ISCELL
  standard offpage *
  page173_i35
#CELL
  pure_quanta q_cap *
  page173_i36
#ISCELL
  pure_quanta_power universal_gnd *
  page173_i37
#CELL
  pure_quanta q_res *
  page173_i38
#ISCELL
  pure_quanta_power vcc_core *
  page173_i39
#CELL
  pure_quanta q_cap *
  page173_i4
#CELL
  pure_quanta q_cap *
  page173_i40
#CELL
  pure_quanta isl99390frztr5935 *
  page173_i41
#ISCELL
  pure_quanta_power universal_gnd *
  page173_i42
#CELL
  pure_quanta q_cap *
  page173_i43
#CELL
  pure_quanta q_cap *
  page173_i44
#CELL
  pure_quanta q_res *
  page173_i45
#CELL
  pure_quanta q_cap *
  page173_i46
#ISCELL
  standard offpage *
  page173_i47
#CELL
  pure_quanta q_res *
  page173_i48
#CELL
  pure_quanta q_cap *
  page173_i49
#ISCELL
  pure_quanta_power universal_gnd *
  page173_i5
#CELL
  pure_quanta q_cap *
  page173_i50
#CELL
  pure_quanta q_cap *
  page173_i51
#CELL
  pure_quanta q_cap *
  page173_i52
#CELL
  pure_quanta q_inductor4p_14 *
  page173_i53
#ISCELL
  standard offpage *
  page173_i54
#ISCELL
  pure_quanta_power universal_gnd *
  page173_i55
#CELL
  pure_quanta q_cap *
  page173_i56
#CELL
  pure_quanta q_cap *
  page173_i57
#ISCELL
  pure_quanta_power vcc_core *
  page173_i58
#CELL
  pure_quanta q_cap *
  page173_i59
#ISCELL
  standard offpage *
  page173_i6
#ISCELL
  pure_quanta_power universal_gnd *
  page173_i60
#CELL
  pure_quanta q_cap *
  page173_i61
#ISCELL
  pure_quanta_power vcc_core *
  page173_i62
#CELL
  pure_quanta q_capp *
  page173_i63
#CELL
  pure_quanta q_capp *
  page173_i64
#ISCELL
  pure_quanta_power universal_gnd *
  page173_i65
#CELL
  pure_quanta q_capp *
  page173_i66
#ISCELL
  pure_quanta_power vcc_core *
  page173_i67
#CELL
  pure_quanta q_cap *
  page173_i68
#CELL
  pure_quanta q_inductor4p_14 *
  page173_i69
#ISCELL
  standard offpage *
  page173_i7
#ISCELL
  pure_quanta_power universal_gnd *
  page173_i70
#ISCELL
  pure_quanta_power vcc_core *
  page173_i71
#CELL
  pure_quanta q_cap *
  page173_i72
#CELL
  pure_quanta q_capp *
  page173_i73
#CELL
  pure_quanta q_inductor *
  page173_i74
#ISCELL
  pure_quanta_power universal_gnd *
  page173_i75
#ISCELL
  pure_quanta_power universal_gnd *
  page173_i76
#CELL
  pure_quanta q_cap *
  page173_i77
#ISCELL
  pure_quanta_power vcc_core *
  page173_i78
#CELL
  pure_quanta q_cap *
  page173_i79
#CELL
  pure_quanta q_res *
  page173_i8
#CELL
  pure_quanta q_cap *
  page173_i80
#ISCELL
  pure_quanta_power universal_gnd *
  page173_i81
#CELL
  pure_quanta q_res *
  page173_i82
#CELL
  pure_quanta q_cap *
  page173_i83
#ISCELL
  pure_quanta_power vcc_core *
  page173_i84
#CELL
  pure_quanta q_cap *
  page173_i85
#CELL
  pure_quanta isl99390frztr5935 *
  page173_i86
#CELL
  pure_quanta q_cap *
  page173_i87
#CELL
  pure_quanta q_cap *
  page173_i88
#ISCELL
  pure_quanta_power universal_gnd *
  page173_i9
#ISCELL
  mstr_misc dns *
  *
#ISCELL
  pure_quanta quanta_title_block_c *
  *
#ISCELL
  standard offpage *
  page174_i1
#CELL
  pure_quanta q_res *
  page174_i10
#CELL
  pure_quanta q_res *
  page174_i11
#CELL
  pure_quanta q_cap *
  page174_i12
#ISCELL
  pure_quanta_power universal_gnd *
  page174_i13
#CELL
  pure_quanta q_cap *
  page174_i14
#CELL
  pure_quanta q_res *
  page174_i15
#ISCELL
  pure_quanta_power vcc_core *
  page174_i16
#ISCELL
  standard offpage *
  page174_i17
#ISCELL
  pure_quanta_power universal_gnd *
  page174_i18
#CELL
  pure_quanta q_cap *
  page174_i19
#CELL
  pure_quanta q_cap *
  page174_i2
#CELL
  pure_quanta q_res *
  page174_i20
#CELL
  pure_quanta q_cap *
  page174_i21
#CELL
  pure_quanta q_cap *
  page174_i22
#ISCELL
  pure_quanta_power universal_gnd *
  page174_i23
#CELL
  pure_quanta q_inductor *
  page174_i24
#CELL
  pure_quanta q_inductor4p_14 *
  page174_i25
#ISCELL
  standard offpage *
  page174_i26
#CELL
  pure_quanta q_cap *
  page174_i27
#ISCELL
  pure_quanta_power universal_gnd *
  page174_i28
#CELL
  pure_quanta q_cap *
  page174_i29
#ISCELL
  pure_quanta_power universal_gnd *
  page174_i3
#CELL
  pure_quanta q_cap *
  page174_i30
#CELL
  pure_quanta q_cap *
  page174_i31
#CELL
  pure_quanta q_cap *
  page174_i32
#ISCELL
  pure_quanta_power universal_gnd *
  page174_i33
#CELL
  pure_quanta q_cap *
  page174_i34
#ISCELL
  pure_quanta_power vcc_core *
  page174_i35
#ISCELL
  pure_quanta_power vcc_core *
  page174_i36
#CELL
  pure_quanta q_cap *
  page174_i37
#CELL
  pure_quanta isl99390frztr5935 *
  page174_i38
#ISCELL
  pure_quanta_power universal_gnd *
  page174_i4
#ISCELL
  standard offpage *
  page174_i5
#ISCELL
  standard offpage *
  page174_i6
#CELL
  pure_quanta q_res *
  page174_i7
#ISCELL
  pure_quanta_power universal_gnd *
  page174_i8
#ISCELL
  pure_quanta_power universal_gnd *
  page174_i9
#ISCELL
  mstr_misc dns *
  *
#ISCELL
  pure_quanta quanta_title_block_c *
  *
#ISCELL
  standard offpage *
  page175_i1
#ISCELL
  pure_quanta_power vcc_core *
  page175_i10
#CELL
  pure_quanta q_cap *
  page175_i100
#ISCELL
  standard offpage *
  page175_i101
#ISCELL
  standard offpage *
  page175_i102
#ISCELL
  standard offpage *
  page175_i103
#ISCELL
  standard offpage *
  page175_i104
#ISCELL
  standard offpage *
  page175_i105
#ISCELL
  standard offpage *
  page175_i106
#ISCELL
  standard offpage *
  page175_i107
#ISCELL
  standard offpage *
  page175_i108
#ISCELL
  standard offpage *
  page175_i109
#ISCELL
  pure_quanta_power vcc_core *
  page175_i11
#ISCELL
  standard offpage *
  page175_i110
#ISCELL
  pure_quanta_power universal_gnd *
  page175_i111
#ISCELL
  pure_quanta_power universal_gnd *
  page175_i112
#ISCELL
  standard offpage *
  page175_i113
#ISCELL
  standard offpage *
  page175_i114
#ISCELL
  standard offpage *
  page175_i115
#ISCELL
  standard offpage *
  page175_i116
#ISCELL
  standard offpage *
  page175_i117
#ISCELL
  standard offpage *
  page175_i118
#ISCELL
  standard offpage *
  page175_i119
#CELL
  pure_quanta q_res *
  page175_i12
#ISCELL
  standard offpage *
  page175_i120
#ISCELL
  standard offpage *
  page175_i121
#ISCELL
  standard offpage *
  page175_i122
#ISCELL
  standard offpage *
  page175_i123
#ISCELL
  standard offpage *
  page175_i124
#ISCELL
  standard offpage *
  page175_i125
#CELL
  pure_quanta q_res *
  page175_i126
#ISCELL
  pure_quanta_power vcc_core *
  page175_i127
#CELL
  pure_quanta raa229620gnpha0 *
  page175_i128
#CELL
  pure_quanta q_res *
  page175_i129
#CELL
  pure_quanta mosfet_pch_gds_esd_protected *
  page175_i13
#CELL
  pure_quanta q_cap *
  page175_i130
#ISCELL
  pure_quanta_power universal_gnd *
  page175_i131
#ISCELL
  pure_quanta_power universal_gnd *
  page175_i132
#CELL
  pure_quanta q_cap *
  page175_i133
#ISCELL
  pure_quanta_power universal_gnd *
  page175_i134
#CELL
  pure_quanta q_cap *
  page175_i135
#CELL
  pure_quanta q_res *
  page175_i136
#CELL
  pure_quanta q_res *
  page175_i137
#ISCELL
  standard offpage *
  page175_i14
#ISCELL
  standard offpage *
  page175_i15
#ISCELL
  standard offpage *
  page175_i16
#CELL
  pure_quanta q_res *
  page175_i17
#ISCELL
  pure_quanta_power vcc_core *
  page175_i18
#CELL
  pure_quanta q_res *
  page175_i19
#CELL
  pure_quanta q_res *
  page175_i2
#ISCELL
  standard offpage *
  page175_i20
#ISCELL
  pure_quanta_power universal_gnd *
  page175_i21
#CELL
  pure_quanta q_res *
  page175_i22
#CELL
  pure_quanta q_res *
  page175_i23
#ISCELL
  pure_quanta_power vcc_core *
  page175_i24
#ISCELL
  pure_quanta_power universal_gnd *
  page175_i25
#ISCELL
  pure_quanta_power universal_gnd *
  page175_i26
#ISCELL
  standard offpage *
  page175_i27
#CELL
  pure_quanta q_res *
  page175_i28
#ISCELL
  standard offpage *
  page175_i29
#CELL
  pure_quanta q_cap *
  page175_i3
#ISCELL
  standard offpage *
  page175_i30
#ISCELL
  standard offpage *
  page175_i31
#CELL
  pure_quanta q_res *
  page175_i32
#CELL
  pure_quanta q_cap *
  page175_i33
#CELL
  pure_quanta q_cap *
  page175_i34
#CELL
  pure_quanta q_cap *
  page175_i35
#CELL
  pure_quanta q_res *
  page175_i36
#ISCELL
  standard offpage *
  page175_i37
#ISCELL
  standard offpage *
  page175_i38
#ISCELL
  standard offpage *
  page175_i39
#ISCELL
  pure_quanta_power universal_gnd *
  page175_i4
#CELL
  pure_quanta q_res *
  page175_i40
#ISCELL
  pure_quanta_power vcc_core *
  page175_i41
#CELL
  pure_quanta q_res *
  page175_i42
#CELL
  pure_quanta q_res *
  page175_i43
#CELL
  pure_quanta q_res *
  page175_i44
#ISCELL
  standard offpage *
  page175_i45
#ISCELL
  standard offpage *
  page175_i46
#ISCELL
  pure_quanta_power vcc_core *
  page175_i47
#ISCELL
  standard offpage *
  page175_i48
#ISCELL
  pure_quanta_power universal_gnd *
  page175_i49
#ISCELL
  standard offpage *
  page175_i5
#CELL
  pure_quanta q_cap *
  page175_i50
#CELL
  pure_quanta q_res *
  page175_i51
#ISCELL
  pure_quanta_power vcc_core *
  page175_i52
#CELL
  pure_quanta q_res *
  page175_i53
#CELL
  pure_quanta q_res *
  page175_i54
#CELL
  pure_quanta q_cap *
  page175_i55
#ISCELL
  pure_quanta_power vcc_core *
  page175_i56
#ISCELL
  pure_quanta_power universal_gnd *
  page175_i57
#ISCELL
  pure_quanta_power universal_gnd *
  page175_i58
#CELL
  pure_quanta q_res *
  page175_i59
#CELL
  pure_quanta mosfet_n *
  page175_i6
#CELL
  pure_quanta q_cap *
  page175_i60
#ISCELL
  pure_quanta_power universal_gnd *
  page175_i61
#ISCELL
  pure_quanta_power universal_gnd *
  page175_i62
#CELL
  pure_quanta q_cap *
  page175_i63
#ISCELL
  pure_quanta_power universal_gnd *
  page175_i64
#ISCELL
  pure_quanta_power vcc_core *
  page175_i65
#CELL
  pure_quanta q_res *
  page175_i66
#CELL
  pure_quanta q_res *
  page175_i67
#CELL
  pure_quanta q_res *
  page175_i68
#CELL
  pure_quanta q_cap *
  page175_i69
#ISCELL
  pure_quanta_power universal_gnd *
  page175_i7
#CELL
  pure_quanta q_res *
  page175_i70
#CELL
  pure_quanta q_res *
  page175_i71
#ISCELL
  pure_quanta_power universal_gnd *
  page175_i72
#CELL
  pure_quanta q_cap *
  page175_i73
#ISCELL
  pure_quanta_power universal_gnd *
  page175_i74
#CELL
  pure_quanta q_cap *
  page175_i75
#CELL
  pure_quanta q_res *
  page175_i76
#CELL
  pure_quanta q_res *
  page175_i77
#CELL
  pure_quanta q_res *
  page175_i78
#ISCELL
  pure_quanta_power vcc_core *
  page175_i79
#CELL
  pure_quanta q_res *
  page175_i8
#CELL
  pure_quanta q_cap *
  page175_i80
#CELL
  pure_quanta q_res *
  page175_i81
#CELL
  pure_quanta q_res *
  page175_i82
#CELL
  pure_quanta q_res *
  page175_i83
#CELL
  pure_quanta q_res *
  page175_i84
#CELL
  pure_quanta q_res *
  page175_i85
#CELL
  pure_quanta q_cap *
  page175_i86
#ISCELL
  pure_quanta_power universal_gnd *
  page175_i87
#CELL
  pure_quanta q_res *
  page175_i88
#CELL
  pure_quanta q_res *
  page175_i89
#CELL
  pure_quanta q_res *
  page175_i9
#CELL
  pure_quanta q_res *
  page175_i90
#CELL
  pure_quanta q_cap *
  page175_i91
#ISCELL
  pure_quanta_power universal_gnd *
  page175_i92
#ISCELL
  pure_quanta_power universal_gnd *
  page175_i93
#CELL
  pure_quanta q_cap *
  page175_i94
#ISCELL
  pure_quanta_power universal_gnd *
  page175_i95
#CELL
  pure_quanta q_cap *
  page175_i96
#ISCELL
  pure_quanta_power universal_gnd *
  page175_i97
#CELL
  pure_quanta q_cap *
  page175_i98
#ISCELL
  pure_quanta_power universal_gnd *
  page175_i99
#ISCELL
  mstr_misc dns *
  *
#ISCELL
  pure_quanta quanta_title_block_c *
  *
#ISCELL
  pure_quanta_power universal_gnd *
  page176_i1
#CELL
  pure_quanta q_cap *
  page176_i10
#ISCELL
  pure_quanta_power universal_gnd *
  page176_i11
#CELL
  pure_quanta q_cap *
  page176_i12
#CELL
  pure_quanta q_res *
  page176_i13
#ISCELL
  pure_quanta_power universal_gnd *
  page176_i14
#CELL
  pure_quanta q_cap *
  page176_i15
#ISCELL
  pure_quanta_power vcc_core *
  page176_i16
#ISCELL
  pure_quanta_power universal_gnd *
  page176_i17
#CELL
  pure_quanta q_res *
  page176_i18
#ISCELL
  standard offpage *
  page176_i19
#CELL
  pure_quanta q_cap *
  page176_i2
#ISCELL
  standard offpage *
  page176_i20
#CELL
  pure_quanta q_res *
  page176_i21
#ISCELL
  pure_quanta_power vcc_core *
  page176_i22
#ISCELL
  pure_quanta_power universal_gnd *
  page176_i23
#CELL
  pure_quanta q_cap *
  page176_i24
#ISCELL
  standard offpage *
  page176_i25
#ISCELL
  standard offpage *
  page176_i26
#CELL
  pure_quanta q_res *
  page176_i27
#ISCELL
  pure_quanta_power vcc_core *
  page176_i28
#CELL
  pure_quanta q_res *
  page176_i29
#ISCELL
  pure_quanta_power universal_gnd *
  page176_i3
#CELL
  pure_quanta q_cap *
  page176_i30
#ISCELL
  pure_quanta_power universal_gnd *
  page176_i31
#ISCELL
  pure_quanta_power vcc_core *
  page176_i32
#CELL
  pure_quanta isl99390frztr5935 *
  page176_i33
#ISCELL
  pure_quanta_power universal_gnd *
  page176_i34
#CELL
  pure_quanta isl99390frztr5935 *
  page176_i35
#ISCELL
  pure_quanta_power universal_gnd *
  page176_i36
#CELL
  pure_quanta q_cap *
  page176_i37
#ISCELL
  pure_quanta_power universal_gnd *
  page176_i38
#CELL
  pure_quanta q_res *
  page176_i39
#CELL
  pure_quanta q_res *
  page176_i4
#CELL
  pure_quanta q_res *
  page176_i40
#CELL
  pure_quanta q_cap *
  page176_i41
#CELL
  pure_quanta q_res *
  page176_i42
#ISCELL
  standard offpage *
  page176_i43
#CELL
  pure_quanta q_cap *
  page176_i44
#ISCELL
  pure_quanta_power universal_gnd *
  page176_i45
#CELL
  pure_quanta q_inductor4p_14 *
  page176_i46
#CELL
  pure_quanta q_cap *
  page176_i47
#CELL
  pure_quanta q_cap *
  page176_i48
#ISCELL
  pure_quanta_power universal_gnd *
  page176_i49
#ISCELL
  standard offpage *
  page176_i5
#CELL
  pure_quanta q_res *
  page176_i50
#CELL
  pure_quanta q_cap *
  page176_i51
#CELL
  pure_quanta q_cap *
  page176_i52
#ISCELL
  pure_quanta_power vcc_core *
  page176_i53
#CELL
  pure_quanta q_res *
  page176_i54
#CELL
  pure_quanta q_cap *
  page176_i55
#CELL
  pure_quanta q_res *
  page176_i56
#CELL
  pure_quanta q_cap *
  page176_i57
#ISCELL
  standard offpage *
  page176_i58
#CELL
  pure_quanta q_cap *
  page176_i59
#ISCELL
  standard offpage *
  page176_i6
#CELL
  pure_quanta q_cap *
  page176_i60
#CELL
  pure_quanta q_cap *
  page176_i61
#CELL
  pure_quanta q_inductor4p_14 *
  page176_i62
#ISCELL
  pure_quanta_power universal_gnd *
  page176_i63
#CELL
  pure_quanta q_cap *
  page176_i64
#CELL
  pure_quanta q_cap *
  page176_i65
#CELL
  pure_quanta q_capp *
  page176_i66
#ISCELL
  pure_quanta_power vcc_core *
  page176_i67
#ISCELL
  standard offpage *
  page176_i68
#CELL
  pure_quanta q_cap *
  page176_i69
#ISCELL
  standard offpage *
  page176_i7
#CELL
  pure_quanta q_capp *
  page176_i70
#CELL
  pure_quanta q_capp *
  page176_i71
#CELL
  pure_quanta q_capp *
  page176_i72
#CELL
  pure_quanta q_capp *
  page176_i73
#ISCELL
  pure_quanta_power universal_gnd *
  page176_i74
#CELL
  pure_quanta q_capp *
  page176_i75
#ISCELL
  pure_quanta_power vcc_core *
  page176_i76
#CELL
  pure_quanta q_cap *
  page176_i77
#ISCELL
  pure_quanta_power universal_gnd *
  page176_i78
#ISCELL
  pure_quanta_power vcc_core *
  page176_i79
#ISCELL
  standard offpage *
  page176_i8
#ISCELL
  pure_quanta_power universal_gnd *
  page176_i80
#ISCELL
  standard offpage *
  page176_i81
#CELL
  pure_quanta q_capp *
  page176_i82
#CELL
  pure_quanta q_inductor *
  page176_i83
#CELL
  pure_quanta q_cap *
  page176_i84
#ISCELL
  pure_quanta_power universal_gnd *
  page176_i85
#CELL
  pure_quanta q_cap *
  page176_i86
#CELL
  pure_quanta q_cap *
  page176_i87
#ISCELL
  pure_quanta_power vcc_core *
  page176_i88
#CELL
  pure_quanta q_cap *
  page176_i89
#ISCELL
  pure_quanta_power universal_gnd *
  page176_i9
#CELL
  pure_quanta q_res *
  page176_i90
#ISCELL
  pure_quanta_power vcc_core *
  page176_i91
#ISCELL
  mstr_misc dns *
  *
#ISCELL
  pure_quanta quanta_title_block_c *
  *
#ISCELL
  pure_quanta_power universal_gnd *
  page177_i1
#ISCELL
  standard offpage *
  page177_i10
#ISCELL
  pure_quanta_power universal_gnd *
  page177_i11
#CELL
  pure_quanta q_cap *
  page177_i12
#CELL
  pure_quanta q_res *
  page177_i13
#ISCELL
  pure_quanta_power vcc_core *
  page177_i14
#ISCELL
  pure_quanta_power universal_gnd *
  page177_i15
#CELL
  pure_quanta q_cap *
  page177_i16
#ISCELL
  pure_quanta_power universal_gnd *
  page177_i17
#CELL
  pure_quanta q_res *
  page177_i18
#ISCELL
  standard offpage *
  page177_i19
#CELL
  pure_quanta q_cap *
  page177_i2
#ISCELL
  standard offpage *
  page177_i20
#CELL
  pure_quanta isl99390frztr5935 *
  page177_i21
#ISCELL
  pure_quanta_power universal_gnd *
  page177_i22
#CELL
  pure_quanta isl99390frztr5935 *
  page177_i23
#CELL
  pure_quanta q_cap *
  page177_i24
#ISCELL
  pure_quanta_power universal_gnd *
  page177_i25
#ISCELL
  standard offpage *
  page177_i26
#ISCELL
  standard offpage *
  page177_i27
#CELL
  pure_quanta q_cap *
  page177_i28
#ISCELL
  pure_quanta_power universal_gnd *
  page177_i29
#ISCELL
  pure_quanta_power universal_gnd *
  page177_i3
#CELL
  pure_quanta q_res *
  page177_i30
#ISCELL
  pure_quanta_power universal_gnd *
  page177_i31
#CELL
  pure_quanta q_cap *
  page177_i32
#ISCELL
  pure_quanta_power vcc_core *
  page177_i33
#CELL
  pure_quanta q_cap *
  page177_i34
#ISCELL
  pure_quanta_power universal_gnd *
  page177_i35
#CELL
  pure_quanta q_res *
  page177_i36
#CELL
  pure_quanta q_res *
  page177_i37
#CELL
  pure_quanta q_cap *
  page177_i38
#ISCELL
  standard offpage *
  page177_i39
#CELL
  pure_quanta q_res *
  page177_i4
#CELL
  pure_quanta q_res *
  page177_i40
#CELL
  pure_quanta q_cap *
  page177_i41
#CELL
  pure_quanta q_inductor4p_14 *
  page177_i42
#CELL
  pure_quanta q_cap *
  page177_i43
#CELL
  pure_quanta q_cap *
  page177_i44
#ISCELL
  pure_quanta_power universal_gnd *
  page177_i45
#CELL
  pure_quanta q_res *
  page177_i46
#CELL
  pure_quanta q_cap *
  page177_i47
#ISCELL
  pure_quanta_power universal_gnd *
  page177_i48
#CELL
  pure_quanta q_cap *
  page177_i49
#ISCELL
  standard offpage *
  page177_i5
#ISCELL
  pure_quanta_power vcc_core *
  page177_i50
#CELL
  pure_quanta q_res *
  page177_i51
#ISCELL
  pure_quanta_power universal_gnd *
  page177_i52
#ISCELL
  pure_quanta_power universal_gnd *
  page177_i53
#CELL
  pure_quanta q_cap *
  page177_i54
#CELL
  pure_quanta q_cap *
  page177_i55
#ISCELL
  pure_quanta_power vcc_core *
  page177_i56
#CELL
  pure_quanta q_res *
  page177_i57
#CELL
  pure_quanta q_cap *
  page177_i58
#ISCELL
  standard offpage *
  page177_i59
#ISCELL
  pure_quanta_power universal_gnd *
  page177_i6
#CELL
  pure_quanta q_cap *
  page177_i60
#CELL
  pure_quanta q_cap *
  page177_i61
#CELL
  pure_quanta q_cap *
  page177_i62
#ISCELL
  pure_quanta_power universal_gnd *
  page177_i63
#CELL
  pure_quanta q_inductor4p_14 *
  page177_i64
#CELL
  pure_quanta q_cap *
  page177_i65
#CELL
  pure_quanta q_cap *
  page177_i66
#ISCELL
  pure_quanta_power vcc_core *
  page177_i67
#ISCELL
  standard offpage *
  page177_i68
#CELL
  pure_quanta q_cap *
  page177_i69
#CELL
  pure_quanta q_cap *
  page177_i7
#ISCELL
  pure_quanta_power universal_gnd *
  page177_i70
#CELL
  pure_quanta q_cap *
  page177_i71
#ISCELL
  pure_quanta_power vcc_core *
  page177_i72
#ISCELL
  standard offpage *
  page177_i8
#ISCELL
  standard offpage *
  page177_i9
#ISCELL
  mstr_misc dns *
  *
#ISCELL
  pure_quanta quanta_title_block_c *
  *
#ISCELL
  pure_quanta_power universal_gnd *
  page178_i1
#CELL
  pure_quanta q_cap *
  page178_i10
#CELL
  pure_quanta q_cap *
  page178_i11
#ISCELL
  pure_quanta_power universal_gnd *
  page178_i12
#CELL
  pure_quanta q_res *
  page178_i13
#ISCELL
  pure_quanta_power universal_gnd *
  page178_i14
#CELL
  pure_quanta q_res *
  page178_i15
#ISCELL
  pure_quanta_power vcc_core *
  page178_i16
#ISCELL
  standard offpage *
  page178_i17
#ISCELL
  standard offpage *
  page178_i18
#ISCELL
  pure_quanta_power universal_gnd *
  page178_i19
#CELL
  pure_quanta q_cap *
  page178_i2
#CELL
  pure_quanta q_cap *
  page178_i20
#ISCELL
  pure_quanta_power universal_gnd *
  page178_i21
#CELL
  pure_quanta isl99390frztr5935 *
  page178_i22
#ISCELL
  pure_quanta_power universal_gnd *
  page178_i23
#ISCELL
  standard offpage *
  page178_i24
#ISCELL
  standard offpage *
  page178_i25
#ISCELL
  pure_quanta_power universal_gnd *
  page178_i26
#CELL
  pure_quanta q_cap *
  page178_i27
#CELL
  pure_quanta q_res *
  page178_i28
#ISCELL
  pure_quanta_power vcc_core *
  page178_i29
#ISCELL
  pure_quanta_power universal_gnd *
  page178_i3
#ISCELL
  pure_quanta_power universal_gnd *
  page178_i30
#CELL
  pure_quanta q_cap *
  page178_i31
#ISCELL
  pure_quanta_power universal_gnd *
  page178_i32
#CELL
  pure_quanta q_res *
  page178_i33
#ISCELL
  pure_quanta_power universal_gnd *
  page178_i34
#CELL
  pure_quanta q_res *
  page178_i35
#CELL
  pure_quanta q_inductor *
  page178_i36
#CELL
  pure_quanta q_cap *
  page178_i37
#CELL
  pure_quanta q_inductor4p_14 *
  page178_i38
#CELL
  pure_quanta q_res *
  page178_i39
#CELL
  pure_quanta q_res *
  page178_i4
#CELL
  pure_quanta q_cap *
  page178_i40
#CELL
  pure_quanta q_cap *
  page178_i41
#CELL
  pure_quanta q_cap *
  page178_i42
#ISCELL
  pure_quanta_power universal_gnd *
  page178_i43
#CELL
  pure_quanta q_res *
  page178_i44
#CELL
  pure_quanta q_cap *
  page178_i45
#ISCELL
  pure_quanta_power universal_gnd *
  page178_i46
#CELL
  pure_quanta q_cap *
  page178_i47
#ISCELL
  pure_quanta_power vcc_core *
  page178_i48
#CELL
  pure_quanta q_res *
  page178_i49
#ISCELL
  standard offpage *
  page178_i5
#ISCELL
  standard offpage *
  page178_i50
#CELL
  pure_quanta q_cap *
  page178_i51
#ISCELL
  pure_quanta_power universal_gnd *
  page178_i52
#CELL
  pure_quanta q_cap *
  page178_i53
#ISCELL
  pure_quanta_power vcc_core *
  page178_i54
#ISCELL
  pure_quanta_power universal_gnd *
  page178_i55
#CELL
  pure_quanta q_res *
  page178_i56
#CELL
  pure_quanta q_cap *
  page178_i57
#CELL
  pure_quanta q_cap *
  page178_i58
#CELL
  pure_quanta q_cap *
  page178_i59
#ISCELL
  standard offpage *
  page178_i6
#CELL
  pure_quanta q_cap *
  page178_i60
#ISCELL
  standard offpage *
  page178_i61
#CELL
  pure_quanta q_cap *
  page178_i62
#CELL
  pure_quanta q_inductor4p_14 *
  page178_i63
#ISCELL
  pure_quanta_power universal_gnd *
  page178_i64
#CELL
  pure_quanta q_cap *
  page178_i65
#CELL
  pure_quanta q_cap *
  page178_i66
#ISCELL
  pure_quanta_power vcc_core *
  page178_i67
#ISCELL
  standard offpage *
  page178_i68
#CELL
  pure_quanta q_cap *
  page178_i69
#ISCELL
  standard offpage *
  page178_i7
#CELL
  pure_quanta q_cap *
  page178_i70
#ISCELL
  pure_quanta_power vcc_core *
  page178_i71
#CELL
  pure_quanta q_cap *
  page178_i72
#CELL
  pure_quanta isl99390frztr5935 *
  page178_i73
#ISCELL
  standard offpage *
  page178_i8
#ISCELL
  pure_quanta_power universal_gnd *
  page178_i9
#ISCELL
  pure_quanta quanta_title_block_c *
  *
#ISCELL
  mstr_misc dns *
  *
#ISCELL
  pure_quanta quanta_title_block_c *
  *
#ISCELL
  pure_quanta_power universal_gnd *
  page180_i1
#CELL
  pure_quanta q_cap *
  page180_i10
#ISCELL
  pure_quanta_power universal_gnd *
  page180_i11
#CELL
  pure_quanta q_res *
  page180_i12
#CELL
  pure_quanta q_cap *
  page180_i13
#ISCELL
  pure_quanta_power vcc_core *
  page180_i14
#CELL
  pure_quanta isl99390frztr5935 *
  page180_i15
#ISCELL
  pure_quanta_power universal_gnd *
  page180_i16
#CELL
  pure_quanta q_res *
  page180_i17
#CELL
  pure_quanta q_cap *
  page180_i18
#ISCELL
  pure_quanta_power universal_gnd *
  page180_i19
#CELL
  pure_quanta q_cap *
  page180_i2
#CELL
  pure_quanta q_cap *
  page180_i20
#ISCELL
  pure_quanta_power universal_gnd *
  page180_i21
#CELL
  pure_quanta q_res *
  page180_i22
#ISCELL
  standard offpage *
  page180_i23
#ISCELL
  standard offpage *
  page180_i24
#ISCELL
  standard offpage *
  page180_i25
#ISCELL
  standard offpage *
  page180_i26
#ISCELL
  pure_quanta_power universal_gnd *
  page180_i27
#CELL
  pure_quanta q_cap *
  page180_i28
#CELL
  pure_quanta q_res *
  page180_i29
#ISCELL
  pure_quanta_power universal_gnd *
  page180_i3
#ISCELL
  pure_quanta_power universal_gnd *
  page180_i30
#CELL
  pure_quanta q_cap *
  page180_i31
#ISCELL
  pure_quanta_power vcc_core *
  page180_i32
#ISCELL
  pure_quanta_power universal_gnd *
  page180_i33
#CELL
  pure_quanta q_res *
  page180_i34
#ISCELL
  pure_quanta_power universal_gnd *
  page180_i35
#CELL
  pure_quanta q_res *
  page180_i36
#CELL
  pure_quanta q_cap *
  page180_i37
#ISCELL
  standard offpage *
  page180_i38
#CELL
  pure_quanta q_res *
  page180_i39
#CELL
  pure_quanta q_res *
  page180_i4
#CELL
  pure_quanta q_inductor4p_14 *
  page180_i40
#CELL
  pure_quanta q_cap *
  page180_i41
#CELL
  pure_quanta q_cap *
  page180_i42
#CELL
  pure_quanta q_cap *
  page180_i43
#ISCELL
  pure_quanta_power universal_gnd *
  page180_i44
#CELL
  pure_quanta q_cap *
  page180_i45
#ISCELL
  pure_quanta_power universal_gnd *
  page180_i46
#CELL
  pure_quanta q_cap *
  page180_i47
#ISCELL
  pure_quanta_power vcc_core *
  page180_i48
#CELL
  pure_quanta q_res *
  page180_i49
#ISCELL
  standard offpage *
  page180_i5
#ISCELL
  standard offpage *
  page180_i50
#CELL
  pure_quanta q_cap *
  page180_i51
#ISCELL
  pure_quanta_power universal_gnd *
  page180_i52
#CELL
  pure_quanta q_cap *
  page180_i53
#CELL
  pure_quanta q_capp *
  page180_i54
#ISCELL
  pure_quanta_power vcc_core *
  page180_i55
#ISCELL
  pure_quanta_power universal_gnd *
  page180_i56
#CELL
  pure_quanta q_capp *
  page180_i57
#CELL
  pure_quanta q_capp *
  page180_i58
#ISCELL
  pure_quanta_power vcc_core *
  page180_i59
#ISCELL
  standard offpage *
  page180_i6
#CELL
  pure_quanta q_res *
  page180_i60
#CELL
  pure_quanta q_cap *
  page180_i61
#ISCELL
  standard offpage *
  page180_i62
#CELL
  pure_quanta q_cap *
  page180_i63
#CELL
  pure_quanta q_inductor4p_14 *
  page180_i64
#ISCELL
  pure_quanta_power universal_gnd *
  page180_i65
#CELL
  pure_quanta q_cap *
  page180_i66
#CELL
  pure_quanta q_capp *
  page180_i67
#ISCELL
  pure_quanta_power vcc_core *
  page180_i68
#CELL
  pure_quanta q_inductor *
  page180_i69
#ISCELL
  standard offpage *
  page180_i7
#ISCELL
  pure_quanta_power universal_gnd *
  page180_i70
#ISCELL
  pure_quanta_power universal_gnd *
  page180_i71
#CELL
  pure_quanta q_cap *
  page180_i72
#CELL
  pure_quanta q_cap *
  page180_i73
#CELL
  pure_quanta q_cap *
  page180_i74
#CELL
  pure_quanta q_cap *
  page180_i75
#ISCELL
  pure_quanta_power vcc_core *
  page180_i76
#ISCELL
  pure_quanta_power universal_gnd *
  page180_i77
#CELL
  pure_quanta q_res *
  page180_i78
#ISCELL
  pure_quanta_power vcc_core *
  page180_i79
#ISCELL
  standard offpage *
  page180_i8
#CELL
  pure_quanta q_cap *
  page180_i80
#CELL
  pure_quanta q_cap *
  page180_i81
#CELL
  pure_quanta q_cap *
  page180_i82
#CELL
  pure_quanta q_cap *
  page180_i83
#CELL
  pure_quanta isl99390frztr5935 *
  page180_i84
#CELL
  pure_quanta q_cap *
  page180_i85
#ISCELL
  pure_quanta_power universal_gnd *
  page180_i9
#ISCELL
  mstr_misc dns *
  *
#ISCELL
  pure_quanta quanta_title_block_c *
  *
#CELL
  pure_quanta q_cap *
  page181_i1
#CELL
  pure_quanta q_cap *
  page181_i10
#ISCELL
  pure_quanta_power universal_gnd *
  page181_i11
#CELL
  pure_quanta q_res *
  page181_i12
#CELL
  pure_quanta q_cap *
  page181_i13
#ISCELL
  pure_quanta_power vcc_core *
  page181_i14
#ISCELL
  pure_quanta_power universal_gnd *
  page181_i15
#CELL
  pure_quanta q_res *
  page181_i16
#CELL
  pure_quanta q_cap *
  page181_i17
#ISCELL
  pure_quanta_power universal_gnd *
  page181_i18
#CELL
  pure_quanta q_cap *
  page181_i19
#ISCELL
  pure_quanta_power universal_gnd *
  page181_i2
#ISCELL
  pure_quanta_power universal_gnd *
  page181_i20
#CELL
  pure_quanta q_res *
  page181_i21
#ISCELL
  standard offpage *
  page181_i22
#ISCELL
  standard offpage *
  page181_i23
#ISCELL
  standard offpage *
  page181_i24
#ISCELL
  standard offpage *
  page181_i25
#ISCELL
  pure_quanta_power universal_gnd *
  page181_i26
#CELL
  pure_quanta q_cap *
  page181_i27
#CELL
  pure_quanta q_res *
  page181_i28
#ISCELL
  pure_quanta_power universal_gnd *
  page181_i29
#ISCELL
  pure_quanta_power universal_gnd *
  page181_i3
#CELL
  pure_quanta q_cap *
  page181_i30
#ISCELL
  pure_quanta_power vcc_core *
  page181_i31
#CELL
  pure_quanta isl99390frztr5935 *
  page181_i32
#ISCELL
  pure_quanta_power universal_gnd *
  page181_i33
#CELL
  pure_quanta q_res *
  page181_i34
#CELL
  pure_quanta q_cap *
  page181_i35
#CELL
  pure_quanta q_cap *
  page181_i36
#ISCELL
  pure_quanta_power universal_gnd *
  page181_i37
#CELL
  pure_quanta q_res *
  page181_i38
#CELL
  pure_quanta q_cap *
  page181_i39
#CELL
  pure_quanta q_res *
  page181_i4
#ISCELL
  pure_quanta_power universal_gnd *
  page181_i40
#CELL
  pure_quanta q_res *
  page181_i41
#CELL
  pure_quanta q_inductor4p_14 *
  page181_i42
#CELL
  pure_quanta q_inductor *
  page181_i43
#CELL
  pure_quanta q_cap *
  page181_i44
#CELL
  pure_quanta q_cap *
  page181_i45
#CELL
  pure_quanta q_cap *
  page181_i46
#CELL
  pure_quanta q_cap *
  page181_i47
#ISCELL
  pure_quanta_power universal_gnd *
  page181_i48
#CELL
  pure_quanta q_cap *
  page181_i49
#ISCELL
  standard offpage *
  page181_i5
#CELL
  pure_quanta q_res *
  page181_i50
#ISCELL
  pure_quanta_power vcc_core *
  page181_i51
#ISCELL
  standard offpage *
  page181_i52
#CELL
  pure_quanta q_cap *
  page181_i53
#ISCELL
  pure_quanta_power universal_gnd *
  page181_i54
#CELL
  pure_quanta q_res *
  page181_i55
#CELL
  pure_quanta q_cap *
  page181_i56
#ISCELL
  standard offpage *
  page181_i57
#CELL
  pure_quanta q_cap *
  page181_i58
#CELL
  pure_quanta q_cap *
  page181_i59
#ISCELL
  standard offpage *
  page181_i6
#CELL
  pure_quanta q_cap *
  page181_i60
#CELL
  pure_quanta q_inductor4p_14 *
  page181_i61
#ISCELL
  pure_quanta_power universal_gnd *
  page181_i62
#CELL
  pure_quanta q_cap *
  page181_i63
#ISCELL
  pure_quanta_power vcc_core *
  page181_i64
#ISCELL
  standard offpage *
  page181_i65
#CELL
  pure_quanta q_cap *
  page181_i66
#ISCELL
  pure_quanta_power universal_gnd *
  page181_i67
#CELL
  pure_quanta q_cap *
  page181_i68
#ISCELL
  pure_quanta_power vcc_core *
  page181_i69
#ISCELL
  standard offpage *
  page181_i7
#ISCELL
  pure_quanta_power universal_gnd *
  page181_i70
#CELL
  pure_quanta q_cap *
  page181_i71
#ISCELL
  pure_quanta_power vcc_core *
  page181_i72
#CELL
  pure_quanta isl99390frztr5935 *
  page181_i73
#ISCELL
  standard offpage *
  page181_i8
#ISCELL
  pure_quanta_power universal_gnd *
  page181_i9
#ISCELL
  mstr_misc dns *
  *
#ISCELL
  pure_quanta quanta_title_block_c *
  *
#ISCELL
  pure_quanta_power vcc_core *
  page182_i1
#ISCELL
  standard offpage *
  page182_i10
#ISCELL
  standard offpage *
  page182_i11
#ISCELL
  standard offpage *
  page182_i12
#CELL
  pure_quanta q_res *
  page182_i13
#ISCELL
  pure_quanta_power universal_gnd *
  page182_i14
#CELL
  pure_quanta q_res *
  page182_i15
#CELL
  pure_quanta q_res *
  page182_i16
#ISCELL
  pure_quanta_power universal_gnd *
  page182_i17
#CELL
  pure_quanta q_res *
  page182_i18
#ISCELL
  pure_quanta_power universal_gnd *
  page182_i19
#CELL
  pure_quanta q_res *
  page182_i2
#CELL
  pure_quanta q_cap *
  page182_i20
#ISCELL
  pure_quanta_power universal_gnd *
  page182_i21
#CELL
  pure_quanta q_res *
  page182_i22
#ISCELL
  pure_quanta_power universal_gnd *
  page182_i23
#CELL
  pure_quanta raa229621gnpha0 *
  page182_i24
#CELL
  pure_quanta q_res *
  page182_i25
#ISCELL
  pure_quanta_power vcc_core *
  page182_i26
#ISCELL
  pure_quanta_power universal_gnd *
  page182_i27
#CELL
  pure_quanta q_res *
  page182_i28
#CELL
  pure_quanta q_cap *
  page182_i29
#ISCELL
  pure_quanta_power universal_gnd *
  page182_i3
#CELL
  pure_quanta q_res *
  page182_i30
#ISCELL
  pure_quanta_power vcc_core *
  page182_i31
#ISCELL
  standard offpage *
  page182_i32
#ISCELL
  standard offpage *
  page182_i33
#ISCELL
  standard offpage *
  page182_i34
#ISCELL
  standard offpage *
  page182_i35
#ISCELL
  standard offpage *
  page182_i36
#ISCELL
  pure_quanta_power vcc_core *
  page182_i37
#CELL
  pure_quanta q_res *
  page182_i38
#CELL
  pure_quanta q_res *
  page182_i39
#CELL
  pure_quanta q_cap *
  page182_i4
#CELL
  pure_quanta q_res *
  page182_i40
#CELL
  pure_quanta q_res *
  page182_i41
#ISCELL
  pure_quanta_power universal_gnd *
  page182_i42
#CELL
  pure_quanta q_res *
  page182_i43
#CELL
  pure_quanta q_res *
  page182_i44
#CELL
  pure_quanta q_cap *
  page182_i45
#ISCELL
  pure_quanta_power universal_gnd *
  page182_i46
#CELL
  pure_quanta q_cap *
  page182_i47
#ISCELL
  pure_quanta_power universal_gnd *
  page182_i48
#ISCELL
  pure_quanta_power universal_gnd *
  page182_i49
#ISCELL
  pure_quanta_power universal_gnd *
  page182_i5
#CELL
  pure_quanta q_cap *
  page182_i50
#ISCELL
  standard offpage *
  page182_i51
#CELL
  pure_quanta q_res *
  page182_i52
#CELL
  pure_quanta q_res *
  page182_i53
#ISCELL
  pure_quanta_power universal_gnd *
  page182_i54
#ISCELL
  pure_quanta_power universal_gnd *
  page182_i55
#ISCELL
  pure_quanta_power universal_gnd *
  page182_i56
#CELL
  pure_quanta q_res *
  page182_i57
#CELL
  pure_quanta q_res *
  page182_i58
#CELL
  pure_quanta q_res *
  page182_i59
#CELL
  pure_quanta q_res *
  page182_i6
#CELL
  pure_quanta q_res *
  page182_i60
#CELL
  pure_quanta q_res *
  page182_i61
#ISCELL
  pure_quanta_power universal_gnd *
  page182_i62
#ISCELL
  pure_quanta_power universal_gnd *
  page182_i63
#ISCELL
  pure_quanta_power universal_gnd *
  page182_i64
#ISCELL
  pure_quanta_power universal_gnd *
  page182_i65
#ISCELL
  pure_quanta_power universal_gnd *
  page182_i66
#CELL
  pure_quanta q_res *
  page182_i67
#CELL
  pure_quanta q_res *
  page182_i68
#ISCELL
  pure_quanta_power vcc_core *
  page182_i69
#ISCELL
  pure_quanta_power vcc_core *
  page182_i7
#ISCELL
  standard offpage *
  page182_i70
#CELL
  pure_quanta q_res *
  page182_i71
#ISCELL
  standard offpage *
  page182_i72
#ISCELL
  standard offpage *
  page182_i73
#ISCELL
  standard offpage *
  page182_i74
#ISCELL
  standard offpage *
  page182_i75
#ISCELL
  pure_quanta_power universal_gnd *
  page182_i76
#CELL
  pure_quanta q_cap *
  page182_i77
#ISCELL
  pure_quanta_power universal_gnd *
  page182_i78
#CELL
  pure_quanta q_cap *
  page182_i79
#ISCELL
  pure_quanta_power vcc_core *
  page182_i8
#CELL
  pure_quanta q_cap *
  page182_i80
#ISCELL
  pure_quanta_power universal_gnd *
  page182_i81
#CELL
  pure_quanta q_cap *
  page182_i82
#ISCELL
  pure_quanta_power universal_gnd *
  page182_i83
#ISCELL
  standard offpage *
  page182_i84
#CELL
  pure_quanta q_res *
  page182_i85
#ISCELL
  pure_quanta_power vcc_core *
  page182_i86
#ISCELL
  pure_quanta_power universal_gnd *
  page182_i87
#CELL
  pure_quanta q_cap *
  page182_i88
#CELL
  pure_quanta q_res *
  page182_i9
#ISCELL
  mstr_misc dns *
  *
#ISCELL
  pure_quanta quanta_title_block_c *
  *
#ISCELL
  standard offpage *
  page183_i1
#ISCELL
  pure_quanta_power universal_gnd *
  page183_i10
#CELL
  pure_quanta q_res *
  page183_i11
#ISCELL
  standard offpage *
  page183_i12
#CELL
  pure_quanta isl99390frztr5935 *
  page183_i13
#CELL
  pure_quanta q_res *
  page183_i14
#ISCELL
  pure_quanta_power vcc_core *
  page183_i15
#ISCELL
  pure_quanta_power universal_gnd *
  page183_i16
#CELL
  pure_quanta q_cap *
  page183_i17
#ISCELL
  pure_quanta_power universal_gnd *
  page183_i18
#ISCELL
  pure_quanta_power universal_gnd *
  page183_i19
#ISCELL
  standard offpage *
  page183_i2
#ISCELL
  standard offpage *
  page183_i20
#ISCELL
  standard offpage *
  page183_i21
#ISCELL
  pure_quanta_power universal_gnd *
  page183_i22
#ISCELL
  pure_quanta_power universal_gnd *
  page183_i23
#CELL
  pure_quanta q_res *
  page183_i24
#CELL
  pure_quanta q_res *
  page183_i25
#CELL
  pure_quanta q_cap *
  page183_i26
#CELL
  pure_quanta q_cap *
  page183_i27
#ISCELL
  pure_quanta_power universal_gnd *
  page183_i28
#CELL
  pure_quanta q_cap *
  page183_i29
#ISCELL
  pure_quanta_power vcc_core *
  page183_i3
#CELL
  pure_quanta q_cap *
  page183_i30
#CELL
  pure_quanta q_cap *
  page183_i31
#ISCELL
  pure_quanta_power universal_gnd *
  page183_i32
#CELL
  pure_quanta q_res *
  page183_i33
#CELL
  pure_quanta q_cap *
  page183_i34
#ISCELL
  pure_quanta_power universal_gnd *
  page183_i35
#CELL
  pure_quanta q_cap *
  page183_i36
#CELL
  pure_quanta q_res *
  page183_i37
#ISCELL
  standard offpage *
  page183_i38
#ISCELL
  pure_quanta_power universal_gnd *
  page183_i39
#ISCELL
  pure_quanta_power universal_gnd *
  page183_i4
#CELL
  pure_quanta q_res *
  page183_i40
#ISCELL
  pure_quanta_power vcc_core *
  page183_i41
#CELL
  pure_quanta q_cap *
  page183_i42
#ISCELL
  pure_quanta_power vcc_core *
  page183_i43
#CELL
  pure_quanta q_cap *
  page183_i44
#CELL
  pure_quanta q_cap *
  page183_i45
#CELL
  pure_quanta q_res *
  page183_i46
#CELL
  pure_quanta q_cap *
  page183_i47
#CELL
  pure_quanta q_cap *
  page183_i48
#CELL
  pure_quanta q_cap *
  page183_i49
#ISCELL
  standard offpage *
  page183_i5
#CELL
  pure_quanta q_cap *
  page183_i50
#CELL
  pure_quanta q_cap *
  page183_i51
#CELL
  pure_quanta q_inductor *
  page183_i52
#ISCELL
  pure_quanta_power universal_gnd *
  page183_i53
#CELL
  pure_quanta q_cap *
  page183_i54
#ISCELL
  pure_quanta_power vcc_core *
  page183_i55
#CELL
  pure_quanta q_res *
  page183_i56
#ISCELL
  pure_quanta_power universal_gnd *
  page183_i57
#CELL
  pure_quanta q_capp *
  page183_i58
#CELL
  pure_quanta q_capp *
  page183_i59
#ISCELL
  standard offpage *
  page183_i6
#ISCELL
  pure_quanta_power vcc_core *
  page183_i60
#ISCELL
  pure_quanta_power universal_gnd *
  page183_i61
#CELL
  pure_quanta q_cap *
  page183_i62
#ISCELL
  pure_quanta_power vcc_core *
  page183_i63
#ISCELL
  pure_quanta_power universal_gnd *
  page183_i64
#CELL
  pure_quanta q_capp *
  page183_i65
#CELL
  pure_quanta q_capp *
  page183_i66
#CELL
  pure_quanta q_capp *
  page183_i67
#ISCELL
  pure_quanta_power vcc_core *
  page183_i68
#ISCELL
  pure_quanta_power universal_gnd *
  page183_i69
#CELL
  pure_quanta q_cap *
  page183_i7
#CELL
  pure_quanta q_capp *
  page183_i70
#CELL
  pure_quanta q_cap *
  page183_i71
#ISCELL
  pure_quanta_power universal_gnd *
  page183_i72
#CELL
  pure_quanta q_inductor *
  page183_i73
#ISCELL
  pure_quanta_power vcc_core *
  page183_i74
#CELL
  pure_quanta q_capp *
  page183_i75
#CELL
  pure_quanta q_cap *
  page183_i76
#ISCELL
  pure_quanta_power universal_gnd *
  page183_i77
#CELL
  pure_quanta q_inductor *
  page183_i78
#CELL
  pure_quanta q_cap *
  page183_i79
#ISCELL
  pure_quanta_power universal_gnd *
  page183_i8
#ISCELL
  pure_quanta_power vcc_core *
  page183_i80
#CELL
  pure_quanta q_cap *
  page183_i81
#CELL
  pure_quanta q_cap *
  page183_i82
#CELL
  pure_quanta q_res *
  page183_i83
#ISCELL
  pure_quanta_power vcc_core *
  page183_i84
#CELL
  pure_quanta q_res *
  page183_i85
#CELL
  pure_quanta q_res *
  page183_i86
#CELL
  pure_quanta q_cap *
  page183_i87
#CELL
  pure_quanta q_cap *
  page183_i88
#CELL
  pure_quanta q_capp *
  page183_i89
#CELL
  pure_quanta q_cap *
  page183_i9
#CELL
  pure_quanta q_cap *
  page183_i90
#CELL
  pure_quanta q_res *
  page183_i91
#CELL
  pure_quanta isl99390frztr5935 *
  page183_i92
#CELL
  pure_quanta q_cap *
  page183_i93
#CELL
  pure_quanta q_cap *
  page183_i94
#CELL
  pure_quanta q_cap *
  page183_i95
#ISCELL
  mstr_misc dns *
  *
#ISCELL
  pure_quanta quanta_title_block_c *
  *
#ISCELL
  pure_quanta_power universal_gnd *
  page184_i1
#ISCELL
  pure_quanta_power universal_gnd *
  page184_i10
#CELL
  pure_quanta q_cap *
  page184_i11
#CELL
  pure_quanta q_res *
  page184_i12
#ISCELL
  pure_quanta_power universal_gnd *
  page184_i13
#ISCELL
  mstr_symbols universal_power *
  page184_i14
#CELL
  pure_quanta q_res *
  page184_i15
#ISCELL
  pure_quanta_power universal_gnd *
  page184_i16
#CELL
  pure_quanta q_res *
  page184_i17
#CELL
  pure_quanta mpq8633bglec838z *
  page184_i18
#ISCELL
  pure_quanta_power universal_gnd *
  page184_i19
#ISCELL
  standard offpage *
  page184_i2
#ISCELL
  pure_quanta_power universal_gnd *
  page184_i20
#CELL
  pure_quanta q_cap *
  page184_i21
#CELL
  pure_quanta q_cap *
  page184_i22
#CELL
  pure_quanta q_res *
  page184_i23
#CELL
  pure_quanta q_cap *
  page184_i24
#CELL
  pure_quanta q_cap *
  page184_i25
#CELL
  pure_quanta q_cap *
  page184_i26
#CELL
  pure_quanta q_cap *
  page184_i27
#CELL
  pure_quanta q_cap *
  page184_i28
#CELL
  pure_quanta q_res *
  page184_i29
#ISCELL
  pure_quanta_power universal_gnd *
  page184_i3
#ISCELL
  mstr_symbols universal_power *
  page184_i30
#CELL
  pure_quanta q_res *
  page184_i31
#ISCELL
  pure_quanta_power universal_gnd *
  page184_i32
#CELL
  pure_quanta q_cap *
  page184_i33
#CELL
  pure_quanta q_cap *
  page184_i34
#CELL
  pure_quanta q_res *
  page184_i35
#CELL
  pure_quanta q_inductor *
  page184_i36
#CELL
  pure_quanta q_res *
  page184_i37
#CELL
  pure_quanta q_res *
  page184_i38
#CELL
  pure_quanta q_cap *
  page184_i39
#CELL
  pure_quanta q_cap *
  page184_i4
#CELL
  pure_quanta q_cap *
  page184_i40
#CELL
  pure_quanta q_cap *
  page184_i41
#CELL
  pure_quanta q_res *
  page184_i42
#ISCELL
  standard offpage *
  page184_i43
#ISCELL
  standard offpage *
  page184_i44
#ISCELL
  pure_quanta_power universal_gnd *
  page184_i45
#CELL
  pure_quanta q_cap *
  page184_i46
#CELL
  pure_quanta q_capp *
  page184_i47
#CELL
  pure_quanta q_cap *
  page184_i48
#ISCELL
  pure_quanta_power universal_gnd *
  page184_i49
#CELL
  pure_quanta q_cap *
  page184_i5
#ISCELL
  pure_quanta_power p1v0 *
  page184_i50
#CELL
  pure_quanta q_res *
  page184_i51
#CELL
  pure_quanta q_res *
  page184_i52
#ISCELL
  standard offpage *
  page184_i53
#CELL
  pure_quanta q_cap *
  page184_i54
#ISCELL
  pure_quanta_power universal_gnd *
  page184_i55
#CELL
  pure_quanta q_cap *
  page184_i56
#CELL
  pure_quanta q_cap *
  page184_i57
#CELL
  pure_quanta q_res *
  page184_i58
#ISCELL
  mstr_symbols p1v0_aux *
  page184_i6
#CELL
  pure_quanta q_inductor *
  page184_i7
#CELL
  pure_quanta q_cap *
  page184_i8
#ISCELL
  pure_quanta_power universal_gnd *
  page184_i9
#ISCELL
  mstr_misc dns *
  *
#ISCELL
  pure_quanta quanta_title_block_c *
  *
#ISCELL
  standard offpage *
  page185_i1
#CELL
  pure_quanta q_res *
  page185_i10
#ISCELL
  standard offpage *
  page185_i100
#ISCELL
  standard offpage *
  page185_i101
#CELL
  pure_quanta q_res *
  page185_i102
#CELL
  pure_quanta q_res *
  page185_i103
#ISCELL
  pure_quanta_power universal_gnd *
  page185_i104
#ISCELL
  pure_quanta_power universal_gnd *
  page185_i105
#ISCELL
  pure_quanta_power universal_gnd *
  page185_i106
#CELL
  pure_quanta q_res *
  page185_i107
#ISCELL
  standard offpage *
  page185_i108
#ISCELL
  standard offpage *
  page185_i109
#ISCELL
  pure_quanta_power vcc_core *
  page185_i11
#ISCELL
  standard offpage *
  page185_i110
#ISCELL
  standard offpage *
  page185_i111
#ISCELL
  standard offpage *
  page185_i112
#ISCELL
  pure_quanta_power universal_gnd *
  page185_i113
#CELL
  pure_quanta q_cap *
  page185_i114
#ISCELL
  pure_quanta_power universal_gnd *
  page185_i115
#CELL
  pure_quanta q_cap *
  page185_i116
#ISCELL
  standard offpage *
  page185_i117
#ISCELL
  standard offpage *
  page185_i118
#ISCELL
  standard offpage *
  page185_i119
#ISCELL
  pure_quanta_power universal_gnd *
  page185_i12
#ISCELL
  standard offpage *
  page185_i120
#ISCELL
  standard offpage *
  page185_i121
#ISCELL
  standard offpage *
  page185_i122
#ISCELL
  standard offpage *
  page185_i123
#ISCELL
  pure_quanta_power universal_gnd *
  page185_i124
#CELL
  pure_quanta q_cap *
  page185_i125
#ISCELL
  pure_quanta_power universal_gnd *
  page185_i126
#CELL
  pure_quanta q_cap *
  page185_i127
#ISCELL
  standard offpage *
  page185_i128
#CELL
  pure_quanta q_res *
  page185_i129
#CELL
  pure_quanta q_cap *
  page185_i13
#ISCELL
  pure_quanta_power vcc_core *
  page185_i130
#ISCELL
  pure_quanta_power vcc_core *
  page185_i131
#CELL
  pure_quanta q_cap *
  page185_i132
#CELL
  pure_quanta raa229620gnpha0 *
  page185_i133
#CELL
  pure_quanta q_res *
  page185_i135
#ISCELL
  pure_quanta_power universal_gnd *
  page185_i136
#CELL
  pure_quanta q_cap *
  page185_i137
#ISCELL
  pure_quanta_power universal_gnd *
  page185_i138
#CELL
  pure_quanta q_cap *
  page185_i139
#CELL
  pure_quanta q_res *
  page185_i14
#ISCELL
  pure_quanta_power universal_gnd *
  page185_i140
#CELL
  pure_quanta q_cap *
  page185_i141
#CELL
  pure_quanta q_res *
  page185_i142
#CELL
  pure_quanta q_res *
  page185_i143
#CELL
  pure_quanta q_res *
  page185_i144
#ISCELL
  standard offpage *
  page185_i15
#CELL
  pure_quanta mosfet_n *
  page185_i16
#CELL
  pure_quanta q_res *
  page185_i17
#CELL
  pure_quanta mosfet_pch_gds_esd_protected *
  page185_i18
#ISCELL
  pure_quanta_power universal_gnd *
  page185_i19
#CELL
  pure_quanta q_res *
  page185_i2
#CELL
  pure_quanta q_res *
  page185_i20
#ISCELL
  pure_quanta_power universal_gnd *
  page185_i21
#CELL
  pure_quanta q_cap *
  page185_i22
#CELL
  pure_quanta q_res *
  page185_i23
#ISCELL
  pure_quanta_power vcc_core *
  page185_i24
#ISCELL
  pure_quanta_power universal_gnd *
  page185_i25
#CELL
  pure_quanta q_res *
  page185_i27
#ISCELL
  pure_quanta_power vcc_core *
  page185_i28
#ISCELL
  pure_quanta_power vcc_core *
  page185_i29
#ISCELL
  pure_quanta_power universal_gnd *
  page185_i3
#ISCELL
  pure_quanta_power vcc_core *
  page185_i30
#ISCELL
  standard offpage *
  page185_i31
#ISCELL
  standard offpage *
  page185_i32
#ISCELL
  standard offpage *
  page185_i33
#ISCELL
  standard offpage *
  page185_i34
#ISCELL
  pure_quanta_power universal_gnd *
  page185_i35
#CELL
  pure_quanta q_res *
  page185_i36
#ISCELL
  standard offpage *
  page185_i37
#ISCELL
  standard offpage *
  page185_i38
#CELL
  pure_quanta q_res *
  page185_i39
#CELL
  pure_quanta q_res *
  page185_i4
#ISCELL
  pure_quanta_power vcc_core *
  page185_i40
#CELL
  pure_quanta q_res *
  page185_i41
#CELL
  pure_quanta q_res *
  page185_i42
#CELL
  pure_quanta q_res *
  page185_i43
#ISCELL
  pure_quanta_power vcc_core *
  page185_i44
#CELL
  pure_quanta q_res *
  page185_i45
#ISCELL
  pure_quanta_power universal_gnd *
  page185_i46
#CELL
  pure_quanta q_res *
  page185_i47
#CELL
  pure_quanta q_res *
  page185_i48
#ISCELL
  pure_quanta_power universal_gnd *
  page185_i49
#ISCELL
  pure_quanta_power universal_gnd *
  page185_i5
#ISCELL
  pure_quanta_power universal_gnd *
  page185_i50
#CELL
  pure_quanta q_cap *
  page185_i51
#CELL
  pure_quanta q_cap *
  page185_i52
#ISCELL
  pure_quanta_power universal_gnd *
  page185_i53
#CELL
  pure_quanta q_res *
  page185_i54
#ISCELL
  pure_quanta_power universal_gnd *
  page185_i55
#ISCELL
  pure_quanta_power universal_gnd *
  page185_i56
#CELL
  pure_quanta q_res *
  page185_i57
#CELL
  pure_quanta q_cap *
  page185_i58
#CELL
  pure_quanta q_res *
  page185_i59
#CELL
  pure_quanta q_res *
  page185_i6
#CELL
  pure_quanta q_cap *
  page185_i60
#ISCELL
  pure_quanta_power universal_gnd *
  page185_i61
#CELL
  pure_quanta q_cap *
  page185_i62
#ISCELL
  pure_quanta_power universal_gnd *
  page185_i63
#CELL
  pure_quanta q_cap *
  page185_i64
#ISCELL
  pure_quanta_power universal_gnd *
  page185_i65
#CELL
  pure_quanta q_cap *
  page185_i66
#CELL
  pure_quanta q_res *
  page185_i67
#CELL
  pure_quanta q_res *
  page185_i68
#CELL
  pure_quanta q_res *
  page185_i69
#ISCELL
  standard offpage *
  page185_i7
#CELL
  pure_quanta q_res *
  page185_i70
#ISCELL
  pure_quanta_power vcc_core *
  page185_i71
#ISCELL
  standard offpage *
  page185_i72
#ISCELL
  standard offpage *
  page185_i73
#ISCELL
  standard offpage *
  page185_i74
#ISCELL
  standard offpage *
  page185_i75
#ISCELL
  standard offpage *
  page185_i76
#ISCELL
  pure_quanta_power vcc_core *
  page185_i77
#CELL
  pure_quanta q_res *
  page185_i78
#CELL
  pure_quanta q_res *
  page185_i79
#ISCELL
  standard offpage *
  page185_i8
#CELL
  pure_quanta q_res *
  page185_i80
#CELL
  pure_quanta q_res *
  page185_i81
#CELL
  pure_quanta q_res *
  page185_i82
#CELL
  pure_quanta q_res *
  page185_i83
#CELL
  pure_quanta q_res *
  page185_i84
#CELL
  pure_quanta q_res *
  page185_i85
#CELL
  pure_quanta q_cap *
  page185_i86
#ISCELL
  pure_quanta_power universal_gnd *
  page185_i87
#CELL
  pure_quanta q_cap *
  page185_i88
#ISCELL
  pure_quanta_power universal_gnd *
  page185_i89
#ISCELL
  standard offpage *
  page185_i9
#ISCELL
  pure_quanta_power universal_gnd *
  page185_i90
#CELL
  pure_quanta q_cap *
  page185_i91
#ISCELL
  standard offpage *
  page185_i92
#ISCELL
  pure_quanta_power universal_gnd *
  page185_i93
#CELL
  pure_quanta q_cap *
  page185_i94
#ISCELL
  standard offpage *
  page185_i95
#ISCELL
  standard offpage *
  page185_i96
#ISCELL
  standard offpage *
  page185_i97
#ISCELL
  standard offpage *
  page185_i98
#ISCELL
  standard offpage *
  page185_i99
#ISCELL
  mstr_misc dns *
  *
#ISCELL
  pure_quanta quanta_title_block_c *
  *
#ISCELL
  standard offpage *
  page186_i1
#ISCELL
  pure_quanta_power universal_gnd *
  page186_i10
#CELL
  pure_quanta q_res *
  page186_i11
#ISCELL
  pure_quanta_power universal_gnd *
  page186_i12
#CELL
  pure_quanta q_cap *
  page186_i13
#ISCELL
  pure_quanta_power vcc_core *
  page186_i14
#ISCELL
  pure_quanta_power universal_gnd *
  page186_i15
#CELL
  pure_quanta q_cap *
  page186_i16
#ISCELL
  pure_quanta_power universal_gnd *
  page186_i17
#ISCELL
  standard offpage *
  page186_i18
#ISCELL
  standard offpage *
  page186_i19
#ISCELL
  standard offpage *
  page186_i2
#ISCELL
  pure_quanta_power universal_gnd *
  page186_i20
#ISCELL
  pure_quanta_power universal_gnd *
  page186_i21
#CELL
  pure_quanta q_res *
  page186_i22
#CELL
  pure_quanta q_res *
  page186_i23
#CELL
  pure_quanta q_cap *
  page186_i24
#CELL
  pure_quanta q_cap *
  page186_i25
#CELL
  pure_quanta q_cap *
  page186_i26
#ISCELL
  pure_quanta_power universal_gnd *
  page186_i27
#CELL
  pure_quanta q_cap *
  page186_i28
#CELL
  pure_quanta q_cap *
  page186_i29
#CELL
  pure_quanta q_res *
  page186_i3
#ISCELL
  pure_quanta_power universal_gnd *
  page186_i30
#CELL
  pure_quanta q_cap *
  page186_i31
#ISCELL
  pure_quanta_power vcc_core *
  page186_i32
#ISCELL
  pure_quanta_power universal_gnd *
  page186_i33
#CELL
  pure_quanta q_res *
  page186_i34
#CELL
  pure_quanta q_res *
  page186_i35
#CELL
  pure_quanta q_cap *
  page186_i36
#CELL
  pure_quanta q_res *
  page186_i37
#ISCELL
  standard offpage *
  page186_i38
#ISCELL
  pure_quanta_power universal_gnd *
  page186_i39
#ISCELL
  pure_quanta_power vcc_core *
  page186_i4
#ISCELL
  pure_quanta_power universal_gnd *
  page186_i40
#CELL
  pure_quanta q_res *
  page186_i41
#ISCELL
  pure_quanta_power vcc_core *
  page186_i42
#CELL
  pure_quanta q_res *
  page186_i43
#CELL
  pure_quanta q_cap *
  page186_i44
#ISCELL
  pure_quanta_power vcc_core *
  page186_i45
#CELL
  pure_quanta q_cap *
  page186_i46
#CELL
  pure_quanta q_cap *
  page186_i47
#CELL
  pure_quanta q_cap *
  page186_i48
#CELL
  pure_quanta q_res *
  page186_i49
#CELL
  pure_quanta q_cap *
  page186_i5
#ISCELL
  standard offpage *
  page186_i50
#CELL
  pure_quanta q_cap *
  page186_i51
#CELL
  pure_quanta q_cap *
  page186_i52
#CELL
  pure_quanta q_cap *
  page186_i53
#ISCELL
  standard offpage *
  page186_i54
#CELL
  pure_quanta q_cap *
  page186_i55
#CELL
  pure_quanta q_inductor4p_14 *
  page186_i56
#ISCELL
  standard offpage *
  page186_i57
#CELL
  pure_quanta q_capp *
  page186_i58
#CELL
  pure_quanta q_capp *
  page186_i59
#ISCELL
  standard offpage *
  page186_i6
#CELL
  pure_quanta q_capp *
  page186_i60
#CELL
  pure_quanta q_cap *
  page186_i61
#ISCELL
  pure_quanta_power universal_gnd *
  page186_i62
#CELL
  pure_quanta q_cap *
  page186_i63
#ISCELL
  pure_quanta_power vcc_core *
  page186_i64
#ISCELL
  pure_quanta_power universal_gnd *
  page186_i65
#CELL
  pure_quanta q_capp *
  page186_i66
#ISCELL
  pure_quanta_power vcc_core *
  page186_i67
#ISCELL
  pure_quanta_power universal_gnd *
  page186_i68
#ISCELL
  pure_quanta_power universal_gnd *
  page186_i69
#ISCELL
  standard offpage *
  page186_i7
#CELL
  pure_quanta q_capp *
  page186_i70
#CELL
  pure_quanta q_capp *
  page186_i71
#ISCELL
  standard offpage *
  page186_i72
#CELL
  pure_quanta q_inductor *
  page186_i73
#CELL
  pure_quanta q_cap *
  page186_i74
#ISCELL
  pure_quanta_power vcc_core *
  page186_i75
#CELL
  pure_quanta q_cap *
  page186_i76
#CELL
  pure_quanta q_cap *
  page186_i77
#CELL
  pure_quanta q_res *
  page186_i78
#ISCELL
  pure_quanta_power vcc_core *
  page186_i79
#ISCELL
  standard offpage *
  page186_i8
#CELL
  pure_quanta q_res *
  page186_i80
#ISCELL
  pure_quanta_power universal_gnd *
  page186_i81
#ISCELL
  pure_quanta_power universal_gnd *
  page186_i82
#CELL
  pure_quanta q_res *
  page186_i83
#CELL
  pure_quanta q_capp *
  page186_i84
#CELL
  pure_quanta q_cap *
  page186_i85
#ISCELL
  pure_quanta_power universal_gnd *
  page186_i86
#ISCELL
  pure_quanta_power vcc_core *
  page186_i87
#CELL
  pure_quanta isl99390frztr5935 *
  page186_i88
#CELL
  pure_quanta q_cap *
  page186_i89
#CELL
  pure_quanta q_cap *
  page186_i9
#CELL
  pure_quanta q_inductor4p_14 *
  page186_i90
#CELL
  pure_quanta isl99390frztr5935 *
  page186_i91
#ISCELL
  mstr_misc dns *
  *
#ISCELL
  pure_quanta quanta_title_block_c *
  *
#ISCELL
  standard offpage *
  page187_i1
#ISCELL
  standard offpage *
  page187_i10
#CELL
  pure_quanta q_res *
  page187_i11
#CELL
  pure_quanta q_res *
  page187_i12
#ISCELL
  pure_quanta_power vcc_core *
  page187_i13
#ISCELL
  pure_quanta_power universal_gnd *
  page187_i14
#CELL
  pure_quanta q_cap *
  page187_i15
#ISCELL
  pure_quanta_power universal_gnd *
  page187_i16
#CELL
  pure_quanta q_res *
  page187_i17
#ISCELL
  pure_quanta_power universal_gnd *
  page187_i18
#CELL
  pure_quanta q_res *
  page187_i19
#CELL
  pure_quanta q_cap *
  page187_i2
#CELL
  pure_quanta q_cap *
  page187_i20
#CELL
  pure_quanta q_res *
  page187_i21
#CELL
  pure_quanta q_cap *
  page187_i22
#CELL
  pure_quanta q_cap *
  page187_i23
#CELL
  pure_quanta q_cap *
  page187_i24
#CELL
  pure_quanta q_cap *
  page187_i25
#ISCELL
  pure_quanta_power universal_gnd *
  page187_i26
#CELL
  pure_quanta q_res *
  page187_i27
#CELL
  pure_quanta q_cap *
  page187_i28
#ISCELL
  pure_quanta_power universal_gnd *
  page187_i29
#ISCELL
  pure_quanta_power universal_gnd *
  page187_i3
#ISCELL
  standard offpage *
  page187_i30
#ISCELL
  pure_quanta_power universal_gnd *
  page187_i31
#ISCELL
  standard offpage *
  page187_i32
#ISCELL
  standard offpage *
  page187_i33
#CELL
  pure_quanta q_res *
  page187_i34
#ISCELL
  pure_quanta_power universal_gnd *
  page187_i35
#ISCELL
  standard offpage *
  page187_i36
#CELL
  pure_quanta q_cap *
  page187_i37
#CELL
  pure_quanta q_res *
  page187_i38
#CELL
  pure_quanta isl99390frztr5935 *
  page187_i39
#ISCELL
  pure_quanta_power universal_gnd *
  page187_i4
#ISCELL
  pure_quanta_power universal_gnd *
  page187_i40
#CELL
  pure_quanta q_cap *
  page187_i41
#ISCELL
  pure_quanta_power vcc_core *
  page187_i42
#ISCELL
  pure_quanta_power universal_gnd *
  page187_i43
#CELL
  pure_quanta q_cap *
  page187_i44
#CELL
  pure_quanta q_res *
  page187_i45
#CELL
  pure_quanta q_cap *
  page187_i46
#CELL
  pure_quanta q_res *
  page187_i47
#CELL
  pure_quanta q_cap *
  page187_i48
#CELL
  pure_quanta q_cap *
  page187_i49
#ISCELL
  pure_quanta_power universal_gnd *
  page187_i5
#CELL
  pure_quanta q_cap *
  page187_i50
#ISCELL
  standard offpage *
  page187_i51
#CELL
  pure_quanta q_cap *
  page187_i52
#CELL
  pure_quanta q_inductor4p_14 *
  page187_i53
#ISCELL
  pure_quanta_power universal_gnd *
  page187_i54
#CELL
  pure_quanta q_cap *
  page187_i55
#ISCELL
  pure_quanta_power vcc_core *
  page187_i56
#ISCELL
  pure_quanta_power universal_gnd *
  page187_i57
#CELL
  pure_quanta q_cap *
  page187_i58
#ISCELL
  pure_quanta_power universal_gnd *
  page187_i59
#CELL
  pure_quanta q_cap *
  page187_i6
#CELL
  pure_quanta q_cap *
  page187_i60
#ISCELL
  pure_quanta_power vcc_core *
  page187_i61
#ISCELL
  standard offpage *
  page187_i62
#CELL
  pure_quanta q_cap *
  page187_i63
#ISCELL
  pure_quanta_power universal_gnd *
  page187_i64
#CELL
  pure_quanta q_cap *
  page187_i65
#ISCELL
  pure_quanta_power vcc_core *
  page187_i66
#CELL
  pure_quanta q_inductor4p_14 *
  page187_i67
#ISCELL
  standard offpage *
  page187_i68
#CELL
  pure_quanta q_cap *
  page187_i69
#ISCELL
  standard offpage *
  page187_i7
#ISCELL
  pure_quanta_power universal_gnd *
  page187_i70
#CELL
  pure_quanta q_cap *
  page187_i71
#ISCELL
  pure_quanta_power vcc_core *
  page187_i72
#ISCELL
  standard offpage *
  page187_i8
#CELL
  pure_quanta isl99390frztr5935 *
  page187_i9
#ISCELL
  mstr_misc dns *
  *
#ISCELL
  pure_quanta quanta_title_block_c *
  *
#ISCELL
  standard offpage *
  page188_i1
#CELL
  pure_quanta q_cap *
  page188_i10
#ISCELL
  standard offpage *
  page188_i11
#CELL
  pure_quanta q_res *
  page188_i12
#ISCELL
  pure_quanta_power universal_gnd *
  page188_i13
#ISCELL
  pure_quanta_power vcc_core *
  page188_i14
#CELL
  pure_quanta q_cap *
  page188_i15
#ISCELL
  pure_quanta_power universal_gnd *
  page188_i16
#ISCELL
  standard offpage *
  page188_i17
#CELL
  pure_quanta isl99390frztr5935 *
  page188_i18
#ISCELL
  pure_quanta_power universal_gnd *
  page188_i19
#ISCELL
  standard offpage *
  page188_i2
#ISCELL
  pure_quanta_power universal_gnd *
  page188_i20
#CELL
  pure_quanta q_res *
  page188_i21
#CELL
  pure_quanta q_res *
  page188_i22
#CELL
  pure_quanta q_cap *
  page188_i23
#ISCELL
  pure_quanta_power universal_gnd *
  page188_i24
#CELL
  pure_quanta q_cap *
  page188_i25
#ISCELL
  pure_quanta_power universal_gnd *
  page188_i26
#CELL
  pure_quanta q_cap *
  page188_i27
#CELL
  pure_quanta q_res *
  page188_i28
#CELL
  pure_quanta q_cap *
  page188_i29
#ISCELL
  pure_quanta_power universal_gnd *
  page188_i3
#CELL
  pure_quanta q_cap *
  page188_i30
#ISCELL
  pure_quanta_power universal_gnd *
  page188_i31
#CELL
  pure_quanta q_res *
  page188_i32
#CELL
  pure_quanta q_res *
  page188_i33
#CELL
  pure_quanta q_cap *
  page188_i34
#ISCELL
  pure_quanta_power universal_gnd *
  page188_i35
#ISCELL
  standard offpage *
  page188_i36
#CELL
  pure_quanta q_res *
  page188_i37
#ISCELL
  pure_quanta_power universal_gnd *
  page188_i38
#CELL
  pure_quanta q_cap *
  page188_i39
#CELL
  pure_quanta q_cap *
  page188_i4
#ISCELL
  standard offpage *
  page188_i40
#CELL
  pure_quanta q_res *
  page188_i41
#ISCELL
  pure_quanta_power universal_gnd *
  page188_i42
#CELL
  pure_quanta q_cap *
  page188_i43
#ISCELL
  pure_quanta_power vcc_core *
  page188_i44
#CELL
  pure_quanta q_cap *
  page188_i45
#CELL
  pure_quanta q_cap *
  page188_i46
#CELL
  pure_quanta q_res *
  page188_i47
#CELL
  pure_quanta q_cap *
  page188_i48
#CELL
  pure_quanta q_cap *
  page188_i49
#ISCELL
  pure_quanta_power universal_gnd *
  page188_i5
#CELL
  pure_quanta q_cap *
  page188_i50
#CELL
  pure_quanta q_inductor *
  page188_i51
#CELL
  pure_quanta q_cap *
  page188_i52
#CELL
  pure_quanta q_inductor4p_14 *
  page188_i53
#ISCELL
  pure_quanta_power universal_gnd *
  page188_i54
#CELL
  pure_quanta q_cap *
  page188_i55
#ISCELL
  pure_quanta_power vcc_core *
  page188_i56
#ISCELL
  standard offpage *
  page188_i57
#CELL
  pure_quanta q_cap *
  page188_i58
#ISCELL
  pure_quanta_power universal_gnd *
  page188_i59
#ISCELL
  standard offpage *
  page188_i6
#CELL
  pure_quanta q_cap *
  page188_i60
#ISCELL
  pure_quanta_power vcc_core *
  page188_i61
#ISCELL
  standard offpage *
  page188_i62
#CELL
  pure_quanta q_cap *
  page188_i63
#CELL
  pure_quanta q_inductor4p_14 *
  page188_i64
#ISCELL
  pure_quanta_power universal_gnd *
  page188_i65
#CELL
  pure_quanta q_cap *
  page188_i66
#ISCELL
  pure_quanta_power vcc_core *
  page188_i67
#ISCELL
  standard offpage *
  page188_i68
#CELL
  pure_quanta q_cap *
  page188_i69
#ISCELL
  standard offpage *
  page188_i7
#ISCELL
  pure_quanta_power universal_gnd *
  page188_i70
#CELL
  pure_quanta q_cap *
  page188_i71
#ISCELL
  pure_quanta_power vcc_core *
  page188_i72
#CELL
  pure_quanta isl99390frztr5935 *
  page188_i73
#CELL
  pure_quanta q_res *
  page188_i8
#ISCELL
  pure_quanta_power universal_gnd *
  page188_i9
#ISCELL
  pure_quanta quanta_title_block_c *
  *
#ISCELL
  mstr_misc dns *
  *
#ISCELL
  pure_quanta quanta_title_block_c *
  *
#ISCELL
  standard offpage *
  page190_i1
#ISCELL
  pure_quanta_power universal_gnd *
  page190_i10
#CELL
  pure_quanta q_cap *
  page190_i11
#CELL
  pure_quanta q_res *
  page190_i12
#ISCELL
  pure_quanta_power vcc_core *
  page190_i13
#CELL
  pure_quanta q_cap *
  page190_i14
#ISCELL
  pure_quanta_power universal_gnd *
  page190_i15
#ISCELL
  standard offpage *
  page190_i16
#CELL
  pure_quanta isl99390frztr5935 *
  page190_i17
#ISCELL
  pure_quanta_power universal_gnd *
  page190_i18
#ISCELL
  pure_quanta_power universal_gnd *
  page190_i19
#ISCELL
  standard offpage *
  page190_i2
#CELL
  pure_quanta q_cap *
  page190_i20
#CELL
  pure_quanta q_res *
  page190_i21
#CELL
  pure_quanta q_cap *
  page190_i22
#ISCELL
  pure_quanta_power universal_gnd *
  page190_i23
#CELL
  pure_quanta q_res *
  page190_i24
#CELL
  pure_quanta q_cap *
  page190_i25
#CELL
  pure_quanta q_cap *
  page190_i26
#CELL
  pure_quanta q_cap *
  page190_i27
#ISCELL
  pure_quanta_power universal_gnd *
  page190_i28
#CELL
  pure_quanta q_res *
  page190_i29
#ISCELL
  pure_quanta_power universal_gnd *
  page190_i3
#CELL
  pure_quanta q_res *
  page190_i30
#ISCELL
  pure_quanta_power universal_gnd *
  page190_i31
#CELL
  pure_quanta q_cap *
  page190_i32
#ISCELL
  pure_quanta_power universal_gnd *
  page190_i33
#ISCELL
  standard offpage *
  page190_i34
#CELL
  pure_quanta q_res *
  page190_i35
#CELL
  pure_quanta q_cap *
  page190_i36
#ISCELL
  pure_quanta_power universal_gnd *
  page190_i37
#ISCELL
  standard offpage *
  page190_i38
#CELL
  pure_quanta q_res *
  page190_i39
#CELL
  pure_quanta q_cap *
  page190_i4
#ISCELL
  pure_quanta_power universal_gnd *
  page190_i40
#CELL
  pure_quanta q_cap *
  page190_i41
#ISCELL
  pure_quanta_power vcc_core *
  page190_i42
#CELL
  pure_quanta q_cap *
  page190_i43
#CELL
  pure_quanta q_cap *
  page190_i44
#CELL
  pure_quanta q_cap *
  page190_i45
#CELL
  pure_quanta q_res *
  page190_i46
#ISCELL
  standard offpage *
  page190_i47
#CELL
  pure_quanta q_cap *
  page190_i48
#CELL
  pure_quanta q_cap *
  page190_i49
#ISCELL
  pure_quanta_power universal_gnd *
  page190_i5
#CELL
  pure_quanta q_cap *
  page190_i50
#ISCELL
  standard offpage *
  page190_i51
#CELL
  pure_quanta q_inductor4p_14 *
  page190_i52
#ISCELL
  standard offpage *
  page190_i53
#CELL
  pure_quanta q_cap *
  page190_i54
#ISCELL
  pure_quanta_power universal_gnd *
  page190_i55
#CELL
  pure_quanta q_cap *
  page190_i56
#CELL
  pure_quanta q_cap *
  page190_i57
#ISCELL
  pure_quanta_power vcc_core *
  page190_i58
#CELL
  pure_quanta q_capp *
  page190_i59
#ISCELL
  standard offpage *
  page190_i6
#CELL
  pure_quanta q_cap *
  page190_i60
#ISCELL
  pure_quanta_power universal_gnd *
  page190_i61
#CELL
  pure_quanta q_cap *
  page190_i62
#CELL
  pure_quanta q_capp *
  page190_i63
#ISCELL
  pure_quanta_power vcc_core *
  page190_i64
#ISCELL
  pure_quanta_power universal_gnd *
  page190_i65
#CELL
  pure_quanta q_capp *
  page190_i66
#ISCELL
  pure_quanta_power vcc_core *
  page190_i67
#CELL
  pure_quanta q_cap *
  page190_i68
#CELL
  pure_quanta q_inductor4p_14 *
  page190_i69
#ISCELL
  standard offpage *
  page190_i7
#ISCELL
  pure_quanta_power universal_gnd *
  page190_i70
#CELL
  pure_quanta q_cap *
  page190_i71
#ISCELL
  pure_quanta_power vcc_core *
  page190_i72
#CELL
  pure_quanta q_capp *
  page190_i73
#CELL
  pure_quanta q_inductor *
  page190_i74
#ISCELL
  pure_quanta_power universal_gnd *
  page190_i75
#ISCELL
  pure_quanta_power universal_gnd *
  page190_i76
#CELL
  pure_quanta q_cap *
  page190_i77
#ISCELL
  pure_quanta_power vcc_core *
  page190_i78
#CELL
  pure_quanta q_cap *
  page190_i79
#CELL
  pure_quanta q_res *
  page190_i8
#CELL
  pure_quanta q_cap *
  page190_i80
#CELL
  pure_quanta q_cap *
  page190_i81
#ISCELL
  pure_quanta_power universal_gnd *
  page190_i82
#CELL
  pure_quanta q_res *
  page190_i83
#ISCELL
  pure_quanta_power vcc_core *
  page190_i84
#CELL
  pure_quanta q_res *
  page190_i85
#CELL
  pure_quanta isl99390frztr5935 *
  page190_i86
#CELL
  pure_quanta q_cap *
  page190_i87
#CELL
  pure_quanta q_cap *
  page190_i88
#ISCELL
  standard offpage *
  page190_i9
#ISCELL
  mstr_misc dns *
  *
#ISCELL
  pure_quanta quanta_title_block_c *
  *
#ISCELL
  standard offpage *
  page191_i1
#CELL
  pure_quanta q_res *
  page191_i10
#CELL
  pure_quanta q_cap *
  page191_i11
#ISCELL
  pure_quanta_power universal_gnd *
  page191_i12
#CELL
  pure_quanta q_cap *
  page191_i13
#CELL
  pure_quanta q_res *
  page191_i14
#ISCELL
  pure_quanta_power vcc_core *
  page191_i15
#ISCELL
  standard offpage *
  page191_i16
#ISCELL
  pure_quanta_power universal_gnd *
  page191_i17
#CELL
  pure_quanta q_cap *
  page191_i18
#CELL
  pure_quanta q_cap *
  page191_i19
#CELL
  pure_quanta q_cap *
  page191_i2
#CELL
  pure_quanta q_cap *
  page191_i20
#CELL
  pure_quanta q_res *
  page191_i21
#CELL
  pure_quanta q_cap *
  page191_i22
#CELL
  pure_quanta q_res *
  page191_i23
#ISCELL
  pure_quanta_power universal_gnd *
  page191_i24
#CELL
  pure_quanta q_inductor *
  page191_i25
#CELL
  pure_quanta q_inductor4p_14 *
  page191_i26
#ISCELL
  standard offpage *
  page191_i27
#CELL
  pure_quanta q_cap *
  page191_i28
#ISCELL
  pure_quanta_power universal_gnd *
  page191_i29
#ISCELL
  pure_quanta_power universal_gnd *
  page191_i3
#CELL
  pure_quanta q_cap *
  page191_i30
#CELL
  pure_quanta q_cap *
  page191_i31
#CELL
  pure_quanta q_cap *
  page191_i32
#CELL
  pure_quanta q_cap *
  page191_i33
#CELL
  pure_quanta q_cap *
  page191_i34
#ISCELL
  pure_quanta_power universal_gnd *
  page191_i35
#ISCELL
  pure_quanta_power vcc_core *
  page191_i36
#ISCELL
  pure_quanta_power vcc_core *
  page191_i37
#CELL
  pure_quanta isl99390frztr5935 *
  page191_i38
#ISCELL
  pure_quanta_power universal_gnd *
  page191_i4
#ISCELL
  standard offpage *
  page191_i5
#ISCELL
  standard offpage *
  page191_i6
#CELL
  pure_quanta q_res *
  page191_i7
#ISCELL
  pure_quanta_power universal_gnd *
  page191_i8
#ISCELL
  pure_quanta_power universal_gnd *
  page191_i9
#ISCELL
  mstr_misc dns *
  *
#ISCELL
  pure_quanta quanta_title_block_c *
  *
#ISCELL
  standard offpage *
  page192_i1
#ISCELL
  pure_quanta_power vcc_core *
  page192_i10
#ISCELL
  standard offpage *
  page192_i100
#ISCELL
  standard offpage *
  page192_i101
#ISCELL
  standard offpage *
  page192_i102
#ISCELL
  standard offpage *
  page192_i103
#ISCELL
  standard offpage *
  page192_i104
#ISCELL
  standard offpage *
  page192_i105
#ISCELL
  standard offpage *
  page192_i106
#ISCELL
  standard offpage *
  page192_i107
#ISCELL
  standard offpage *
  page192_i108
#ISCELL
  pure_quanta_power universal_gnd *
  page192_i109
#ISCELL
  pure_quanta_power vcc_core *
  page192_i11
#ISCELL
  pure_quanta_power universal_gnd *
  page192_i110
#ISCELL
  standard offpage *
  page192_i111
#ISCELL
  standard offpage *
  page192_i112
#ISCELL
  standard offpage *
  page192_i113
#ISCELL
  standard offpage *
  page192_i114
#ISCELL
  standard offpage *
  page192_i115
#ISCELL
  standard offpage *
  page192_i116
#ISCELL
  standard offpage *
  page192_i117
#ISCELL
  standard offpage *
  page192_i118
#ISCELL
  standard offpage *
  page192_i119
#CELL
  pure_quanta q_res *
  page192_i12
#ISCELL
  standard offpage *
  page192_i120
#ISCELL
  standard offpage *
  page192_i121
#ISCELL
  standard offpage *
  page192_i122
#ISCELL
  standard offpage *
  page192_i123
#CELL
  pure_quanta q_res *
  page192_i124
#ISCELL
  pure_quanta_power vcc_core *
  page192_i125
#ISCELL
  standard offpage *
  page192_i126
#CELL
  pure_quanta q_res *
  page192_i127
#CELL
  pure_quanta raa229620gnpha0 *
  page192_i128
#CELL
  pure_quanta mosfet_pch_gds_esd_protected *
  page192_i13
#CELL
  pure_quanta q_res *
  page192_i130
#CELL
  pure_quanta q_cap *
  page192_i131
#ISCELL
  pure_quanta_power universal_gnd *
  page192_i132
#CELL
  pure_quanta q_cap *
  page192_i133
#ISCELL
  pure_quanta_power universal_gnd *
  page192_i134
#ISCELL
  pure_quanta_power universal_gnd *
  page192_i135
#CELL
  pure_quanta q_cap *
  page192_i136
#CELL
  pure_quanta q_res *
  page192_i137
#CELL
  pure_quanta q_res *
  page192_i138
#ISCELL
  standard offpage *
  page192_i14
#ISCELL
  standard offpage *
  page192_i15
#ISCELL
  standard offpage *
  page192_i16
#CELL
  pure_quanta q_res *
  page192_i17
#ISCELL
  pure_quanta_power vcc_core *
  page192_i18
#CELL
  pure_quanta q_res *
  page192_i19
#CELL
  pure_quanta q_res *
  page192_i2
#ISCELL
  standard offpage *
  page192_i20
#ISCELL
  standard offpage *
  page192_i21
#CELL
  pure_quanta q_res *
  page192_i22
#CELL
  pure_quanta q_res *
  page192_i23
#ISCELL
  standard offpage *
  page192_i24
#ISCELL
  standard offpage *
  page192_i25
#ISCELL
  standard offpage *
  page192_i26
#ISCELL
  standard offpage *
  page192_i27
#ISCELL
  pure_quanta_power universal_gnd *
  page192_i28
#CELL
  pure_quanta q_res *
  page192_i29
#CELL
  pure_quanta q_cap *
  page192_i3
#CELL
  pure_quanta q_res *
  page192_i30
#CELL
  pure_quanta q_cap *
  page192_i31
#CELL
  pure_quanta q_cap *
  page192_i32
#CELL
  pure_quanta q_cap *
  page192_i33
#CELL
  pure_quanta q_res *
  page192_i34
#ISCELL
  standard offpage *
  page192_i35
#ISCELL
  standard offpage *
  page192_i36
#ISCELL
  standard offpage *
  page192_i37
#CELL
  pure_quanta q_res *
  page192_i38
#ISCELL
  pure_quanta_power vcc_core *
  page192_i39
#ISCELL
  pure_quanta_power universal_gnd *
  page192_i4
#CELL
  pure_quanta q_res *
  page192_i40
#CELL
  pure_quanta q_res *
  page192_i41
#CELL
  pure_quanta q_res *
  page192_i42
#ISCELL
  standard offpage *
  page192_i43
#ISCELL
  standard offpage *
  page192_i44
#ISCELL
  pure_quanta_power vcc_core *
  page192_i45
#ISCELL
  pure_quanta_power universal_gnd *
  page192_i46
#CELL
  pure_quanta q_cap *
  page192_i47
#ISCELL
  pure_quanta_power vcc_core *
  page192_i48
#CELL
  pure_quanta q_res *
  page192_i49
#ISCELL
  standard offpage *
  page192_i5
#CELL
  pure_quanta q_res *
  page192_i50
#CELL
  pure_quanta q_res *
  page192_i51
#CELL
  pure_quanta q_cap *
  page192_i52
#ISCELL
  pure_quanta_power vcc_core *
  page192_i53
#ISCELL
  pure_quanta_power universal_gnd *
  page192_i54
#CELL
  pure_quanta q_res *
  page192_i55
#CELL
  pure_quanta q_cap *
  page192_i56
#ISCELL
  pure_quanta_power universal_gnd *
  page192_i57
#ISCELL
  pure_quanta_power universal_gnd *
  page192_i58
#ISCELL
  pure_quanta_power universal_gnd *
  page192_i59
#CELL
  pure_quanta mosfet_n *
  page192_i6
#CELL
  pure_quanta q_cap *
  page192_i60
#ISCELL
  pure_quanta_power universal_gnd *
  page192_i61
#ISCELL
  pure_quanta_power universal_gnd *
  page192_i62
#ISCELL
  pure_quanta_power vcc_core *
  page192_i63
#CELL
  pure_quanta q_res *
  page192_i64
#CELL
  pure_quanta q_res *
  page192_i65
#CELL
  pure_quanta q_res *
  page192_i66
#CELL
  pure_quanta q_cap *
  page192_i67
#ISCELL
  pure_quanta_power vcc_core *
  page192_i68
#CELL
  pure_quanta q_res *
  page192_i69
#ISCELL
  pure_quanta_power universal_gnd *
  page192_i7
#ISCELL
  pure_quanta_power universal_gnd *
  page192_i70
#CELL
  pure_quanta q_res *
  page192_i71
#ISCELL
  pure_quanta_power universal_gnd *
  page192_i72
#CELL
  pure_quanta q_cap *
  page192_i73
#ISCELL
  pure_quanta_power universal_gnd *
  page192_i74
#CELL
  pure_quanta q_cap *
  page192_i75
#CELL
  pure_quanta q_res *
  page192_i76
#CELL
  pure_quanta q_res *
  page192_i77
#ISCELL
  pure_quanta_power vcc_core *
  page192_i78
#CELL
  pure_quanta q_cap *
  page192_i79
#CELL
  pure_quanta q_res *
  page192_i8
#CELL
  pure_quanta q_res *
  page192_i80
#CELL
  pure_quanta q_res *
  page192_i81
#CELL
  pure_quanta q_res *
  page192_i82
#CELL
  pure_quanta q_res *
  page192_i83
#CELL
  pure_quanta q_res *
  page192_i84
#CELL
  pure_quanta q_cap *
  page192_i85
#ISCELL
  pure_quanta_power universal_gnd *
  page192_i86
#CELL
  pure_quanta q_res *
  page192_i87
#CELL
  pure_quanta q_res *
  page192_i88
#CELL
  pure_quanta q_res *
  page192_i89
#CELL
  pure_quanta q_res *
  page192_i9
#CELL
  pure_quanta q_cap *
  page192_i90
#ISCELL
  pure_quanta_power universal_gnd *
  page192_i91
#ISCELL
  pure_quanta_power universal_gnd *
  page192_i92
#CELL
  pure_quanta q_cap *
  page192_i93
#ISCELL
  pure_quanta_power universal_gnd *
  page192_i94
#CELL
  pure_quanta q_cap *
  page192_i95
#ISCELL
  pure_quanta_power universal_gnd *
  page192_i96
#CELL
  pure_quanta q_cap *
  page192_i97
#ISCELL
  pure_quanta_power universal_gnd *
  page192_i98
#CELL
  pure_quanta q_cap *
  page192_i99
#ISCELL
  mstr_misc dns *
  *
#ISCELL
  pure_quanta quanta_title_block_c *
  *
#ISCELL
  pure_quanta_power universal_gnd *
  page193_i1
#ISCELL
  pure_quanta_power universal_gnd *
  page193_i10
#CELL
  pure_quanta q_cap *
  page193_i11
#CELL
  pure_quanta q_cap *
  page193_i12
#ISCELL
  pure_quanta_power universal_gnd *
  page193_i13
#CELL
  pure_quanta q_res *
  page193_i14
#CELL
  pure_quanta q_cap *
  page193_i15
#ISCELL
  pure_quanta_power universal_gnd *
  page193_i16
#CELL
  pure_quanta q_res *
  page193_i17
#ISCELL
  pure_quanta_power vcc_core *
  page193_i18
#ISCELL
  standard offpage *
  page193_i19
#CELL
  pure_quanta q_cap *
  page193_i2
#ISCELL
  standard offpage *
  page193_i20
#ISCELL
  pure_quanta_power vcc_core *
  page193_i21
#ISCELL
  pure_quanta_power universal_gnd *
  page193_i22
#CELL
  pure_quanta q_cap *
  page193_i23
#ISCELL
  standard offpage *
  page193_i24
#ISCELL
  standard offpage *
  page193_i25
#ISCELL
  pure_quanta_power vcc_core *
  page193_i26
#CELL
  pure_quanta q_res *
  page193_i27
#ISCELL
  pure_quanta_power universal_gnd *
  page193_i28
#CELL
  pure_quanta q_cap *
  page193_i29
#ISCELL
  pure_quanta_power universal_gnd *
  page193_i3
#ISCELL
  pure_quanta_power vcc_core *
  page193_i30
#CELL
  pure_quanta isl99390frztr5935 *
  page193_i31
#ISCELL
  pure_quanta_power universal_gnd *
  page193_i32
#ISCELL
  pure_quanta_power universal_gnd *
  page193_i33
#CELL
  pure_quanta q_cap *
  page193_i34
#ISCELL
  pure_quanta_power universal_gnd *
  page193_i35
#CELL
  pure_quanta q_res *
  page193_i36
#CELL
  pure_quanta q_cap *
  page193_i37
#CELL
  pure_quanta q_res *
  page193_i38
#ISCELL
  standard offpage *
  page193_i39
#CELL
  pure_quanta q_res *
  page193_i4
#CELL
  pure_quanta q_cap *
  page193_i40
#CELL
  pure_quanta q_res *
  page193_i41
#CELL
  pure_quanta q_cap *
  page193_i42
#CELL
  pure_quanta q_cap *
  page193_i43
#ISCELL
  pure_quanta_power universal_gnd *
  page193_i44
#CELL
  pure_quanta q_res *
  page193_i45
#CELL
  pure_quanta q_cap *
  page193_i46
#ISCELL
  pure_quanta_power universal_gnd *
  page193_i47
#CELL
  pure_quanta q_cap *
  page193_i48
#ISCELL
  pure_quanta_power vcc_core *
  page193_i49
#ISCELL
  standard offpage *
  page193_i5
#CELL
  pure_quanta q_cap *
  page193_i50
#CELL
  pure_quanta q_res *
  page193_i51
#CELL
  pure_quanta q_cap *
  page193_i52
#CELL
  pure_quanta q_cap *
  page193_i53
#CELL
  pure_quanta q_cap *
  page193_i54
#ISCELL
  standard offpage *
  page193_i55
#ISCELL
  pure_quanta_power universal_gnd *
  page193_i56
#CELL
  pure_quanta q_cap *
  page193_i57
#CELL
  pure_quanta q_cap *
  page193_i58
#ISCELL
  pure_quanta_power vcc_core *
  page193_i59
#ISCELL
  standard offpage *
  page193_i6
#CELL
  pure_quanta q_cap *
  page193_i60
#CELL
  pure_quanta q_inductor4p_14 *
  page193_i62
#ISCELL
  standard offpage *
  page193_i63
#CELL
  pure_quanta q_res *
  page193_i64
#CELL
  pure_quanta q_capp *
  page193_i65
#CELL
  pure_quanta q_capp *
  page193_i66
#CELL
  pure_quanta q_capp *
  page193_i67
#CELL
  pure_quanta q_cap *
  page193_i68
#ISCELL
  pure_quanta_power universal_gnd *
  page193_i69
#ISCELL
  standard offpage *
  page193_i7
#CELL
  pure_quanta q_cap *
  page193_i70
#ISCELL
  pure_quanta_power vcc_core *
  page193_i71
#ISCELL
  pure_quanta_power universal_gnd *
  page193_i72
#CELL
  pure_quanta q_capp *
  page193_i73
#CELL
  pure_quanta q_capp *
  page193_i74
#ISCELL
  pure_quanta_power vcc_core *
  page193_i75
#ISCELL
  pure_quanta_power universal_gnd *
  page193_i76
#CELL
  pure_quanta q_inductor4p_14 *
  page193_i77
#CELL
  pure_quanta q_inductor *
  page193_i79
#ISCELL
  standard offpage *
  page193_i8
#ISCELL
  standard offpage *
  page193_i80
#ISCELL
  pure_quanta_power universal_gnd *
  page193_i81
#CELL
  pure_quanta q_cap *
  page193_i82
#CELL
  pure_quanta q_cap *
  page193_i83
#ISCELL
  pure_quanta_power vcc_core *
  page193_i84
#CELL
  pure_quanta q_cap *
  page193_i85
#CELL
  pure_quanta q_cap *
  page193_i86
#CELL
  pure_quanta q_res *
  page193_i87
#ISCELL
  pure_quanta_power vcc_core *
  page193_i88
#CELL
  pure_quanta q_res *
  page193_i89
#ISCELL
  pure_quanta_power universal_gnd *
  page193_i9
#CELL
  pure_quanta q_res *
  page193_i90
#CELL
  pure_quanta isl99390frztr5935 *
  page193_i91
#CELL
  pure_quanta q_capp *
  page193_i92
#CELL
  pure_quanta q_capp *
  page193_i93
#ISCELL
  mstr_misc dns *
  *
#ISCELL
  pure_quanta quanta_title_block_c *
  *
#ISCELL
  pure_quanta_power universal_gnd *
  page194_i1
#ISCELL
  standard offpage *
  page194_i10
#ISCELL
  pure_quanta_power universal_gnd *
  page194_i11
#CELL
  pure_quanta q_cap *
  page194_i12
#CELL
  pure_quanta q_res *
  page194_i13
#ISCELL
  pure_quanta_power vcc_core *
  page194_i14
#ISCELL
  pure_quanta_power universal_gnd *
  page194_i15
#CELL
  pure_quanta q_cap *
  page194_i16
#ISCELL
  pure_quanta_power universal_gnd *
  page194_i17
#CELL
  pure_quanta q_res *
  page194_i18
#ISCELL
  standard offpage *
  page194_i19
#CELL
  pure_quanta q_cap *
  page194_i2
#ISCELL
  standard offpage *
  page194_i20
#CELL
  pure_quanta isl99390frztr5935 *
  page194_i21
#ISCELL
  pure_quanta_power universal_gnd *
  page194_i22
#CELL
  pure_quanta q_cap *
  page194_i23
#ISCELL
  pure_quanta_power universal_gnd *
  page194_i24
#ISCELL
  standard offpage *
  page194_i25
#ISCELL
  standard offpage *
  page194_i26
#CELL
  pure_quanta q_cap *
  page194_i27
#ISCELL
  pure_quanta_power universal_gnd *
  page194_i28
#CELL
  pure_quanta q_res *
  page194_i29
#ISCELL
  pure_quanta_power universal_gnd *
  page194_i3
#ISCELL
  pure_quanta_power universal_gnd *
  page194_i30
#CELL
  pure_quanta q_cap *
  page194_i31
#ISCELL
  pure_quanta_power vcc_core *
  page194_i32
#CELL
  pure_quanta q_cap *
  page194_i33
#ISCELL
  pure_quanta_power universal_gnd *
  page194_i34
#CELL
  pure_quanta q_res *
  page194_i35
#CELL
  pure_quanta q_res *
  page194_i36
#CELL
  pure_quanta q_cap *
  page194_i37
#CELL
  pure_quanta q_res *
  page194_i38
#ISCELL
  standard offpage *
  page194_i39
#CELL
  pure_quanta q_res *
  page194_i4
#CELL
  pure_quanta q_cap *
  page194_i40
#CELL
  pure_quanta q_cap *
  page194_i41
#CELL
  pure_quanta q_cap *
  page194_i42
#ISCELL
  pure_quanta_power universal_gnd *
  page194_i43
#CELL
  pure_quanta q_res *
  page194_i44
#CELL
  pure_quanta q_cap *
  page194_i45
#ISCELL
  pure_quanta_power universal_gnd *
  page194_i46
#CELL
  pure_quanta q_cap *
  page194_i47
#ISCELL
  pure_quanta_power vcc_core *
  page194_i48
#CELL
  pure_quanta q_res *
  page194_i49
#ISCELL
  standard offpage *
  page194_i5
#CELL
  pure_quanta q_inductor4p_14 *
  page194_i50
#ISCELL
  pure_quanta_power universal_gnd *
  page194_i51
#CELL
  pure_quanta q_res *
  page194_i52
#CELL
  pure_quanta q_cap *
  page194_i53
#CELL
  pure_quanta q_cap *
  page194_i54
#CELL
  pure_quanta q_cap *
  page194_i55
#ISCELL
  standard offpage *
  page194_i56
#CELL
  pure_quanta q_cap *
  page194_i57
#ISCELL
  pure_quanta_power universal_gnd *
  page194_i58
#CELL
  pure_quanta q_cap *
  page194_i59
#ISCELL
  pure_quanta_power universal_gnd *
  page194_i6
#CELL
  pure_quanta q_cap *
  page194_i60
#ISCELL
  pure_quanta_power vcc_core *
  page194_i61
#CELL
  pure_quanta q_inductor4p_14 *
  page194_i62
#ISCELL
  standard offpage *
  page194_i63
#CELL
  pure_quanta q_cap *
  page194_i64
#CELL
  pure_quanta q_cap *
  page194_i65
#ISCELL
  pure_quanta_power universal_gnd *
  page194_i66
#CELL
  pure_quanta q_cap *
  page194_i67
#ISCELL
  pure_quanta_power vcc_core *
  page194_i68
#ISCELL
  pure_quanta_power universal_gnd *
  page194_i69
#CELL
  pure_quanta q_cap *
  page194_i7
#CELL
  pure_quanta q_cap *
  page194_i70
#ISCELL
  pure_quanta_power vcc_core *
  page194_i71
#CELL
  pure_quanta isl99390frztr5935 *
  page194_i72
#ISCELL
  standard offpage *
  page194_i8
#ISCELL
  standard offpage *
  page194_i9
#ISCELL
  mstr_misc dns *
  *
#ISCELL
  pure_quanta quanta_title_block_c *
  *
#CELL
  pure_quanta q_cap *
  page195_i1
#CELL
  pure_quanta q_cap *
  page195_i10
#ISCELL
  pure_quanta_power universal_gnd *
  page195_i11
#CELL
  pure_quanta q_cap *
  page195_i12
#CELL
  pure_quanta q_res *
  page195_i13
#ISCELL
  pure_quanta_power universal_gnd *
  page195_i14
#CELL
  pure_quanta q_res *
  page195_i15
#ISCELL
  pure_quanta_power vcc_core *
  page195_i16
#ISCELL
  standard offpage *
  page195_i17
#ISCELL
  standard offpage *
  page195_i18
#CELL
  pure_quanta isl99390frztr5935 *
  page195_i19
#ISCELL
  pure_quanta_power universal_gnd *
  page195_i2
#ISCELL
  pure_quanta_power universal_gnd *
  page195_i20
#ISCELL
  pure_quanta_power universal_gnd *
  page195_i21
#CELL
  pure_quanta q_cap *
  page195_i22
#ISCELL
  pure_quanta_power universal_gnd *
  page195_i23
#ISCELL
  standard offpage *
  page195_i24
#ISCELL
  standard offpage *
  page195_i25
#ISCELL
  pure_quanta_power universal_gnd *
  page195_i26
#CELL
  pure_quanta q_cap *
  page195_i27
#CELL
  pure_quanta q_res *
  page195_i28
#ISCELL
  pure_quanta_power vcc_core *
  page195_i29
#ISCELL
  pure_quanta_power universal_gnd *
  page195_i3
#ISCELL
  pure_quanta_power universal_gnd *
  page195_i30
#CELL
  pure_quanta q_cap *
  page195_i31
#ISCELL
  pure_quanta_power universal_gnd *
  page195_i32
#CELL
  pure_quanta q_res *
  page195_i33
#CELL
  pure_quanta q_cap *
  page195_i34
#CELL
  pure_quanta q_res *
  page195_i35
#ISCELL
  pure_quanta_power universal_gnd *
  page195_i36
#CELL
  pure_quanta q_inductor *
  page195_i37
#CELL
  pure_quanta q_cap *
  page195_i38
#CELL
  pure_quanta q_res *
  page195_i39
#CELL
  pure_quanta q_res *
  page195_i4
#CELL
  pure_quanta q_cap *
  page195_i40
#CELL
  pure_quanta q_cap *
  page195_i41
#ISCELL
  pure_quanta_power universal_gnd *
  page195_i42
#CELL
  pure_quanta q_res *
  page195_i43
#CELL
  pure_quanta q_cap *
  page195_i44
#CELL
  pure_quanta q_cap *
  page195_i45
#ISCELL
  pure_quanta_power universal_gnd *
  page195_i46
#CELL
  pure_quanta q_cap *
  page195_i47
#ISCELL
  pure_quanta_power vcc_core *
  page195_i48
#CELL
  pure_quanta q_res *
  page195_i49
#ISCELL
  standard offpage *
  page195_i5
#CELL
  pure_quanta q_inductor4p_14 *
  page195_i50
#ISCELL
  standard offpage *
  page195_i51
#CELL
  pure_quanta q_res *
  page195_i52
#CELL
  pure_quanta q_cap *
  page195_i53
#CELL
  pure_quanta q_cap *
  page195_i54
#CELL
  pure_quanta q_cap *
  page195_i55
#CELL
  pure_quanta q_cap *
  page195_i56
#CELL
  pure_quanta q_cap *
  page195_i57
#ISCELL
  standard offpage *
  page195_i58
#ISCELL
  pure_quanta_power universal_gnd *
  page195_i59
#ISCELL
  standard offpage *
  page195_i6
#CELL
  pure_quanta q_cap *
  page195_i60
#CELL
  pure_quanta q_cap *
  page195_i61
#ISCELL
  pure_quanta_power vcc_core *
  page195_i62
#CELL
  pure_quanta q_inductor4p_14 *
  page195_i63
#ISCELL
  standard offpage *
  page195_i64
#CELL
  pure_quanta q_cap *
  page195_i65
#ISCELL
  pure_quanta_power universal_gnd *
  page195_i66
#CELL
  pure_quanta q_cap *
  page195_i67
#ISCELL
  pure_quanta_power vcc_core *
  page195_i68
#ISCELL
  pure_quanta_power universal_gnd *
  page195_i69
#ISCELL
  standard offpage *
  page195_i7
#CELL
  pure_quanta q_cap *
  page195_i70
#CELL
  pure_quanta q_cap *
  page195_i71
#ISCELL
  pure_quanta_power vcc_core *
  page195_i72
#CELL
  pure_quanta isl99390frztr5935 *
  page195_i73
#ISCELL
  standard offpage *
  page195_i8
#ISCELL
  pure_quanta_power universal_gnd *
  page195_i9
#ISCELL
  pure_quanta quanta_title_block_c *
  *
#ISCELL
  mstr_misc dns *
  *
#ISCELL
  pure_quanta quanta_title_block_c *
  *
#ISCELL
  pure_quanta_power universal_gnd *
  page197_i1
#ISCELL
  standard offpage *
  page197_i10
#ISCELL
  pure_quanta_power universal_gnd *
  page197_i11
#CELL
  pure_quanta q_cap *
  page197_i12
#CELL
  pure_quanta q_res *
  page197_i13
#ISCELL
  pure_quanta_power vcc_core *
  page197_i14
#ISCELL
  pure_quanta_power universal_gnd *
  page197_i15
#CELL
  pure_quanta q_cap *
  page197_i16
#ISCELL
  pure_quanta_power universal_gnd *
  page197_i17
#ISCELL
  pure_quanta_power universal_gnd *
  page197_i18
#CELL
  pure_quanta q_res *
  page197_i19
#ISCELL
  pure_quanta_power universal_gnd *
  page197_i2
#CELL
  pure_quanta q_cap *
  page197_i20
#CELL
  pure_quanta q_cap *
  page197_i21
#CELL
  pure_quanta q_res *
  page197_i22
#CELL
  pure_quanta q_cap *
  page197_i23
#ISCELL
  pure_quanta_power universal_gnd *
  page197_i24
#ISCELL
  pure_quanta_power universal_gnd *
  page197_i25
#CELL
  pure_quanta q_res *
  page197_i26
#ISCELL
  pure_quanta_power universal_gnd *
  page197_i27
#CELL
  pure_quanta q_res *
  page197_i28
#ISCELL
  standard offpage *
  page197_i29
#CELL
  pure_quanta q_cap *
  page197_i3
#ISCELL
  standard offpage *
  page197_i30
#ISCELL
  standard offpage *
  page197_i31
#ISCELL
  standard offpage *
  page197_i32
#ISCELL
  pure_quanta_power universal_gnd *
  page197_i33
#CELL
  pure_quanta q_cap *
  page197_i34
#CELL
  pure_quanta q_res *
  page197_i35
#ISCELL
  pure_quanta_power vcc_core *
  page197_i36
#ISCELL
  pure_quanta_power universal_gnd *
  page197_i37
#CELL
  pure_quanta q_cap *
  page197_i38
#CELL
  pure_quanta isl99390frztr5935 *
  page197_i39
#CELL
  pure_quanta q_cap *
  page197_i4
#CELL
  pure_quanta q_cap *
  page197_i40
#CELL
  pure_quanta q_cap *
  page197_i41
#CELL
  pure_quanta q_cap *
  page197_i42
#CELL
  pure_quanta q_res *
  page197_i43
#CELL
  pure_quanta q_cap *
  page197_i44
#CELL
  pure_quanta q_res *
  page197_i45
#ISCELL
  standard offpage *
  page197_i46
#CELL
  pure_quanta q_cap *
  page197_i47
#CELL
  pure_quanta q_cap *
  page197_i48
#CELL
  pure_quanta q_cap *
  page197_i49
#ISCELL
  pure_quanta_power universal_gnd *
  page197_i5
#CELL
  pure_quanta q_res *
  page197_i50
#ISCELL
  pure_quanta_power universal_gnd *
  page197_i51
#CELL
  pure_quanta q_cap *
  page197_i52
#ISCELL
  pure_quanta_power vcc_core *
  page197_i53
#ISCELL
  standard offpage *
  page197_i54
#CELL
  pure_quanta q_cap *
  page197_i55
#ISCELL
  pure_quanta_power universal_gnd *
  page197_i56
#CELL
  pure_quanta q_cap *
  page197_i57
#CELL
  pure_quanta q_capp *
  page197_i58
#CELL
  pure_quanta q_capp *
  page197_i59
#CELL
  pure_quanta q_res *
  page197_i6
#ISCELL
  pure_quanta_power vcc_core *
  page197_i60
#ISCELL
  pure_quanta_power universal_gnd *
  page197_i61
#CELL
  pure_quanta q_capp *
  page197_i62
#ISCELL
  pure_quanta_power vcc_core *
  page197_i63
#ISCELL
  standard offpage *
  page197_i64
#CELL
  pure_quanta q_cap *
  page197_i65
#CELL
  pure_quanta q_cap *
  page197_i66
#ISCELL
  pure_quanta_power universal_gnd *
  page197_i67
#ISCELL
  pure_quanta_power vcc_core *
  page197_i68
#CELL
  pure_quanta q_cap *
  page197_i69
#ISCELL
  standard offpage *
  page197_i7
#CELL
  pure_quanta q_inductor4p_14 *
  page197_i71
#CELL
  pure_quanta q_inductor *
  page197_i72
#ISCELL
  pure_quanta_power universal_gnd *
  page197_i73
#CELL
  pure_quanta q_cap *
  page197_i74
#ISCELL
  pure_quanta_power vcc_core *
  page197_i75
#ISCELL
  pure_quanta_power universal_gnd *
  page197_i76
#CELL
  pure_quanta q_cap *
  page197_i77
#CELL
  pure_quanta q_cap *
  page197_i78
#CELL
  pure_quanta q_cap *
  page197_i79
#ISCELL
  standard offpage *
  page197_i8
#ISCELL
  pure_quanta_power universal_gnd *
  page197_i80
#CELL
  pure_quanta q_res *
  page197_i81
#ISCELL
  pure_quanta_power vcc_core *
  page197_i82
#CELL
  pure_quanta q_inductor4p_14 *
  page197_i83
#CELL
  pure_quanta isl99390frztr5935 *
  page197_i84
#CELL
  pure_quanta q_capp *
  page197_i85
#CELL
  pure_quanta q_cap *
  page197_i86
#ISCELL
  standard offpage *
  page197_i9
#ISCELL
  mstr_misc dns *
  *
#ISCELL
  pure_quanta quanta_title_block_c *
  *
#ISCELL
  pure_quanta_power universal_gnd *
  page198_i1
#CELL
  pure_quanta q_cap *
  page198_i10
#ISCELL
  pure_quanta_power universal_gnd *
  page198_i11
#CELL
  pure_quanta q_res *
  page198_i12
#CELL
  pure_quanta q_cap *
  page198_i13
#ISCELL
  pure_quanta_power vcc_core *
  page198_i14
#CELL
  pure_quanta isl99390frztr5935 *
  page198_i15
#ISCELL
  pure_quanta_power universal_gnd *
  page198_i16
#CELL
  pure_quanta q_res *
  page198_i17
#CELL
  pure_quanta q_cap *
  page198_i18
#ISCELL
  pure_quanta_power universal_gnd *
  page198_i19
#CELL
  pure_quanta q_cap *
  page198_i2
#CELL
  pure_quanta q_cap *
  page198_i20
#ISCELL
  pure_quanta_power universal_gnd *
  page198_i21
#CELL
  pure_quanta q_res *
  page198_i22
#ISCELL
  standard offpage *
  page198_i23
#ISCELL
  standard offpage *
  page198_i24
#ISCELL
  standard offpage *
  page198_i25
#ISCELL
  standard offpage *
  page198_i26
#ISCELL
  pure_quanta_power universal_gnd *
  page198_i27
#CELL
  pure_quanta q_cap *
  page198_i28
#CELL
  pure_quanta q_res *
  page198_i29
#ISCELL
  pure_quanta_power universal_gnd *
  page198_i3
#ISCELL
  pure_quanta_power universal_gnd *
  page198_i30
#CELL
  pure_quanta q_cap *
  page198_i31
#ISCELL
  pure_quanta_power vcc_core *
  page198_i32
#ISCELL
  pure_quanta_power universal_gnd *
  page198_i33
#CELL
  pure_quanta q_res *
  page198_i34
#CELL
  pure_quanta q_cap *
  page198_i35
#CELL
  pure_quanta q_cap *
  page198_i36
#CELL
  pure_quanta q_cap *
  page198_i37
#ISCELL
  pure_quanta_power universal_gnd *
  page198_i38
#CELL
  pure_quanta q_res *
  page198_i39
#CELL
  pure_quanta q_res *
  page198_i4
#ISCELL
  pure_quanta_power universal_gnd *
  page198_i40
#CELL
  pure_quanta q_res *
  page198_i41
#CELL
  pure_quanta q_inductor4p_14 *
  page198_i42
#CELL
  pure_quanta q_inductor *
  page198_i43
#CELL
  pure_quanta q_cap *
  page198_i44
#CELL
  pure_quanta q_cap *
  page198_i45
#CELL
  pure_quanta q_cap *
  page198_i46
#ISCELL
  pure_quanta_power universal_gnd *
  page198_i47
#CELL
  pure_quanta q_cap *
  page198_i48
#ISCELL
  pure_quanta_power vcc_core *
  page198_i49
#ISCELL
  standard offpage *
  page198_i5
#ISCELL
  standard offpage *
  page198_i50
#CELL
  pure_quanta q_cap *
  page198_i51
#ISCELL
  pure_quanta_power universal_gnd *
  page198_i52
#CELL
  pure_quanta q_cap *
  page198_i53
#ISCELL
  pure_quanta_power vcc_core *
  page198_i54
#CELL
  pure_quanta q_res *
  page198_i55
#ISCELL
  pure_quanta_power universal_gnd *
  page198_i56
#CELL
  pure_quanta q_res *
  page198_i57
#CELL
  pure_quanta q_cap *
  page198_i58
#ISCELL
  standard offpage *
  page198_i59
#ISCELL
  standard offpage *
  page198_i6
#CELL
  pure_quanta q_cap *
  page198_i60
#CELL
  pure_quanta q_cap *
  page198_i61
#CELL
  pure_quanta q_inductor4p_14 *
  page198_i62
#CELL
  pure_quanta q_cap *
  page198_i63
#ISCELL
  pure_quanta_power universal_gnd *
  page198_i64
#CELL
  pure_quanta q_cap *
  page198_i65
#ISCELL
  pure_quanta_power vcc_core *
  page198_i66
#ISCELL
  standard offpage *
  page198_i67
#CELL
  pure_quanta q_cap *
  page198_i68
#ISCELL
  pure_quanta_power universal_gnd *
  page198_i69
#ISCELL
  standard offpage *
  page198_i7
#CELL
  pure_quanta q_cap *
  page198_i70
#ISCELL
  pure_quanta_power vcc_core *
  page198_i71
#CELL
  pure_quanta q_cap *
  page198_i72
#CELL
  pure_quanta isl99390frztr5935 *
  page198_i73
#ISCELL
  standard offpage *
  page198_i8
#ISCELL
  pure_quanta_power universal_gnd *
  page198_i9
#ISCELL
  mstr_misc dns *
  *
#ISCELL
  pure_quanta quanta_title_block_c *
  *
#ISCELL
  pure_quanta_power vcc_core *
  page199_i1
#ISCELL
  standard offpage *
  page199_i10
#ISCELL
  standard offpage *
  page199_i11
#ISCELL
  standard offpage *
  page199_i12
#CELL
  pure_quanta q_res *
  page199_i13
#ISCELL
  pure_quanta_power universal_gnd *
  page199_i14
#CELL
  pure_quanta q_res *
  page199_i15
#ISCELL
  pure_quanta_power universal_gnd *
  page199_i16
#CELL
  pure_quanta q_res *
  page199_i17
#CELL
  pure_quanta q_res *
  page199_i18
#ISCELL
  pure_quanta_power universal_gnd *
  page199_i19
#CELL
  pure_quanta q_res *
  page199_i2
#CELL
  pure_quanta q_cap *
  page199_i20
#ISCELL
  pure_quanta_power universal_gnd *
  page199_i21
#ISCELL
  pure_quanta_power universal_gnd *
  page199_i23
#CELL
  pure_quanta q_res *
  page199_i24
#ISCELL
  pure_quanta_power vcc_core *
  page199_i25
#ISCELL
  pure_quanta_power universal_gnd *
  page199_i26
#CELL
  pure_quanta q_res *
  page199_i27
#CELL
  pure_quanta q_cap *
  page199_i28
#CELL
  pure_quanta q_res *
  page199_i29
#ISCELL
  pure_quanta_power universal_gnd *
  page199_i3
#ISCELL
  pure_quanta_power vcc_core *
  page199_i30
#ISCELL
  standard offpage *
  page199_i31
#ISCELL
  standard offpage *
  page199_i32
#ISCELL
  standard offpage *
  page199_i33
#ISCELL
  standard offpage *
  page199_i34
#ISCELL
  standard offpage *
  page199_i35
#ISCELL
  pure_quanta_power vcc_core *
  page199_i36
#CELL
  pure_quanta q_res *
  page199_i37
#CELL
  pure_quanta q_res *
  page199_i38
#CELL
  pure_quanta q_res *
  page199_i39
#CELL
  pure_quanta q_cap *
  page199_i4
#CELL
  pure_quanta q_res *
  page199_i40
#ISCELL
  pure_quanta_power universal_gnd *
  page199_i41
#CELL
  pure_quanta q_res *
  page199_i42
#CELL
  pure_quanta q_res *
  page199_i43
#CELL
  pure_quanta q_cap *
  page199_i44
#ISCELL
  pure_quanta_power universal_gnd *
  page199_i45
#CELL
  pure_quanta q_cap *
  page199_i46
#ISCELL
  pure_quanta_power universal_gnd *
  page199_i47
#ISCELL
  pure_quanta_power universal_gnd *
  page199_i48
#CELL
  pure_quanta q_cap *
  page199_i49
#ISCELL
  pure_quanta_power universal_gnd *
  page199_i5
#ISCELL
  standard offpage *
  page199_i50
#CELL
  pure_quanta q_res *
  page199_i51
#CELL
  pure_quanta q_res *
  page199_i52
#ISCELL
  pure_quanta_power universal_gnd *
  page199_i53
#ISCELL
  pure_quanta_power universal_gnd *
  page199_i54
#ISCELL
  pure_quanta_power universal_gnd *
  page199_i55
#CELL
  pure_quanta q_res *
  page199_i56
#CELL
  pure_quanta q_res *
  page199_i57
#CELL
  pure_quanta q_res *
  page199_i58
#CELL
  pure_quanta q_res *
  page199_i59
#CELL
  pure_quanta q_res *
  page199_i6
#CELL
  pure_quanta q_res *
  page199_i60
#ISCELL
  pure_quanta_power universal_gnd *
  page199_i61
#ISCELL
  pure_quanta_power universal_gnd *
  page199_i62
#ISCELL
  pure_quanta_power universal_gnd *
  page199_i63
#ISCELL
  pure_quanta_power universal_gnd *
  page199_i64
#ISCELL
  pure_quanta_power universal_gnd *
  page199_i65
#CELL
  pure_quanta q_res *
  page199_i66
#CELL
  pure_quanta q_res *
  page199_i67
#ISCELL
  pure_quanta_power vcc_core *
  page199_i68
#ISCELL
  standard offpage *
  page199_i69
#ISCELL
  pure_quanta_power vcc_core *
  page199_i7
#CELL
  pure_quanta q_res *
  page199_i70
#ISCELL
  pure_quanta_power universal_gnd *
  page199_i71
#CELL
  pure_quanta q_cap *
  page199_i72
#CELL
  pure_quanta q_cap *
  page199_i73
#ISCELL
  pure_quanta_power universal_gnd *
  page199_i74
#ISCELL
  standard offpage *
  page199_i75
#ISCELL
  standard offpage *
  page199_i76
#ISCELL
  standard offpage *
  page199_i77
#ISCELL
  standard offpage *
  page199_i78
#ISCELL
  pure_quanta_power universal_gnd *
  page199_i79
#ISCELL
  pure_quanta_power vcc_core *
  page199_i8
#CELL
  pure_quanta q_cap *
  page199_i80
#CELL
  pure_quanta q_cap *
  page199_i81
#ISCELL
  pure_quanta_power universal_gnd *
  page199_i82
#ISCELL
  standard offpage *
  page199_i83
#CELL
  pure_quanta q_res *
  page199_i84
#ISCELL
  pure_quanta_power vcc_core *
  page199_i85
#CELL
  pure_quanta raa229621gnpha0 *
  page199_i86
#ISCELL
  pure_quanta_power universal_gnd *
  page199_i87
#CELL
  pure_quanta q_cap *
  page199_i88
#CELL
  pure_quanta q_res *
  page199_i89
#CELL
  pure_quanta q_res *
  page199_i9
#ISCELL
  mstr_misc dns *
  *
#ISCELL
  pure_quanta quanta_title_block_c *
  *
#ISCELL
  standard offpage *
  page200_i1
#CELL
  pure_quanta q_cap *
  page200_i10
#ISCELL
  pure_quanta_power universal_gnd *
  page200_i11
#CELL
  pure_quanta q_res *
  page200_i12
#ISCELL
  standard offpage *
  page200_i13
#CELL
  pure_quanta q_res *
  page200_i14
#ISCELL
  pure_quanta_power vcc_core *
  page200_i15
#ISCELL
  pure_quanta_power universal_gnd *
  page200_i16
#CELL
  pure_quanta q_cap *
  page200_i17
#ISCELL
  pure_quanta_power universal_gnd *
  page200_i18
#ISCELL
  pure_quanta_power universal_gnd *
  page200_i19
#ISCELL
  standard offpage *
  page200_i2
#ISCELL
  standard offpage *
  page200_i20
#ISCELL
  standard offpage *
  page200_i21
#CELL
  pure_quanta isl99390frztr5935 *
  page200_i22
#ISCELL
  pure_quanta_power universal_gnd *
  page200_i23
#ISCELL
  pure_quanta_power universal_gnd *
  page200_i24
#CELL
  pure_quanta q_res *
  page200_i25
#CELL
  pure_quanta q_res *
  page200_i26
#CELL
  pure_quanta q_cap *
  page200_i27
#ISCELL
  pure_quanta_power universal_gnd *
  page200_i28
#CELL
  pure_quanta q_cap *
  page200_i29
#CELL
  pure_quanta q_res *
  page200_i3
#CELL
  pure_quanta q_cap *
  page200_i30
#CELL
  pure_quanta q_cap *
  page200_i31
#ISCELL
  pure_quanta_power universal_gnd *
  page200_i32
#CELL
  pure_quanta q_res *
  page200_i33
#CELL
  pure_quanta q_cap *
  page200_i34
#ISCELL
  pure_quanta_power universal_gnd *
  page200_i35
#CELL
  pure_quanta q_cap *
  page200_i36
#CELL
  pure_quanta q_res *
  page200_i37
#ISCELL
  standard offpage *
  page200_i38
#ISCELL
  pure_quanta_power universal_gnd *
  page200_i39
#ISCELL
  pure_quanta_power vcc_core *
  page200_i4
#CELL
  pure_quanta q_res *
  page200_i40
#CELL
  pure_quanta q_res *
  page200_i41
#ISCELL
  pure_quanta_power vcc_core *
  page200_i42
#CELL
  pure_quanta q_cap *
  page200_i43
#ISCELL
  pure_quanta_power vcc_core *
  page200_i44
#CELL
  pure_quanta q_cap *
  page200_i45
#CELL
  pure_quanta q_cap *
  page200_i46
#CELL
  pure_quanta q_res *
  page200_i47
#CELL
  pure_quanta q_cap *
  page200_i48
#CELL
  pure_quanta q_cap *
  page200_i49
#ISCELL
  pure_quanta_power universal_gnd *
  page200_i5
#CELL
  pure_quanta q_cap *
  page200_i50
#CELL
  pure_quanta q_cap *
  page200_i51
#CELL
  pure_quanta q_cap *
  page200_i52
#CELL
  pure_quanta q_res *
  page200_i53
#CELL
  pure_quanta q_cap *
  page200_i54
#CELL
  pure_quanta q_inductor *
  page200_i55
#CELL
  pure_quanta q_cap *
  page200_i56
#ISCELL
  pure_quanta_power universal_gnd *
  page200_i57
#CELL
  pure_quanta q_cap *
  page200_i58
#ISCELL
  pure_quanta_power vcc_core *
  page200_i59
#ISCELL
  standard offpage *
  page200_i6
#CELL
  pure_quanta q_res *
  page200_i60
#ISCELL
  pure_quanta_power universal_gnd *
  page200_i61
#CELL
  pure_quanta q_capp *
  page200_i62
#CELL
  pure_quanta q_capp *
  page200_i63
#ISCELL
  pure_quanta_power vcc_core *
  page200_i64
#CELL
  pure_quanta q_capp *
  page200_i65
#ISCELL
  pure_quanta_power universal_gnd *
  page200_i66
#CELL
  pure_quanta q_cap *
  page200_i67
#ISCELL
  pure_quanta_power vcc_core *
  page200_i68
#CELL
  pure_quanta q_capp *
  page200_i69
#ISCELL
  standard offpage *
  page200_i7
#ISCELL
  pure_quanta_power universal_gnd *
  page200_i70
#ISCELL
  pure_quanta_power vcc_core *
  page200_i71
#CELL
  pure_quanta q_capp *
  page200_i72
#CELL
  pure_quanta q_capp *
  page200_i73
#ISCELL
  pure_quanta_power universal_gnd *
  page200_i74
#CELL
  pure_quanta q_capp *
  page200_i75
#CELL
  pure_quanta q_cap *
  page200_i76
#ISCELL
  pure_quanta_power universal_gnd *
  page200_i77
#CELL
  pure_quanta q_inductor *
  page200_i78
#ISCELL
  pure_quanta_power vcc_core *
  page200_i79
#CELL
  pure_quanta q_cap *
  page200_i8
#CELL
  pure_quanta q_cap *
  page200_i80
#CELL
  pure_quanta q_capp *
  page200_i81
#CELL
  pure_quanta q_cap *
  page200_i82
#ISCELL
  pure_quanta_power universal_gnd *
  page200_i83
#CELL
  pure_quanta q_inductor *
  page200_i84
#CELL
  pure_quanta q_cap *
  page200_i85
#ISCELL
  pure_quanta_power vcc_core *
  page200_i86
#CELL
  pure_quanta q_cap *
  page200_i87
#CELL
  pure_quanta q_cap *
  page200_i88
#CELL
  pure_quanta q_res *
  page200_i89
#ISCELL
  pure_quanta_power universal_gnd *
  page200_i9
#ISCELL
  pure_quanta_power vcc_core *
  page200_i90
#CELL
  pure_quanta q_cap *
  page200_i91
#CELL
  pure_quanta isl99390frztr5935 *
  page200_i92
#CELL
  pure_quanta q_cap *
  page200_i93
#CELL
  pure_quanta q_cap *
  page200_i94
#CELL
  pure_quanta q_cap *
  page200_i95
#ISCELL
  mstr_misc dns *
  *
#ISCELL
  pure_quanta quanta_title_block_c *
  *
#ISCELL
  standard offpage *
  page201_i1
#ISCELL
  pure_quanta_power universal_gnd *
  page201_i10
#CELL
  pure_quanta q_res *
  page201_i11
#CELL
  pure_quanta q_res *
  page201_i12
#ISCELL
  mstr_symbols universal_power *
  page201_i13
#CELL
  pure_quanta q_res *
  page201_i14
#CELL
  pure_quanta mpq8633bglec838z *
  page201_i15
#ISCELL
  pure_quanta_power universal_gnd *
  page201_i16
#ISCELL
  pure_quanta_power universal_gnd *
  page201_i17
#CELL
  pure_quanta q_cap *
  page201_i18
#CELL
  pure_quanta q_cap *
  page201_i19
#ISCELL
  pure_quanta_power universal_gnd *
  page201_i2
#ISCELL
  pure_quanta_power universal_gnd *
  page201_i20
#CELL
  pure_quanta q_cap *
  page201_i21
#CELL
  pure_quanta q_cap *
  page201_i22
#CELL
  pure_quanta q_cap *
  page201_i23
#CELL
  pure_quanta q_cap *
  page201_i24
#CELL
  pure_quanta q_cap *
  page201_i25
#CELL
  pure_quanta q_res *
  page201_i26
#ISCELL
  mstr_symbols universal_power *
  page201_i27
#ISCELL
  pure_quanta_power universal_gnd *
  page201_i28
#CELL
  pure_quanta q_res *
  page201_i29
#CELL
  pure_quanta q_cap *
  page201_i3
#CELL
  pure_quanta q_res *
  page201_i30
#CELL
  pure_quanta q_cap *
  page201_i31
#CELL
  pure_quanta q_res *
  page201_i32
#CELL
  pure_quanta q_inductor *
  page201_i33
#CELL
  pure_quanta q_cap *
  page201_i34
#CELL
  pure_quanta q_res *
  page201_i35
#CELL
  pure_quanta q_res *
  page201_i36
#CELL
  pure_quanta q_cap *
  page201_i37
#CELL
  pure_quanta q_cap *
  page201_i38
#CELL
  pure_quanta q_res *
  page201_i39
#CELL
  pure_quanta q_inductor *
  page201_i4
#CELL
  pure_quanta q_cap *
  page201_i40
#CELL
  pure_quanta q_cap *
  page201_i41
#CELL
  pure_quanta q_cap *
  page201_i42
#CELL
  pure_quanta q_capp *
  page201_i43
#ISCELL
  standard offpage *
  page201_i44
#ISCELL
  standard offpage *
  page201_i45
#ISCELL
  pure_quanta_power universal_gnd *
  page201_i46
#CELL
  pure_quanta q_cap *
  page201_i47
#CELL
  pure_quanta q_res *
  page201_i48
#ISCELL
  standard offpage *
  page201_i49
#ISCELL
  mstr_symbols p1v0_aux *
  page201_i5
#CELL
  pure_quanta q_res *
  page201_i50
#ISCELL
  pure_quanta_power universal_gnd *
  page201_i51
#ISCELL
  pure_quanta_power p1v0 *
  page201_i52
#CELL
  pure_quanta q_cap *
  page201_i53
#CELL
  pure_quanta q_cap *
  page201_i54
#CELL
  pure_quanta q_cap *
  page201_i55
#ISCELL
  pure_quanta_power universal_gnd *
  page201_i56
#CELL
  pure_quanta q_cap *
  page201_i57
#CELL
  pure_quanta q_res *
  page201_i58
#CELL
  pure_quanta q_cap *
  page201_i6
#ISCELL
  pure_quanta_power universal_gnd *
  page201_i7
#ISCELL
  pure_quanta_power universal_gnd *
  page201_i8
#ISCELL
  pure_quanta_power universal_gnd *
  page201_i9
#ISCELL
  pure_quanta quanta_title_block_c *
  *
#ISCELL
  pure_quanta quanta_title_block_c *
  *
#ISCELL
  pure_quanta quanta_title_block_c *
  *
#ISCELL
  pure_quanta_power universal_gnd *
  page211_i1
#ISCELL
  pure_quanta_power universal_gnd *
  page211_i16
#ISCELL
  pure_quanta_power universal_gnd *
  page211_i19
#ISCELL
  pure_quanta_power universal_gnd *
  page211_i2
#ISCELL
  pure_quanta_power universal_gnd *
  page211_i20
#ISCELL
  pure_quanta_power universal_gnd *
  page211_i22
#ISCELL
  pure_quanta_power universal_gnd *
  page211_i25
#ISCELL
  pure_quanta_power universal_gnd *
  page211_i26
#ISCELL
  pure_quanta_power universal_gnd *
  page211_i3
#ISCELL
  pure_quanta_power universal_gnd *
  page211_i30
#ISCELL
  pure_quanta_power universal_gnd *
  page211_i32
#ISCELL
  pure_quanta_power universal_gnd *
  page211_i33
#ISCELL
  pure_quanta_power universal_gnd *
  page211_i35
#ISCELL
  pure_quanta_power universal_gnd *
  page211_i37
#ISCELL
  pure_quanta_power universal_gnd *
  page211_i38
#ISCELL
  pure_quanta_power universal_gnd *
  page211_i4
#ISCELL
  pure_quanta_power universal_gnd *
  page211_i40
#ISCELL
  pure_quanta_power universal_gnd *
  page211_i42
#ISCELL
  pure_quanta_power universal_gnd *
  page211_i45
#ISCELL
  pure_quanta_power universal_gnd *
  page211_i48
#ISCELL
  pure_quanta_power universal_gnd *
  page211_i49
#ISCELL
  pure_quanta_power universal_gnd *
  page211_i5
#ISCELL
  pure_quanta_power universal_gnd *
  page211_i51
#ISCELL
  pure_quanta_power universal_gnd *
  page211_i54
#ISCELL
  pure_quanta_power universal_gnd *
  page211_i55
#ISCELL
  pure_quanta_power universal_gnd *
  page211_i56
#ISCELL
  pure_quanta_power universal_gnd *
  page211_i58
#ISCELL
  pure_quanta_power universal_gnd *
  page211_i6
#ISCELL
  pure_quanta_power universal_gnd *
  page211_i61
#ISCELL
  pure_quanta_power universal_gnd *
  page211_i63
#CELL
  pure_quanta picoprobe_bxa *
  page211_i65
#CELL
  pure_quanta picoprobe_bxa *
  page211_i66
#CELL
  pure_quanta picoprobe_bxa *
  page211_i67
#CELL
  pure_quanta picoprobe_bxa *
  page211_i68
#CELL
  pure_quanta picoprobe_bxa *
  page211_i69
#ISCELL
  pure_quanta_power universal_gnd *
  page211_i7
#CELL
  pure_quanta picoprobe_bxa *
  page211_i70
#CELL
  pure_quanta picoprobe_bxa *
  page211_i71
#CELL
  pure_quanta picoprobe_bxa *
  page211_i72
#CELL
  pure_quanta picoprobe_bxa *
  page211_i73
#CELL
  pure_quanta picoprobe_bxa *
  page211_i74
#CELL
  pure_quanta picoprobe_bxa *
  page211_i75
#CELL
  pure_quanta picoprobe_bxa *
  page211_i76
#CELL
  pure_quanta picoprobe_bxa *
  page211_i77
#CELL
  pure_quanta picoprobe_bxa *
  page211_i78
#CELL
  pure_quanta picoprobe_bxa *
  page211_i79
#ISCELL
  pure_quanta_power universal_gnd *
  page211_i8
#CELL
  pure_quanta picoprobe_bxa *
  page211_i80
#CELL
  pure_quanta picoprobe_bxa *
  page211_i81
#CELL
  pure_quanta picoprobe_bxa *
  page211_i82
#CELL
  pure_quanta picoprobe_bxa *
  page211_i83
#CELL
  pure_quanta picoprobe_bxa *
  page211_i84
#CELL
  pure_quanta picoprobe_bxa *
  page211_i85
#CELL
  pure_quanta picoprobe_bxa *
  page211_i86
#CELL
  pure_quanta picoprobe_bxa *
  page211_i87
#CELL
  pure_quanta picoprobe_bxa *
  page211_i88
#CELL
  pure_quanta picoprobe_bxa *
  page211_i89
#CELL
  pure_quanta picoprobe_bxa *
  page211_i90
#CELL
  pure_quanta picoprobe_bxa *
  page211_i91
#CELL
  pure_quanta picoprobe_bxa *
  page211_i92
#CELL
  pure_quanta picoprobe_bxa *
  page211_i93
#CELL
  pure_quanta picoprobe_bxa *
  page211_i94
#CELL
  pure_quanta picoprobe_bxa *
  page211_i95
#CELL
  pure_quanta picoprobe_bxa *
  page211_i96
#ISCELL
  pure_quanta quanta_title_block_c *
  *
#CELL
  pure_quanta hole *
  page212_i10
#CELL
  pure_quanta conn1_10165288101lf *
  page212_i101
#CELL
  pure_quanta conn1_10165288101lf *
  page212_i106
#ISCELL
  pure_quanta_power universal_gnd *
  page212_i11
#CELL
  pure_quanta hole *
  page212_i111
#CELL
  pure_quanta hole *
  page212_i113
#ISCELL
  pure_quanta_power universal_gnd *
  page212_i114
#ISCELL
  pure_quanta_power universal_gnd *
  page212_i115
#CELL
  pure_quanta hole *
  page212_i116
#CELL
  pure_quanta hole *
  page212_i12
#CELL
  pure_quanta gnd_hole *
  page212_i120
#ISCELL
  pure_quanta_power universal_gnd *
  page212_i122
#CELL
  pure_quanta gnd_hole *
  page212_i123
#ISCELL
  pure_quanta_power universal_gnd *
  page212_i124
#CELL
  pure_quanta hole *
  page212_i125
#ISCELL
  pure_quanta_power universal_gnd *
  page212_i126
#CELL
  pure_quanta hole *
  page212_i127
#ISCELL
  pure_quanta_power universal_gnd *
  page212_i128
#CELL
  pure_quanta hole *
  page212_i129
#ISCELL
  pure_quanta_power universal_gnd *
  page212_i130
#ISCELL
  pure_quanta_power universal_gnd *
  page212_i131
#CELL
  pure_quanta hole *
  page212_i132
#CELL
  pure_quanta hole *
  page212_i133
#ISCELL
  pure_quanta_power universal_gnd *
  page212_i134
#CELL
  pure_quanta hole *
  page212_i135
#ISCELL
  pure_quanta_power universal_gnd *
  page212_i136
#ISCELL
  pure_quanta_power universal_gnd *
  page212_i137
#CELL
  pure_quanta hole *
  page212_i138
#ISCELL
  pure_quanta_power universal_gnd *
  page212_i139
#CELL
  pure_quanta hole *
  page212_i140
#CELL
  pure_quanta hole *
  page212_i141
#CELL
  pure_quanta hole *
  page212_i142
#ISCELL
  pure_quanta_power universal_gnd *
  page212_i143
#ISCELL
  pure_quanta_power universal_gnd *
  page212_i144
#CELL
  pure_quanta hole *
  page212_i145
#ISCELL
  pure_quanta_power universal_gnd *
  page212_i146
#CELL
  pure_quanta hole *
  page212_i147
#ISCELL
  pure_quanta_power universal_gnd *
  page212_i148
#CELL
  pure_quanta hole *
  page212_i149
#ISCELL
  pure_quanta_power universal_gnd *
  page212_i150
#ISCELL
  pure_quanta_power universal_gnd *
  page212_i151
#CELL
  pure_quanta hole *
  page212_i152
#CELL
  pure_quanta hole *
  page212_i153
#ISCELL
  pure_quanta_power universal_gnd *
  page212_i154
#ISCELL
  pure_quanta_power universal_gnd *
  page212_i155
#CELL
  pure_quanta hole *
  page212_i156
#CELL
  pure_quanta hole *
  page212_i157
#ISCELL
  pure_quanta_power universal_gnd *
  page212_i158
#CELL
  pure_quanta hole *
  page212_i159
#ISCELL
  pure_quanta_power universal_gnd *
  page212_i160
#CELL
  pure_quanta hole *
  page212_i161
#ISCELL
  pure_quanta_power universal_gnd *
  page212_i162
#CELL
  pure_quanta hole *
  page212_i163
#ISCELL
  pure_quanta_power universal_gnd *
  page212_i164
#ISCELL
  pure_quanta_power universal_gnd *
  page212_i165
#CELL
  pure_quanta hole *
  page212_i166
#CELL
  pure_quanta hole *
  page212_i167
#CELL
  pure_quanta hole *
  page212_i168
#ISCELL
  pure_quanta_power universal_gnd *
  page212_i169
#CELL
  pure_quanta hole *
  page212_i170
#ISCELL
  pure_quanta_power universal_gnd *
  page212_i171
#CELL
  pure_quanta hole *
  page212_i176
#ISCELL
  pure_quanta_power universal_gnd *
  page212_i177
#CELL
  pure_quanta hole *
  page212_i178
#ISCELL
  pure_quanta_power universal_gnd *
  page212_i179
#ISCELL
  pure_quanta_power universal_gnd *
  page212_i186
#CELL
  pure_quanta hole *
  page212_i187
#ISCELL
  pure_quanta_power universal_gnd *
  page212_i192
#CELL
  pure_quanta hole *
  page212_i193
#ISCELL
  pure_quanta_power universal_gnd *
  page212_i194
#CELL
  pure_quanta hole *
  page212_i195
#ISCELL
  pure_quanta_power universal_gnd *
  page212_i21
#ISCELL
  pure_quanta_power universal_gnd *
  page212_i24
#CELL
  pure_quanta gnd_hole *
  page212_i25
#CELL
  pure_quanta hole *
  page212_i26
#CELL
  pure_quanta hole *
  page212_i27
#ISCELL
  pure_quanta_power universal_gnd *
  page212_i28
#ISCELL
  pure_quanta_power universal_gnd *
  page212_i29
#ISCELL
  pure_quanta_power universal_gnd *
  page212_i3
#CELL
  pure_quanta gnd_hole *
  page212_i30
#CELL
  pure_quanta hole *
  page212_i31
#ISCELL
  pure_quanta_power universal_gnd *
  page212_i32
#CELL
  pure_quanta hole *
  page212_i33
#ISCELL
  pure_quanta_power universal_gnd *
  page212_i34
#ISCELL
  pure_quanta_power universal_gnd *
  page212_i35
#CELL
  pure_quanta hole *
  page212_i36
#ISCELL
  pure_quanta_power universal_gnd *
  page212_i37
#CELL
  pure_quanta hole *
  page212_i38
#ISCELL
  pure_quanta_power universal_gnd *
  page212_i39
#CELL
  pure_quanta hole *
  page212_i4
#CELL
  pure_quanta hole *
  page212_i40
#CELL
  pure_quanta hole *
  page212_i41
#ISCELL
  pure_quanta_power universal_gnd *
  page212_i42
#CELL
  pure_quanta gnd_hole *
  page212_i43
#ISCELL
  pure_quanta_power universal_gnd *
  page212_i44
#CELL
  pure_quanta hole *
  page212_i45
#CELL
  pure_quanta hole *
  page212_i46
#ISCELL
  pure_quanta_power universal_gnd *
  page212_i47
#ISCELL
  pure_quanta_power universal_gnd *
  page212_i48
#CELL
  pure_quanta hole *
  page212_i49
#CELL
  pure_quanta hole *
  page212_i5
#CELL
  pure_quanta hole *
  page212_i50
#CELL
  pure_quanta hole *
  page212_i51
#CELL
  pure_quanta hole *
  page212_i52
#ISCELL
  pure_quanta_power universal_gnd *
  page212_i53
#ISCELL
  pure_quanta_power universal_gnd *
  page212_i54
#CELL
  pure_quanta hole *
  page212_i55
#CELL
  pure_quanta hole *
  page212_i56
#ISCELL
  pure_quanta_power universal_gnd *
  page212_i6
#CELL
  pure_quanta hole *
  page212_i7
#ISCELL
  pure_quanta_power universal_gnd *
  page212_i8
#CELL
  pure_quanta hole *
  page212_i84
#CELL
  pure_quanta hole *
  page212_i85
#ISCELL
  pure_quanta_power universal_gnd *
  page212_i86
#CELL
  pure_quanta hole *
  page212_i87
#CELL
  pure_quanta hole *
  page212_i88
#CELL
  pure_quanta hole *
  page212_i89
#ISCELL
  pure_quanta_power universal_gnd *
  page212_i9
#ISCELL
  pure_quanta_power universal_gnd *
  page212_i90
#CELL
  pure_quanta hole *
  page212_i91
#ISCELL
  pure_quanta_power universal_gnd *
  page212_i92
#CELL
  pure_quanta hole *
  page212_i93
#CELL
  pure_quanta hole *
  page212_i94
#ISCELL
  pure_quanta quanta_title_block_c *
  *
#ISCELL
  pure_quanta quanta_title_block_c *
  *
#ISCELL
  mstr_misc dns *
  *
#ISCELL
  pure_quanta quanta_title_block_c *
  *
#ISCELL
  pure_quanta_power design_note *
  *
#ISCELL
  standard offpage *
  page232_i1
#ISCELL
  pure_quanta_power universal_gnd *
  page232_i11
#ISCELL
  pure_quanta_power universal_gnd *
  page232_i12
#CELL
  pure_quanta q_xtal_4p_13bi_24gnd *
  page232_i14
#ISCELL
  pure_quanta_power universal_power *
  page232_i15
#CELL
  pure_quanta q_res *
  page232_i16
#ISCELL
  standard offpage *
  page232_i17
#ISCELL
  standard offpage *
  page232_i18
#ISCELL
  pure_quanta_power universal_gnd *
  page232_i19
#ISCELL
  standard offpage *
  page232_i2
#ISCELL
  pure_quanta_power universal_gnd *
  page232_i20
#CELL
  pure_quanta q_res *
  page232_i22
#ISCELL
  standard offpage *
  page232_i23
#ISCELL
  standard offpage *
  page232_i24
#ISCELL
  pure_quanta_power universal_gnd *
  page232_i25
#CELL
  pure_quanta 74lvc1g32gw *
  page232_i26
#ISCELL
  pure_quanta_power universal_gnd *
  page232_i27
#CELL
  pure_quanta q_cap *
  page232_i28
#ISCELL
  pure_quanta_power universal_power *
  page232_i29
#ISCELL
  standard offpage *
  page232_i3
#ISCELL
  pure_quanta_power universal_power *
  page232_i30
#CELL
  pure_quanta q_res *
  page232_i31
#ISCELL
  pure_quanta_power universal_power *
  page232_i32
#CELL
  pure_quanta q_inductor *
  page232_i33
#ISCELL
  pure_quanta_power universal_power *
  page232_i34
#ISCELL
  pure_quanta_power universal_power *
  page232_i35
#CELL
  pure_quanta q_cap *
  page232_i36
#CELL
  pure_quanta q_cap *
  page232_i37
#ISCELL
  pure_quanta_power universal_power *
  page232_i38
#ISCELL
  pure_quanta_power universal_gnd *
  page232_i39
#ISCELL
  standard offpage *
  page232_i4
#CELL
  pure_quanta q_cap *
  page232_i40
#CELL
  pure_quanta q_cap *
  page232_i41
#CELL
  pure_quanta q_cap *
  page232_i42
#CELL
  pure_quanta q_res *
  page232_i43
#ISCELL
  standard offpage *
  page232_i44
#ISCELL
  pure_quanta_power universal_gnd *
  page232_i45
#CELL
  pure_quanta q_res *
  page232_i46
#CELL
  pure_quanta q_res *
  page232_i47
#ISCELL
  pure_quanta_power universal_power *
  page232_i48
#ISCELL
  standard offpage *
  page232_i49
#ISCELL
  pure_quanta_power universal_gnd *
  page232_i5
#CELL
  pure_quanta q_res *
  page232_i50
#CELL
  pure_quanta q_res *
  page232_i51
#CELL
  pure_quanta q_res *
  page232_i52
#CELL
  pure_quanta q_res *
  page232_i53
#ISCELL
  pure_quanta_power universal_gnd *
  page232_i54
#CELL
  pure_quanta q_res *
  page232_i55
#CELL
  pure_quanta q_res *
  page232_i56
#ISCELL
  pure_quanta_power universal_power *
  page232_i57
#ISCELL
  standard offpage *
  page232_i58
#CELL
  pure_quanta q_res *
  page232_i59
#CELL
  pure_quanta q_res *
  page232_i6
#ISCELL
  pure_quanta_power universal_power *
  page232_i60
#ISCELL
  standard offpage *
  page232_i61
#ISCELL
  standard offpage *
  page232_i62
#ISCELL
  standard offpage *
  page232_i63
#ISCELL
  standard offpage *
  page232_i64
#ISCELL
  standard offpage *
  page232_i65
#ISCELL
  pure_quanta_power universal_gnd *
  page232_i66
#ISCELL
  standard offpage *
  page232_i67
#CELL
  pure_quanta q_cap *
  page232_i68
#CELL
  pure_quanta q_cap *
  page232_i69
#CELL
  pure_quanta q_res *
  page232_i7
#ISCELL
  pure_quanta_power universal_power *
  page232_i70
#ISCELL
  pure_quanta_power universal_gnd *
  page232_i71
#CELL
  pure_quanta q_res *
  page232_i73
#CELL
  pure_quanta q_res *
  page232_i74
#CELL
  pure_quanta q_cap *
  page232_i75
#CELL
  pure_quanta q_cap *
  page232_i76
#CELL
  pure_quanta 9fgl0251dkilft *
  page232_i77
#CELL
  pure_quanta q_res *
  page232_i8
#ISCELL
  mstr_misc dns *
  *
#ISCELL
  pure_quanta quanta_title_block_c *
  *
#ISCELL
  pure_quanta_power cad_note *
  *
#CELL
  pure_quanta gl852gohy60 *
  page358_i100
#ISCELL
  pure_quanta_power universal_gnd *
  page358_i115
#ISCELL
  pure_quanta_power universal_gnd *
  page358_i116
#ISCELL
  pure_quanta_power universal_gnd *
  page358_i117
#ISCELL
  pure_quanta_power universal_gnd *
  page358_i118
#ISCELL
  pure_quanta_power universal_gnd *
  page358_i122
#ISCELL
  standard offpage *
  page358_i133
#ISCELL
  standard offpage *
  page358_i134
#ISCELL
  standard offpage *
  page358_i135
#ISCELL
  standard offpage *
  page358_i136
#CELL
  pure_quanta q_res *
  page358_i137
#CELL
  pure_quanta q_res *
  page358_i138
#CELL
  pure_quanta q_res *
  page358_i139
#ISCELL
  pure_quanta_power universal_gnd *
  page358_i140
#CELL
  pure_quanta q_cap *
  page358_i142
#CELL
  pure_quanta q_cap *
  page358_i143
#ISCELL
  pure_quanta_power universal_power *
  page358_i144
#CELL
  pure_quanta q_cap *
  page358_i145
#CELL
  pure_quanta q_cap *
  page358_i147
#CELL
  pure_quanta q_cap *
  page358_i148
#ISCELL
  pure_quanta_power universal_power *
  page358_i151
#CELL
  pure_quanta q_res *
  page358_i155
#ISCELL
  standard offpage *
  page358_i156
#ISCELL
  pure_quanta_power universal_gnd *
  page358_i157
#CELL
  pure_quanta q_cap *
  page358_i158
#CELL
  pure_quanta q_res *
  page358_i159
#CELL
  pure_quanta q_res *
  page358_i161
#CELL
  pure_quanta q_cap *
  page358_i162
#CELL
  pure_quanta q_cap *
  page358_i163
#CELL
  pure_quanta q_cap *
  page358_i164
#ISCELL
  pure_quanta_power universal_gnd *
  page358_i165
#ISCELL
  pure_quanta_power universal_gnd *
  page358_i166
#CELL
  pure_quanta q_res *
  page358_i167
#ISCELL
  standard offpage *
  page358_i168
#ISCELL
  standard offpage *
  page358_i169
#ISCELL
  standard offpage *
  page358_i170
#ISCELL
  standard offpage *
  page358_i171
#CELL
  pure_quanta q_res *
  page358_i182
#ISCELL
  pure_quanta_power universal_gnd *
  page358_i183
#ISCELL
  standard offpage *
  page358_i184
#ISCELL
  pure_quanta_power universal_power *
  page358_i185
#CELL
  pure_quanta q_res *
  page358_i186
#CELL
  pure_quanta q_res *
  page358_i187
#ISCELL
  pure_quanta_power universal_gnd *
  page358_i188
#ISCELL
  standard offpage *
  page358_i189
#ISCELL
  standard offpage *
  page358_i190
#ISCELL
  standard offpage *
  page358_i191
#ISCELL
  standard offpage *
  page358_i192
#ISCELL
  standard offpage *
  page358_i193
#CELL
  pure_quanta q_res *
  page358_i194
#CELL
  pure_quanta q_res *
  page358_i195
#CELL
  pure_quanta q_res *
  page358_i196
#ISCELL
  pure_quanta_power universal_power *
  page358_i197
#CELL
  pure_quanta q_res *
  page358_i198
#CELL
  pure_quanta q_res *
  page358_i199
#CELL
  pure_quanta q_res *
  page358_i201
#CELL
  pure_quanta q_res *
  page358_i202
#CELL
  pure_quanta q_res *
  page358_i203
#ISCELL
  pure_quanta_power universal_gnd *
  page358_i204
#ISCELL
  pure_quanta_power universal_gnd *
  page358_i205
#CELL
  pure_quanta q_res *
  page358_i206
#ISCELL
  pure_quanta_power universal_gnd *
  page358_i207
#CELL
  pure_quanta q_res *
  page358_i208
#ISCELL
  pure_quanta_power universal_gnd *
  page358_i209
#CELL
  pure_quanta q_xtal_4p_13bi_24gnd *
  page358_i210
#CELL
  pure_quanta q_cap *
  page358_i211
#CELL
  pure_quanta q_cap *
  page358_i212
#ISCELL
  standard offpage *
  page358_i76
#ISCELL
  standard offpage *
  page358_i77
#CELL
  pure_quanta q_res *
  page358_i78
#CELL
  pure_quanta q_res *
  page358_i79
#ISCELL
  pure_quanta_power universal_gnd *
  page358_i80
#CELL
  pure_quanta q_cap *
  page358_i81
#ISCELL
  pure_quanta_power universal_gnd *
  page358_i82
#CELL
  pure_quanta q_res *
  page358_i83
#CELL
  pure_quanta tusb211irwbr *
  page358_i84
#ISCELL
  pure_quanta_power universal_gnd *
  page358_i85
#ISCELL
  pure_quanta_power universal_gnd *
  page358_i86
#CELL
  pure_quanta q_cap *
  page358_i87
#CELL
  pure_quanta q_cap *
  page358_i88
#ISCELL
  pure_quanta_power universal_gnd *
  page358_i89
#CELL
  pure_quanta q_res *
  page358_i90
#CELL
  pure_quanta q_res *
  page358_i91
#CELL
  pure_quanta q_cap *
  page358_i92
#ISCELL
  standard offpage *
  page358_i93
#ISCELL
  standard offpage *
  page358_i94
#ISCELL
  pure_quanta_power universal_power *
  page358_i95
#CELL
  pure_quanta q_res *
  page358_i96
#CELL
  pure_quanta q_res *
  page358_i97
#CELL
  pure_quanta q_res *
  page358_i98
#CELL
  pure_quanta q_res *
  page358_i99
#ISCELL
  mstr_misc dns *
  *
#ISCELL
  pure_quanta quanta_title_block_c *
  *
#ISCELL
  pure_quanta_power universal_power *
  page359_i100
#CELL
  pure_quanta q_res *
  page359_i101
#CELL
  pure_quanta q_res *
  page359_i102
#ISCELL
  pure_quanta_power universal_gnd *
  page359_i103
#CELL
  pure_quanta q_cap *
  page359_i104
#ISCELL
  pure_quanta_power universal_gnd *
  page359_i105
#ISCELL
  pure_quanta_power universal_gnd *
  page359_i106
#CELL
  pure_quanta q_res *
  page359_i107
#CELL
  pure_quanta q_res *
  page359_i108
#CELL
  pure_quanta q_res *
  page359_i109
#ISCELL
  standard offpage *
  page359_i110
#ISCELL
  standard offpage *
  page359_i111
#ISCELL
  standard offpage *
  page359_i112
#ISCELL
  standard offpage *
  page359_i113
#CELL
  pure_quanta q_res *
  page359_i114
#CELL
  pure_quanta q_res *
  page359_i115
#CELL
  pure_quanta q_res *
  page359_i116
#ISCELL
  pure_quanta_power universal_gnd *
  page359_i117
#ISCELL
  pure_quanta_power universal_gnd *
  page359_i118
#CELL
  pure_quanta q_cap *
  page359_i119
#ISCELL
  pure_quanta_power universal_gnd *
  page359_i120
#CELL
  pure_quanta q_res *
  page359_i121
#CELL
  pure_quanta q_res *
  page359_i122
#ISCELL
  pure_quanta_power universal_power *
  page359_i123
#ISCELL
  pure_quanta_power universal_gnd *
  page359_i124
#CELL
  pure_quanta q_res *
  page359_i125
#ISCELL
  pure_quanta_power universal_gnd *
  page359_i126
#CELL
  pure_quanta q_res *
  page359_i127
#CELL
  pure_quanta q_res *
  page359_i128
#CELL
  pure_quanta q_res *
  page359_i129
#ISCELL
  pure_quanta_power universal_power *
  page359_i130
#ISCELL
  standard offpage *
  page359_i132
#ISCELL
  standard offpage *
  page359_i133
#CELL
  pure_quanta q_res *
  page359_i134
#CELL
  pure_quanta q_res *
  page359_i135
#CELL
  pure_quanta q_res *
  page359_i136
#ISCELL
  pure_quanta_power universal_gnd *
  page359_i137
#ISCELL
  pure_quanta_power universal_gnd *
  page359_i138
#CELL
  pure_quanta q_cap *
  page359_i139
#ISCELL
  pure_quanta_power universal_gnd *
  page359_i140
#CELL
  pure_quanta q_res *
  page359_i141
#CELL
  pure_quanta q_res *
  page359_i142
#ISCELL
  pure_quanta_power universal_power *
  page359_i143
#ISCELL
  pure_quanta_power universal_gnd *
  page359_i144
#CELL
  pure_quanta q_res *
  page359_i145
#ISCELL
  pure_quanta_power universal_gnd *
  page359_i146
#CELL
  pure_quanta q_res *
  page359_i147
#CELL
  pure_quanta q_res *
  page359_i148
#CELL
  pure_quanta q_res *
  page359_i149
#ISCELL
  pure_quanta_power universal_power *
  page359_i15
#ISCELL
  pure_quanta_power universal_power *
  page359_i150
#ISCELL
  pure_quanta_power universal_power *
  page359_i153
#ISCELL
  pure_quanta_power universal_power *
  page359_i154
#ISCELL
  pure_quanta_power universal_power *
  page359_i156
#ISCELL
  pure_quanta_power universal_power *
  page359_i159
#CELL
  pure_quanta q_cap *
  page359_i16
#ISCELL
  standard offpage *
  page359_i160
#ISCELL
  standard offpage *
  page359_i161
#ISCELL
  standard offpage *
  page359_i162
#ISCELL
  standard offpage *
  page359_i163
#CELL
  pure_quanta lm75bd *
  page359_i164
#CELL
  pure_quanta lm75bd *
  page359_i165
#CELL
  pure_quanta lm75bd *
  page359_i166
#CELL
  pure_quanta lm75bd *
  page359_i167
#CELL
  pure_quanta q_res *
  page359_i168
#CELL
  pure_quanta q_res *
  page359_i169
#ISCELL
  pure_quanta_power universal_gnd *
  page359_i17
#CELL
  pure_quanta q_res *
  page359_i170
#CELL
  pure_quanta q_res *
  page359_i171
#ISCELL
  pure_quanta_power universal_gnd *
  page359_i21
#ISCELL
  standard offpage *
  page359_i75
#ISCELL
  standard offpage *
  page359_i76
#CELL
  pure_quanta q_res *
  page359_i77
#CELL
  pure_quanta q_res *
  page359_i78
#CELL
  pure_quanta q_res *
  page359_i79
#ISCELL
  pure_quanta_power universal_gnd *
  page359_i80
#CELL
  pure_quanta q_res *
  page359_i81
#CELL
  pure_quanta q_res *
  page359_i82
#ISCELL
  pure_quanta_power universal_power *
  page359_i83
#ISCELL
  pure_quanta_power universal_gnd *
  page359_i84
#CELL
  pure_quanta q_res *
  page359_i85
#CELL
  pure_quanta q_res *
  page359_i86
#CELL
  pure_quanta q_res *
  page359_i89
#ISCELL
  pure_quanta_power universal_gnd *
  page359_i90
#CELL
  pure_quanta q_res *
  page359_i91
#ISCELL
  pure_quanta_power universal_power *
  page359_i93
#CELL
  pure_quanta q_res *
  page359_i94
#CELL
  pure_quanta q_res *
  page359_i95
#CELL
  pure_quanta q_res *
  page359_i96
#ISCELL
  pure_quanta_power universal_gnd *
  page359_i97
#CELL
  pure_quanta q_res *
  page359_i98
#ISCELL
  pure_quanta_power universal_gnd *
  page359_i99
#ISCELL
  mstr_misc dns *
  *
#ISCELL
  pure_quanta quanta_title_block_c *
  *
#ISCELL
  pure_quanta_power bom_note *
  *
#ISCELL
  standard offpage *
  page295_i121
#CELL
  pure_quanta q_res *
  page295_i122
#ISCELL
  pure_quanta_power universal_power *
  page295_i123
#ISCELL
  pure_quanta_power universal_gnd *
  page295_i124
#CELL
  pure_quanta q_cap *
  page295_i125
#ISCELL
  pure_quanta_power universal_gnd *
  page295_i128
#CELL
  pure_quanta isl28022frzt *
  page295_i129
#CELL
  pure_quanta q_res *
  page295_i132
#CELL
  pure_quanta q_cap *
  page295_i133
#CELL
  pure_quanta q_res *
  page295_i134
#CELL
  pure_quanta q_res *
  page295_i135
#CELL
  pure_quanta q_res *
  page295_i136
#ISCELL
  pure_quanta_power universal_gnd *
  page295_i137
#ISCELL
  standard offpage *
  page295_i138
#ISCELL
  standard offpage *
  page295_i139
#ISCELL
  pure_quanta_power universal_power *
  page295_i140
#CELL
  pure_quanta q_cap *
  page295_i142
#ISCELL
  pure_quanta_power universal_gnd *
  page295_i143
#CELL
  pure_quanta q_res *
  page295_i144
#ISCELL
  pure_quanta_power universal_power *
  page295_i145
#CELL
  pure_quanta q_res *
  page295_i146
#ISCELL
  pure_quanta_power universal_power *
  page295_i147
#ISCELL
  pure_quanta_power universal_power *
  page295_i148
#CELL
  pure_quanta q_res *
  page295_i149
#ISCELL
  pure_quanta_power universal_power *
  page295_i150
#CELL
  pure_quanta q_res *
  page295_i151
#CELL
  pure_quanta q_res *
  page295_i152
#CELL
  pure_quanta q_res *
  page295_i153
#CELL
  pure_quanta q_res *
  page295_i154
#CELL
  pure_quanta q_res *
  page295_i155
#CELL
  pure_quanta isl28022frzt *
  page295_i30
#CELL
  pure_quanta q_res *
  page295_i31
#ISCELL
  standard offpage *
  page295_i32
#ISCELL
  pure_quanta_power universal_power *
  page295_i33
#CELL
  pure_quanta q_cap *
  page295_i34
#CELL
  pure_quanta q_res *
  page295_i35
#ISCELL
  pure_quanta_power universal_gnd *
  page295_i36
#ISCELL
  pure_quanta_power universal_gnd *
  page295_i37
#CELL
  pure_quanta q_res *
  page295_i40
#CELL
  pure_quanta q_res *
  page295_i41
#CELL
  pure_quanta q_res *
  page295_i43
#ISCELL
  pure_quanta_power universal_gnd *
  page295_i45
#ISCELL
  standard offpage *
  page295_i46
#ISCELL
  standard offpage *
  page295_i47
#ISCELL
  pure_quanta_power universal_gnd *
  page295_i49
#CELL
  pure_quanta q_cap *
  page295_i50
#CELL
  pure_quanta q_cap *
  page295_i77
#ISCELL
  pure_quanta_power universal_power *
  page295_i79
#ISCELL
  pure_quanta_power universal_power *
  page295_i80
#ISCELL
  pure_quanta_power universal_power *
  page295_i81
#ISCELL
  pure_quanta_power universal_power *
  page295_i87
#CELL
  pure_quanta q_res *
  page295_i88
#CELL
  pure_quanta q_res *
  page295_i89
#CELL
  pure_quanta q_res *
  page295_i93
#ISCELL
  mstr_misc dns *
  *
#ISCELL
  pure_quanta quanta_title_block_c *
  *
#ISCELL
  pure_quanta_power bom_note *
  *
#CELL
  pure_quanta q_res *
  page360_i100
#CELL
  pure_quanta q_res *
  page360_i103
#CELL
  pure_quanta q_res *
  page360_i104
#ISCELL
  pure_quanta_power universal_gnd *
  page360_i105
#ISCELL
  standard offpage *
  page360_i106
#ISCELL
  pure_quanta_power universal_gnd *
  page360_i107
#CELL
  pure_quanta q_cap *
  page360_i108
#CELL
  pure_quanta q_res *
  page360_i109
#CELL
  pure_quanta q_res *
  page360_i110
#ISCELL
  standard offpage *
  page360_i111
#ISCELL
  pure_quanta_power universal_power *
  page360_i112
#ISCELL
  pure_quanta_power universal_power *
  page360_i113
#CELL
  pure_quanta q_cap *
  page360_i114
#ISCELL
  pure_quanta_power universal_gnd *
  page360_i115
#CELL
  pure_quanta q_res *
  page360_i116
#ISCELL
  pure_quanta_power universal_power *
  page360_i117
#ISCELL
  pure_quanta_power universal_power *
  page360_i118
#ISCELL
  pure_quanta_power universal_power *
  page360_i119
#ISCELL
  pure_quanta_power universal_power *
  page360_i120
#ISCELL
  pure_quanta_power universal_power *
  page360_i121
#CELL
  pure_quanta q_res *
  page360_i122
#ISCELL
  pure_quanta_power universal_power *
  page360_i123
#CELL
  pure_quanta q_res *
  page360_i124
#ISCELL
  pure_quanta_power universal_power *
  page360_i125
#CELL
  pure_quanta q_res *
  page360_i126
#CELL
  pure_quanta q_res *
  page360_i127
#CELL
  pure_quanta q_res *
  page360_i128
#CELL
  pure_quanta q_res *
  page360_i129
#CELL
  pure_quanta q_res *
  page360_i130
#CELL
  pure_quanta q_res *
  page360_i131
#CELL
  pure_quanta q_res *
  page360_i132
#ISCELL
  pure_quanta_power universal_power *
  page360_i24
#CELL
  pure_quanta q_cap *
  page360_i26
#ISCELL
  pure_quanta_power universal_gnd *
  page360_i27
#ISCELL
  standard offpage *
  page360_i29
#ISCELL
  standard offpage *
  page360_i30
#ISCELL
  pure_quanta_power universal_gnd *
  page360_i31
#ISCELL
  pure_quanta_power universal_power *
  page360_i32
#CELL
  pure_quanta q_res *
  page360_i33
#CELL
  pure_quanta q_res *
  page360_i35
#CELL
  pure_quanta q_res *
  page360_i36
#ISCELL
  pure_quanta_power universal_gnd *
  page360_i39
#ISCELL
  pure_quanta_power universal_gnd *
  page360_i40
#CELL
  pure_quanta q_res *
  page360_i41
#CELL
  pure_quanta q_cap *
  page360_i42
#ISCELL
  pure_quanta_power universal_power *
  page360_i43
#ISCELL
  standard offpage *
  page360_i44
#CELL
  pure_quanta q_res *
  page360_i45
#CELL
  pure_quanta isl28022frzt *
  page360_i46
#CELL
  pure_quanta q_cap *
  page360_i49
#ISCELL
  pure_quanta_power universal_gnd *
  page360_i50
#ISCELL
  standard offpage *
  page360_i52
#ISCELL
  standard offpage *
  page360_i53
#ISCELL
  pure_quanta_power universal_gnd *
  page360_i54
#CELL
  pure_quanta q_res *
  page360_i56
#CELL
  pure_quanta q_res *
  page360_i58
#CELL
  pure_quanta q_res *
  page360_i59
#ISCELL
  pure_quanta_power universal_gnd *
  page360_i62
#ISCELL
  pure_quanta_power universal_gnd *
  page360_i63
#CELL
  pure_quanta q_res *
  page360_i64
#CELL
  pure_quanta q_cap *
  page360_i65
#ISCELL
  pure_quanta_power universal_power *
  page360_i66
#ISCELL
  standard offpage *
  page360_i67
#CELL
  pure_quanta q_res *
  page360_i68
#CELL
  pure_quanta isl28022frzt *
  page360_i69
#CELL
  pure_quanta q_cap *
  page360_i71
#CELL
  pure_quanta q_cap *
  page360_i72
#ISCELL
  pure_quanta_power universal_power *
  page360_i76
#ISCELL
  pure_quanta_power universal_power *
  page360_i85
#CELL
  pure_quanta q_res *
  page360_i86
#CELL
  pure_quanta q_res *
  page360_i87
#ISCELL
  pure_quanta_power universal_power *
  page360_i88
#CELL
  pure_quanta q_res *
  page360_i89
#CELL
  pure_quanta q_res *
  page360_i90
#CELL
  pure_quanta q_res *
  page360_i92
#CELL
  pure_quanta q_res *
  page360_i93
#CELL
  pure_quanta isl28022frzt *
  page360_i94
#ISCELL
  standard offpage *
  page360_i95
#CELL
  pure_quanta q_res *
  page360_i96
#ISCELL
  pure_quanta_power universal_power *
  page360_i97
#CELL
  pure_quanta q_cap *
  page360_i98
#ISCELL
  pure_quanta_power universal_gnd *
  page360_i99
#ISCELL
  mstr_misc dns *
  *
#ISCELL
  pure_quanta quanta_title_block_c *
  *
#CELL
  pure_quanta q_res *
  page361_i101
#ISCELL
  pure_quanta_power universal_power *
  page361_i102
#CELL
  pure_quanta q_res *
  page361_i103
#CELL
  pure_quanta q_res *
  page361_i104
#ISCELL
  pure_quanta_power universal_gnd *
  page361_i105
#ISCELL
  pure_quanta_power universal_gnd *
  page361_i106
#CELL
  pure_quanta q_res *
  page361_i107
#ISCELL
  pure_quanta_power universal_gnd *
  page361_i108
#ISCELL
  pure_quanta_power universal_power *
  page361_i109
#CELL
  pure_quanta q_cap *
  page361_i110
#ISCELL
  pure_quanta_power universal_gnd *
  page361_i111
#ISCELL
  pure_quanta_power universal_power *
  page361_i112
#CELL
  pure_quanta q_res *
  page361_i113
#CELL
  pure_quanta q_res *
  page361_i114
#CELL
  pure_quanta q_res *
  page361_i115
#ISCELL
  pure_quanta_power universal_gnd *
  page361_i116
#ISCELL
  standard offpage *
  page361_i118
#ISCELL
  standard offpage *
  page361_i119
#CELL
  pure_quanta q_res *
  page361_i120
#CELL
  pure_quanta q_res *
  page361_i121
#CELL
  pure_quanta q_res *
  page361_i122
#CELL
  pure_quanta q_res *
  page361_i123
#CELL
  pure_quanta q_res *
  page361_i124
#CELL
  pure_quanta q_res *
  page361_i125
#ISCELL
  standard offpage *
  page361_i126
#ISCELL
  standard offpage *
  page361_i127
#CELL
  pure_quanta m24128bwmn6tp *
  page361_i35
#CELL
  pure_quanta q_res *
  page361_i45
#CELL
  pure_quanta q_res *
  page361_i47
#ISCELL
  pure_quanta_power universal_gnd *
  page361_i49
#CELL
  pure_quanta q_res *
  page361_i50
#ISCELL
  pure_quanta_power universal_gnd *
  page361_i51
#CELL
  pure_quanta q_res *
  page361_i52
#ISCELL
  pure_quanta_power universal_gnd *
  page361_i53
#ISCELL
  pure_quanta_power universal_power *
  page361_i54
#CELL
  pure_quanta q_cap *
  page361_i55
#ISCELL
  pure_quanta_power universal_gnd *
  page361_i56
#CELL
  pure_quanta q_res *
  page361_i57
#ISCELL
  pure_quanta_power universal_gnd *
  page361_i58
#ISCELL
  pure_quanta_power universal_gnd *
  page361_i59
#ISCELL
  pure_quanta_power universal_power *
  page361_i60
#CELL
  pure_quanta q_res *
  page361_i61
#CELL
  pure_quanta q_res *
  page361_i62
#CELL
  pure_quanta q_res *
  page361_i93
#CELL
  pure_quanta q_res *
  page361_i95
#ISCELL
  pure_quanta_power universal_power *
  page361_i96
#CELL
  pure_quanta m24128bwmn6tp *
  page361_i97
#ISCELL
  pure_quanta_power universal_gnd *
  page361_i98
#ISCELL
  pure_quanta quanta_title_block_c *
  *
#ISCELL
  mstr_misc dns *
  *
#ISCELL
  pure_quanta quanta_title_block_c *
  *
#ISCELL
  pure_quanta_power universal_power *
  page363_i369
#ISCELL
  pure_quanta_power universal_gnd *
  page363_i370
#ISCELL
  standard offpage *
  page363_i371
#ISCELL
  standard offpage *
  page363_i377
#ISCELL
  standard offpage *
  page363_i378
#ISCELL
  standard offpage *
  page363_i379
#ISCELL
  standard offpage *
  page363_i380
#CELL
  pure_quanta q_res *
  page363_i387
#CELL
  pure_quanta q_res *
  page363_i388
#CELL
  pure_quanta mosfet_nch_gds_esd_protected *
  page363_i392
#ISCELL
  standard offpage *
  page363_i393
#CELL
  pure_quanta q_res *
  page363_i394
#ISCELL
  pure_quanta_power universal_power *
  page363_i395
#CELL
  pure_quanta q_res *
  page363_i396
#ISCELL
  pure_quanta_power universal_gnd *
  page363_i397
#CELL
  pure_quanta ltc4307cms8 *
  page363_i398
#ISCELL
  standard offpage *
  page363_i403
#ISCELL
  standard offpage *
  page363_i404
#ISCELL
  pure_quanta_power universal_gnd *
  page363_i405
#CELL
  pure_quanta q_cap *
  page363_i412
#ISCELL
  pure_quanta_power universal_gnd *
  page363_i413
#ISCELL
  pure_quanta_power universal_power *
  page363_i414
#CELL
  pure_quanta q_res *
  page363_i420
#CELL
  pure_quanta q_res *
  page363_i425
#CELL
  pure_quanta q_res *
  page363_i426
#ISCELL
  standard offpage *
  page363_i427
#ISCELL
  standard offpage *
  page363_i428
#CELL
  pure_quanta q_res *
  page363_i429
#CELL
  pure_quanta q_res *
  page363_i430
#CELL
  pure_quanta q_res *
  page363_i436
#ISCELL
  pure_quanta_power universal_power *
  page363_i437
#CELL
  pure_quanta q_res *
  page363_i438
#ISCELL
  standard offpage *
  page363_i439
#CELL
  pure_quanta q_res *
  page363_i440
#CELL
  pure_quanta q_res *
  page363_i441
#ISCELL
  standard offpage *
  page363_i444
#ISCELL
  standard offpage *
  page363_i450
#CELL
  pure_quanta q_cap *
  page363_i452
#CELL
  pure_quanta q_cap *
  page363_i453
#CELL
  pure_quanta q_cap *
  page363_i454
#CELL
  pure_quanta q_cap *
  page363_i455
#CELL
  pure_quanta q_cap *
  page363_i456
#ISCELL
  standard offpage *
  page363_i457
#ISCELL
  standard offpage *
  page363_i458
#ISCELL
  standard offpage *
  page363_i459
#ISCELL
  standard offpage *
  page363_i460
#ISCELL
  standard offpage *
  page363_i461
#ISCELL
  pure_quanta_power universal_gnd *
  page363_i462
#CELL
  pure_quanta q_res *
  page363_i463
#CELL
  pure_quanta q_res *
  page363_i464
#ISCELL
  standard offpage *
  page363_i465
#CELL
  pure_quanta conn60_101062636003k02lf *
  page363_i466
#CELL
  pure_quanta q_res *
  page363_i467
#ISCELL
  standard offpage *
  page363_i468
#CELL
  pure_quanta q_cap *
  page363_i469
#ISCELL
  standard offpage *
  page363_i470
#ISCELL
  pure_quanta_power universal_power *
  page363_i471
#CELL
  pure_quanta q_res *
  page363_i472
#ISCELL
  pure_quanta_power universal_power *
  page363_i473
#CELL
  pure_quanta q_res *
  page363_i475
#CELL
  pure_quanta q_res *
  page363_i476
#ISCELL
  standard offpage *
  page363_i477
#CELL
  pure_quanta q_cap *
  page363_i478
#ISCELL
  pure_quanta_power universal_gnd *
  page363_i479
#ISCELL
  mstr_misc dns *
  *
#ISCELL
  pure_quanta quanta_title_block_c *
  *
#ISCELL
  pure_quanta_power universal_power *
  page364_i10
#ISCELL
  pure_quanta_power universal_gnd *
  page364_i12
#ISCELL
  pure_quanta_power universal_gnd *
  page364_i13
#CELL
  pure_quanta q_cap *
  page364_i14
#ISCELL
  pure_quanta_power universal_power *
  page364_i15
#ISCELL
  pure_quanta_power universal_gnd *
  page364_i22
#CELL
  pure_quanta q_res *
  page364_i24
#CELL
  pure_quanta q_res *
  page364_i25
#ISCELL
  pure_quanta_power universal_power *
  page364_i26
#ISCELL
  standard offpage *
  page364_i27
#CELL
  pure_quanta q_res *
  page364_i28
#CELL
  pure_quanta q_res *
  page364_i29
#CELL
  pure_quanta q_res *
  page364_i30
#CELL
  pure_quanta 74lvc1g08w57 *
  page364_i31
#CELL
  pure_quanta q_res *
  page364_i34
#ISCELL
  standard offpage *
  page364_i35
#ISCELL
  pure_quanta_power universal_gnd *
  page364_i36
#CELL
  pure_quanta 74lvc2g07dw7 *
  page364_i37
#ISCELL
  pure_quanta_power universal_power *
  page364_i38
#ISCELL
  pure_quanta_power universal_gnd *
  page364_i39
#CELL
  pure_quanta q_cap *
  page364_i40
#CELL
  pure_quanta q_res *
  page364_i41
#ISCELL
  standard offpage *
  page364_i42
#CELL
  pure_quanta q_res *
  page364_i43
#ISCELL
  pure_quanta_power universal_gnd *
  page364_i44
#ISCELL
  standard offpage *
  page364_i45
#ISCELL
  pure_quanta_power universal_power *
  page364_i46
#CELL
  pure_quanta q_res *
  page364_i47
#CELL
  pure_quanta q_res *
  page364_i48
#ISCELL
  standard offpage *
  page364_i49
#CELL
  pure_quanta q_res *
  page364_i50
#CELL
  pure_quanta q_res *
  page364_i51
#ISCELL
  pure_quanta_power universal_power *
  page364_i52
#CELL
  pure_quanta mosfet_nch_dual *
  page364_i53
#ISCELL
  pure_quanta_power universal_gnd *
  page364_i54
#CELL
  pure_quanta q_res *
  page364_i55
#ISCELL
  pure_quanta_power universal_power *
  page364_i56
#ISCELL
  pure_quanta_power universal_gnd *
  page364_i57
#CELL
  pure_quanta mosfet_nch_dual *
  page364_i58
#CELL
  pure_quanta q_res *
  page364_i59
#ISCELL
  pure_quanta_power universal_gnd *
  page364_i6
#ISCELL
  pure_quanta_power universal_power *
  page364_i60
#ISCELL
  pure_quanta_power universal_gnd *
  page364_i61
#CELL
  pure_quanta q_cap *
  page364_i62
#ISCELL
  standard offpage *
  page364_i63
#ISCELL
  pure_quanta_power universal_gnd *
  page364_i64
#ISCELL
  standard offpage *
  page364_i7
#ISCELL
  mstr_misc dns *
  *
#ISCELL
  pure_quanta quanta_title_block_c *
  *
#ISCELL
  standard offpage *
  page365_i1
#CELL
  pure_quanta q_res *
  page365_i10
#ISCELL
  pure_quanta_power universal_power *
  page365_i11
#CELL
  pure_quanta mosfet_nch_gds_esd_protected *
  page365_i14
#ISCELL
  pure_quanta_power universal_gnd *
  page365_i15
#CELL
  pure_quanta 74lvc2g07dw7 *
  page365_i16
#ISCELL
  pure_quanta_power universal_gnd *
  page365_i17
#CELL
  pure_quanta q_res *
  page365_i18
#ISCELL
  standard offpage *
  page365_i19
#CELL
  pure_quanta q_res *
  page365_i20
#ISCELL
  standard offpage *
  page365_i21
#ISCELL
  pure_quanta_power universal_power *
  page365_i22
#CELL
  pure_quanta q_cap *
  page365_i23
#ISCELL
  pure_quanta_power universal_gnd *
  page365_i24
#CELL
  pure_quanta q_cap *
  page365_i25
#ISCELL
  pure_quanta_power universal_gnd *
  page365_i26
#CELL
  pure_quanta q_res *
  page365_i27
#ISCELL
  pure_quanta_power universal_power *
  page365_i28
#CELL
  pure_quanta q_res *
  page365_i3
#ISCELL
  pure_quanta_power universal_power *
  page365_i30
#CELL
  pure_quanta q_res *
  page365_i31
#ISCELL
  pure_quanta_power universal_gnd *
  page365_i5
#CELL
  pure_quanta mosfet_nch_gds_esd_protected *
  page365_i6
#CELL
  pure_quanta q_res *
  page365_i7
#CELL
  pure_quanta q_res *
  page365_i8
#ISCELL
  pure_quanta_power universal_power *
  page365_i9
#ISCELL
  pure_quanta quanta_title_block_c *
  *
#ISCELL
  pure_quanta quanta_title_block_c *
  *
#ISCELL
  mstr_misc dns *
  *
#ISCELL
  pure_quanta quanta_title_block_c *
  *
#ISCELL
  pure_quanta_power universal_gnd *
  page246_i1
#ISCELL
  standard offpage *
  page246_i10
#ISCELL
  standard offpage *
  page246_i11
#ISCELL
  standard offpage *
  page246_i12
#ISCELL
  standard offpage *
  page246_i13
#ISCELL
  standard offpage *
  page246_i14
#ISCELL
  standard offpage *
  page246_i15
#ISCELL
  standard offpage *
  page246_i16
#ISCELL
  standard offpage *
  page246_i17
#ISCELL
  standard offpage *
  page246_i18
#ISCELL
  standard offpage *
  page246_i19
#CELL
  pure_quanta q_res *
  page246_i2
#ISCELL
  standard offpage *
  page246_i20
#ISCELL
  standard offpage *
  page246_i21
#ISCELL
  standard offpage *
  page246_i22
#ISCELL
  standard offpage *
  page246_i23
#ISCELL
  standard offpage *
  page246_i24
#ISCELL
  pure_quanta_power universal_gnd *
  page246_i25
#ISCELL
  standard offpage *
  page246_i26
#ISCELL
  standard offpage *
  page246_i27
#ISCELL
  standard offpage *
  page246_i28
#ISCELL
  standard offpage *
  page246_i29
#CELL
  pure_quanta q_res *
  page246_i3
#ISCELL
  standard offpage *
  page246_i30
#CELL
  pure_quanta q_res *
  page246_i31
#ISCELL
  standard offpage *
  page246_i32
#ISCELL
  standard offpage *
  page246_i33
#ISCELL
  pure_quanta_power universal_power *
  page246_i34
#CELL
  pure_quanta q_res *
  page246_i35
#ISCELL
  standard offpage *
  page246_i36
#CELL
  pure_quanta q_res *
  page246_i37
#ISCELL
  pure_quanta_power universal_power *
  page246_i38
#CELL
  pure_quanta q_res *
  page246_i39
#ISCELL
  pure_quanta_power universal_power *
  page246_i4
#CELL
  pure_quanta q_res *
  page246_i40
#CELL
  pure_quanta q_res *
  page246_i41
#CELL
  pure_quanta q_res *
  page246_i42
#CELL
  pure_quanta q_res *
  page246_i43
#CELL
  pure_quanta q_res *
  page246_i44
#CELL
  pure_quanta q_res *
  page246_i45
#CELL
  pure_quanta q_res *
  page246_i46
#CELL
  pure_quanta q_res *
  page246_i47
#ISCELL
  standard offpage *
  page246_i48
#ISCELL
  standard offpage *
  page246_i49
#ISCELL
  pure_quanta_power universal_gnd *
  page246_i5
#ISCELL
  standard offpage *
  page246_i50
#ISCELL
  standard offpage *
  page246_i51
#ISCELL
  standard offpage *
  page246_i52
#ISCELL
  standard offpage *
  page246_i53
#ISCELL
  standard offpage *
  page246_i54
#CELL
  pure_quanta q_res *
  page246_i55
#CELL
  pure_quanta q_res *
  page246_i56
#CELL
  pure_quanta q_res *
  page246_i57
#CELL
  pure_quanta q_res *
  page246_i58
#CELL
  pure_quanta q_res *
  page246_i59
#CELL
  pure_quanta q_res *
  page246_i6
#ISCELL
  pure_quanta_power universal_gnd *
  page246_i60
#CELL
  pure_quanta q_cap *
  page246_i61
#ISCELL
  pure_quanta_power universal_power *
  page246_i62
#ISCELL
  standard offpage *
  page246_i63
#ISCELL
  standard offpage *
  page246_i64
#ISCELL
  standard offpage *
  page246_i65
#ISCELL
  standard offpage *
  page246_i66
#ISCELL
  standard offpage *
  page246_i67
#ISCELL
  standard offpage *
  page246_i68
#ISCELL
  standard offpage *
  page246_i69
#CELL
  pure_quanta q_res *
  page246_i7
#ISCELL
  standard offpage *
  page246_i70
#ISCELL
  standard offpage *
  page246_i71
#ISCELL
  standard offpage *
  page246_i72
#ISCELL
  standard offpage *
  page246_i73
#ISCELL
  standard offpage *
  page246_i74
#ISCELL
  standard offpage *
  page246_i75
#ISCELL
  standard offpage *
  page246_i76
#ISCELL
  standard offpage *
  page246_i77
#ISCELL
  standard offpage *
  page246_i78
#ISCELL
  standard offpage *
  page246_i79
#ISCELL
  standard offpage *
  page246_i8
#ISCELL
  standard offpage *
  page246_i80
#ISCELL
  standard offpage *
  page246_i81
#CELL
  pure_quanta q_res *
  page246_i82
#CELL
  pure_quanta pca9539rpw *
  page246_i83
#ISCELL
  standard offpage *
  page246_i9
#ISCELL
  pure_quanta quanta_title_block_c *
  *
#ISCELL
  mstr_misc dns *
  *
#ISCELL
  pure_quanta quanta_title_block_c *
  *
#ISCELL
  standard offpage *
  page248_i1
#ISCELL
  pure_quanta_power universal_power *
  page248_i10
#ISCELL
  standard offpage *
  page248_i11
#ISCELL
  standard offpage *
  page248_i12
#ISCELL
  pure_quanta_power universal_gnd *
  page248_i13
#CELL
  pure_quanta pca9617adp *
  page248_i14
#CELL
  pure_quanta q_cap *
  page248_i15
#ISCELL
  pure_quanta_power universal_gnd *
  page248_i16
#ISCELL
  pure_quanta_power universal_power *
  page248_i17
#ISCELL
  pure_quanta_power universal_power *
  page248_i18
#CELL
  pure_quanta q_cap *
  page248_i19
#ISCELL
  standard offpage *
  page248_i2
#ISCELL
  pure_quanta_power universal_gnd *
  page248_i20
#ISCELL
  pure_quanta_power universal_power *
  page248_i22
#CELL
  pure_quanta q_res *
  page248_i23
#ISCELL
  standard offpage *
  page248_i24
#ISCELL
  standard offpage *
  page248_i25
#CELL
  pure_quanta q_res *
  page248_i27
#ISCELL
  pure_quanta_power universal_power *
  page248_i28
#ISCELL
  standard offpage *
  page248_i29
#ISCELL
  pure_quanta_power universal_gnd *
  page248_i3
#ISCELL
  standard offpage *
  page248_i30
#CELL
  pure_quanta q_res *
  page248_i31
#ISCELL
  standard offpage *
  page248_i32
#ISCELL
  standard offpage *
  page248_i33
#CELL
  pure_quanta q_res *
  page248_i34
#CELL
  pure_quanta q_res *
  page248_i35
#ISCELL
  standard offpage *
  page248_i37
#CELL
  pure_quanta q_res *
  page248_i38
#CELL
  pure_quanta q_cap *
  page248_i4
#ISCELL
  standard offpage *
  page248_i40
#CELL
  pure_quanta q_res *
  page248_i41
#ISCELL
  standard offpage *
  page248_i42
#CELL
  pure_quanta q_res *
  page248_i43
#CELL
  pure_quanta q_res *
  page248_i44
#CELL
  pure_quanta q_res *
  page248_i45
#ISCELL
  standard offpage *
  page248_i46
#ISCELL
  pure_quanta_power universal_gnd *
  page248_i5
#CELL
  pure_quanta pca9617adp *
  page248_i6
#ISCELL
  pure_quanta_power universal_power *
  page248_i7
#ISCELL
  pure_quanta_power universal_gnd *
  page248_i8
#CELL
  pure_quanta q_cap *
  page248_i9
#ISCELL
  mstr_misc dns *
  *
#ISCELL
  pure_quanta quanta_title_block_c *
  *
#ISCELL
  standard offpage *
  page249_i1
#ISCELL
  standard offpage *
  page249_i10
#ISCELL
  standard offpage *
  page249_i11
#CELL
  pure_quanta q_res *
  page249_i12
#CELL
  pure_quanta q_res *
  page249_i13
#CELL
  pure_quanta q_res *
  page249_i14
#CELL
  pure_quanta ltc4307cms8 *
  page249_i15
#ISCELL
  pure_quanta_power universal_gnd *
  page249_i16
#CELL
  pure_quanta q_res *
  page249_i17
#CELL
  pure_quanta q_res *
  page249_i18
#ISCELL
  pure_quanta_power universal_gnd *
  page249_i19
#ISCELL
  standard offpage *
  page249_i2
#ISCELL
  standard offpage *
  page249_i20
#ISCELL
  standard offpage *
  page249_i21
#ISCELL
  standard offpage *
  page249_i22
#CELL
  pure_quanta q_res *
  page249_i23
#CELL
  pure_quanta q_res *
  page249_i25
#CELL
  pure_quanta q_res *
  page249_i26
#CELL
  pure_quanta q_res *
  page249_i27
#CELL
  pure_quanta q_res *
  page249_i28
#ISCELL
  pure_quanta_power universal_gnd *
  page249_i29
#ISCELL
  standard offpage *
  page249_i3
#CELL
  pure_quanta ltc4307cms8 *
  page249_i30
#ISCELL
  pure_quanta_power universal_gnd *
  page249_i31
#CELL
  pure_quanta q_cap *
  page249_i32
#ISCELL
  pure_quanta_power universal_power *
  page249_i33
#CELL
  pure_quanta q_res *
  page249_i34
#CELL
  pure_quanta q_res *
  page249_i35
#CELL
  pure_quanta q_res *
  page249_i36
#CELL
  pure_quanta q_res *
  page249_i37
#CELL
  pure_quanta q_res *
  page249_i38
#CELL
  pure_quanta q_res *
  page249_i39
#ISCELL
  standard offpage *
  page249_i4
#ISCELL
  pure_quanta_power universal_power *
  page249_i40
#ISCELL
  pure_quanta_power universal_gnd *
  page249_i41
#CELL
  pure_quanta ltc4307cms8 *
  page249_i42
#CELL
  pure_quanta q_res *
  page249_i43
#CELL
  pure_quanta q_res *
  page249_i44
#CELL
  pure_quanta q_res *
  page249_i45
#ISCELL
  pure_quanta_power universal_gnd *
  page249_i46
#CELL
  pure_quanta q_res *
  page249_i47
#CELL
  pure_quanta q_res *
  page249_i48
#CELL
  pure_quanta ltc4307cms8 *
  page249_i49
#ISCELL
  standard offpage *
  page249_i5
#CELL
  pure_quanta q_res *
  page249_i50
#ISCELL
  pure_quanta_power universal_gnd *
  page249_i51
#CELL
  pure_quanta q_cap *
  page249_i52
#ISCELL
  pure_quanta_power universal_power *
  page249_i53
#CELL
  pure_quanta q_res *
  page249_i54
#ISCELL
  pure_quanta_power universal_power *
  page249_i55
#CELL
  pure_quanta q_res *
  page249_i56
#CELL
  pure_quanta q_res *
  page249_i57
#CELL
  pure_quanta q_res *
  page249_i58
#ISCELL
  pure_quanta_power universal_gnd *
  page249_i59
#ISCELL
  standard offpage *
  page249_i6
#ISCELL
  pure_quanta_power universal_power *
  page249_i60
#CELL
  pure_quanta q_cap *
  page249_i61
#CELL
  pure_quanta q_res *
  page249_i62
#CELL
  pure_quanta q_res *
  page249_i63
#ISCELL
  pure_quanta_power universal_power *
  page249_i64
#ISCELL
  standard offpage *
  page249_i65
#ISCELL
  standard offpage *
  page249_i66
#CELL
  pure_quanta q_res *
  page249_i67
#CELL
  pure_quanta q_res *
  page249_i68
#CELL
  pure_quanta q_res *
  page249_i69
#ISCELL
  pure_quanta_power universal_gnd *
  page249_i7
#ISCELL
  standard offpage *
  page249_i71
#ISCELL
  standard offpage *
  page249_i72
#CELL
  pure_quanta q_res *
  page249_i73
#CELL
  pure_quanta q_res *
  page249_i74
#ISCELL
  standard offpage *
  page249_i75
#ISCELL
  standard offpage *
  page249_i76
#ISCELL
  pure_quanta_power universal_gnd *
  page249_i77
#CELL
  pure_quanta q_cap *
  page249_i78
#ISCELL
  pure_quanta_power universal_power *
  page249_i79
#CELL
  pure_quanta q_res *
  page249_i8
#CELL
  pure_quanta q_res *
  page249_i80
#CELL
  pure_quanta q_res *
  page249_i81
#ISCELL
  pure_quanta_power universal_power *
  page249_i82
#ISCELL
  standard offpage *
  page249_i83
#ISCELL
  standard offpage *
  page249_i84
#CELL
  pure_quanta q_res *
  page249_i85
#CELL
  pure_quanta q_res *
  page249_i86
#ISCELL
  standard offpage *
  page249_i9
#ISCELL
  pure_quanta quanta_title_block_c *
  *
#ISCELL
  mstr_misc dns *
  *
#ISCELL
  pure_quanta quanta_title_block_c *
  *
#ISCELL
  pure_quanta_power universal_gnd *
  page252_i1
#CELL
  pure_quanta q_res *
  page252_i10
#ISCELL
  standard offpage *
  page252_i11
#ISCELL
  standard offpage *
  page252_i12
#ISCELL
  standard offpage *
  page252_i13
#ISCELL
  standard offpage *
  page252_i14
#ISCELL
  standard offpage *
  page252_i15
#ISCELL
  standard offpage *
  page252_i16
#ISCELL
  standard offpage *
  page252_i17
#ISCELL
  standard offpage *
  page252_i18
#ISCELL
  standard offpage *
  page252_i19
#CELL
  pure_quanta q_res *
  page252_i2
#ISCELL
  standard offpage *
  page252_i20
#CELL
  pure_quanta q_res *
  page252_i21
#ISCELL
  pure_quanta_power universal_power *
  page252_i22
#CELL
  pure_quanta q_res *
  page252_i23
#CELL
  pure_quanta q_res *
  page252_i24
#CELL
  pure_quanta q_res *
  page252_i25
#CELL
  pure_quanta q_res *
  page252_i26
#CELL
  pure_quanta q_res *
  page252_i27
#CELL
  pure_quanta q_res *
  page252_i28
#CELL
  pure_quanta q_res *
  page252_i29
#ISCELL
  pure_quanta_power universal_gnd *
  page252_i3
#ISCELL
  standard offpage *
  page252_i30
#ISCELL
  standard offpage *
  page252_i31
#ISCELL
  standard offpage *
  page252_i32
#CELL
  pure_quanta tca9548apwr *
  page252_i33
#CELL
  pure_quanta q_cap *
  page252_i34
#ISCELL
  pure_quanta_power universal_gnd *
  page252_i35
#ISCELL
  pure_quanta_power universal_power *
  page252_i36
#CELL
  pure_quanta q_res *
  page252_i37
#CELL
  pure_quanta q_res *
  page252_i38
#CELL
  pure_quanta q_res *
  page252_i39
#CELL
  pure_quanta q_res *
  page252_i4
#CELL
  pure_quanta q_res *
  page252_i40
#CELL
  pure_quanta q_res *
  page252_i41
#CELL
  pure_quanta q_res *
  page252_i42
#CELL
  pure_quanta q_res *
  page252_i43
#CELL
  pure_quanta q_res *
  page252_i44
#CELL
  pure_quanta q_res *
  page252_i45
#CELL
  pure_quanta q_res *
  page252_i46
#CELL
  pure_quanta q_res *
  page252_i47
#CELL
  pure_quanta q_res *
  page252_i48
#CELL
  pure_quanta q_res *
  page252_i49
#ISCELL
  pure_quanta_power universal_gnd *
  page252_i5
#CELL
  pure_quanta q_res *
  page252_i50
#ISCELL
  pure_quanta_power universal_power *
  page252_i51
#ISCELL
  standard offpage *
  page252_i52
#ISCELL
  standard offpage *
  page252_i53
#ISCELL
  standard offpage *
  page252_i54
#ISCELL
  standard offpage *
  page252_i55
#ISCELL
  standard offpage *
  page252_i56
#ISCELL
  standard offpage *
  page252_i57
#ISCELL
  standard offpage *
  page252_i58
#ISCELL
  standard offpage *
  page252_i59
#CELL
  pure_quanta q_res *
  page252_i6
#ISCELL
  standard offpage *
  page252_i60
#ISCELL
  standard offpage *
  page252_i61
#ISCELL
  standard offpage *
  page252_i62
#ISCELL
  standard offpage *
  page252_i63
#ISCELL
  standard offpage *
  page252_i64
#ISCELL
  standard offpage *
  page252_i65
#ISCELL
  pure_quanta_power universal_gnd *
  page252_i66
#CELL
  pure_quanta q_res *
  page252_i67
#CELL
  pure_quanta q_res *
  page252_i68
#CELL
  pure_quanta q_res *
  page252_i69
#CELL
  pure_quanta q_res *
  page252_i7
#CELL
  pure_quanta q_res *
  page252_i70
#CELL
  pure_quanta q_res *
  page252_i71
#CELL
  pure_quanta q_res *
  page252_i72
#CELL
  pure_quanta q_res *
  page252_i73
#CELL
  pure_quanta q_res *
  page252_i74
#ISCELL
  standard offpage *
  page252_i75
#ISCELL
  standard offpage *
  page252_i76
#ISCELL
  standard offpage *
  page252_i77
#ISCELL
  standard offpage *
  page252_i78
#ISCELL
  standard offpage *
  page252_i79
#CELL
  pure_quanta q_res *
  page252_i8
#ISCELL
  standard offpage *
  page252_i80
#ISCELL
  standard offpage *
  page252_i81
#ISCELL
  standard offpage *
  page252_i82
#CELL
  pure_quanta q_res *
  page252_i83
#CELL
  pure_quanta q_res *
  page252_i84
#ISCELL
  standard offpage *
  page252_i85
#ISCELL
  standard offpage *
  page252_i86
#CELL
  pure_quanta q_res *
  page252_i89
#ISCELL
  pure_quanta_power universal_power *
  page252_i9
#CELL
  pure_quanta q_res *
  page252_i90
#ISCELL
  standard offpage *
  page252_i91
#ISCELL
  standard offpage *
  page252_i92
#ISCELL
  pure_quanta quanta_title_block_c *
  *
#ISCELL
  standard offpage *
  page253_i1
#CELL
  pure_quanta q_res *
  page253_i10
#CELL
  pure_quanta q_res *
  page253_i11
#CELL
  pure_quanta q_res *
  page253_i12
#ISCELL
  standard offpage *
  page253_i13
#ISCELL
  standard offpage *
  page253_i14
#ISCELL
  standard offpage *
  page253_i15
#ISCELL
  standard offpage *
  page253_i16
#ISCELL
  standard offpage *
  page253_i17
#ISCELL
  standard offpage *
  page253_i18
#ISCELL
  standard offpage *
  page253_i19
#ISCELL
  standard offpage *
  page253_i2
#ISCELL
  standard offpage *
  page253_i20
#ISCELL
  standard offpage *
  page253_i21
#ISCELL
  standard offpage *
  page253_i22
#CELL
  pure_quanta q_res *
  page253_i23
#CELL
  pure_quanta q_res *
  page253_i24
#CELL
  pure_quanta q_res *
  page253_i25
#CELL
  pure_quanta q_res *
  page253_i26
#CELL
  pure_quanta q_res *
  page253_i27
#CELL
  pure_quanta q_res *
  page253_i28
#ISCELL
  standard offpage *
  page253_i29
#CELL
  pure_quanta q_res *
  page253_i3
#ISCELL
  standard offpage *
  page253_i30
#ISCELL
  standard offpage *
  page253_i31
#ISCELL
  standard offpage *
  page253_i32
#ISCELL
  standard offpage *
  page253_i33
#ISCELL
  standard offpage *
  page253_i34
#CELL
  pure_quanta q_res *
  page253_i4
#CELL
  pure_quanta q_res *
  page253_i5
#CELL
  pure_quanta q_res *
  page253_i6
#CELL
  pure_quanta q_res *
  page253_i7
#CELL
  pure_quanta q_res *
  page253_i8
#CELL
  pure_quanta q_res *
  page253_i9
#ISCELL
  mstr_misc dns *
  *
#ISCELL
  pure_quanta quanta_title_block_c *
  *
#CELL
  pure_quanta q_res *
  page251_i1
#CELL
  pure_quanta q_res *
  page251_i10
#ISCELL
  standard offpage *
  page251_i11
#ISCELL
  standard offpage *
  page251_i12
#ISCELL
  standard offpage *
  page251_i13
#ISCELL
  standard offpage *
  page251_i14
#ISCELL
  standard offpage *
  page251_i15
#ISCELL
  standard offpage *
  page251_i16
#ISCELL
  standard offpage *
  page251_i17
#CELL
  pure_quanta q_res *
  page251_i18
#CELL
  pure_quanta q_res *
  page251_i19
#ISCELL
  pure_quanta_power universal_gnd *
  page251_i2
#CELL
  pure_quanta q_res *
  page251_i20
#CELL
  pure_quanta q_res *
  page251_i21
#ISCELL
  standard offpage *
  page251_i22
#ISCELL
  standard offpage *
  page251_i23
#ISCELL
  standard offpage *
  page251_i24
#ISCELL
  standard offpage *
  page251_i25
#ISCELL
  standard offpage *
  page251_i26
#CELL
  pure_quanta q_res *
  page251_i27
#ISCELL
  pure_quanta_power universal_power *
  page251_i28
#CELL
  pure_quanta q_res *
  page251_i29
#ISCELL
  pure_quanta_power universal_gnd *
  page251_i3
#CELL
  pure_quanta q_res *
  page251_i30
#CELL
  pure_quanta q_res *
  page251_i31
#CELL
  pure_quanta q_res *
  page251_i32
#CELL
  pure_quanta q_res *
  page251_i33
#ISCELL
  standard offpage *
  page251_i34
#ISCELL
  standard offpage *
  page251_i35
#ISCELL
  standard offpage *
  page251_i36
#ISCELL
  pure_quanta_power universal_gnd *
  page251_i37
#CELL
  pure_quanta q_cap *
  page251_i38
#ISCELL
  pure_quanta_power universal_power *
  page251_i39
#CELL
  pure_quanta q_res *
  page251_i4
#CELL
  pure_quanta q_res *
  page251_i40
#CELL
  pure_quanta q_res *
  page251_i41
#CELL
  pure_quanta q_res *
  page251_i42
#CELL
  pure_quanta q_res *
  page251_i43
#CELL
  pure_quanta q_res *
  page251_i44
#CELL
  pure_quanta q_res *
  page251_i45
#ISCELL
  pure_quanta_power universal_gnd *
  page251_i46
#CELL
  pure_quanta q_res *
  page251_i47
#CELL
  pure_quanta q_res *
  page251_i48
#CELL
  pure_quanta q_res *
  page251_i49
#ISCELL
  pure_quanta_power universal_gnd *
  page251_i5
#CELL
  pure_quanta q_res *
  page251_i50
#ISCELL
  pure_quanta_power universal_power *
  page251_i51
#CELL
  pure_quanta q_res *
  page251_i52
#CELL
  pure_quanta q_res *
  page251_i53
#ISCELL
  standard offpage *
  page251_i54
#ISCELL
  standard offpage *
  page251_i55
#ISCELL
  standard offpage *
  page251_i56
#ISCELL
  standard offpage *
  page251_i57
#ISCELL
  standard offpage *
  page251_i58
#ISCELL
  standard offpage *
  page251_i59
#CELL
  pure_quanta q_res *
  page251_i6
#ISCELL
  standard offpage *
  page251_i60
#ISCELL
  standard offpage *
  page251_i61
#ISCELL
  standard offpage *
  page251_i62
#ISCELL
  standard offpage *
  page251_i63
#ISCELL
  standard offpage *
  page251_i64
#ISCELL
  standard offpage *
  page251_i65
#CELL
  pure_quanta q_res *
  page251_i66
#CELL
  pure_quanta q_res *
  page251_i67
#CELL
  pure_quanta q_res *
  page251_i68
#CELL
  pure_quanta q_res *
  page251_i69
#CELL
  pure_quanta q_res *
  page251_i7
#ISCELL
  standard offpage *
  page251_i70
#ISCELL
  standard offpage *
  page251_i71
#ISCELL
  standard offpage *
  page251_i72
#ISCELL
  standard offpage *
  page251_i73
#CELL
  pure_quanta tca9548apwr *
  page251_i74
#CELL
  pure_quanta q_res *
  page251_i75
#CELL
  pure_quanta q_res *
  page251_i76
#ISCELL
  standard offpage *
  page251_i77
#ISCELL
  standard offpage *
  page251_i78
#CELL
  pure_quanta q_res *
  page251_i79
#CELL
  pure_quanta q_res *
  page251_i8
#CELL
  pure_quanta q_res *
  page251_i80
#ISCELL
  standard offpage *
  page251_i81
#ISCELL
  standard offpage *
  page251_i82
#CELL
  pure_quanta q_res *
  page251_i83
#CELL
  pure_quanta q_res *
  page251_i84
#ISCELL
  standard offpage *
  page251_i85
#ISCELL
  standard offpage *
  page251_i86
#ISCELL
  pure_quanta_power universal_power *
  page251_i9
#ISCELL
  pure_quanta quanta_title_block_c *
  *
#ISCELL
  standard offpage *
  page368_i1
#CELL
  pure_quanta mosfet_nch_dual *
  page368_i10
#CELL
  pure_quanta q_res *
  page368_i11
#ISCELL
  pure_quanta_power universal_power *
  page368_i12
#CELL
  pure_quanta q_res *
  page368_i13
#ISCELL
  standard offpage *
  page368_i14
#ISCELL
  standard offpage *
  page368_i15
#ISCELL
  standard offpage *
  page368_i16
#ISCELL
  standard offpage *
  page368_i2
#CELL
  pure_quanta mosfet_nch_dual *
  page368_i3
#ISCELL
  pure_quanta_power universal_gnd *
  page368_i4
#CELL
  pure_quanta q_res *
  page368_i5
#ISCELL
  pure_quanta_power universal_power *
  page368_i6
#CELL
  pure_quanta q_res *
  page368_i7
#CELL
  pure_quanta q_res *
  page368_i8
#ISCELL
  pure_quanta_power universal_gnd *
  page368_i9
#ISCELL
  pure_quanta quanta_title_block_c *
  *
#ISCELL
  standard offpage *
  page254_i1
#ISCELL
  pure_quanta_power universal_power *
  page254_i10
#ISCELL
  pure_quanta_power universal_power *
  page254_i11
#CELL
  pure_quanta q_led *
  page254_i14
#CELL
  pure_quanta q_res *
  page254_i15
#ISCELL
  pure_quanta_power universal_power *
  page254_i16
#CELL
  pure_quanta q_led *
  page254_i17
#CELL
  pure_quanta mosfet_nch_dual *
  page254_i18
#ISCELL
  standard offpage *
  page254_i19
#ISCELL
  pure_quanta_power universal_gnd *
  page254_i2
#ISCELL
  pure_quanta_power universal_gnd *
  page254_i20
#CELL
  pure_quanta q_res *
  page254_i21
#ISCELL
  pure_quanta_power universal_power *
  page254_i22
#CELL
  pure_quanta q_led *
  page254_i23
#CELL
  pure_quanta mosfet_nch_dual *
  page254_i24
#CELL
  pure_quanta q_led *
  page254_i3
#ISCELL
  pure_quanta_power universal_power *
  page254_i31
#CELL
  pure_quanta q_res *
  page254_i32
#CELL
  pure_quanta q_led *
  page254_i33
#ISCELL
  pure_quanta_power universal_gnd *
  page254_i34
#CELL
  pure_quanta mosfet_nch_dual *
  page254_i35
#ISCELL
  standard offpage *
  page254_i36
#ISCELL
  standard offpage *
  page254_i37
#CELL
  pure_quanta mosfet_nch_dual *
  page254_i38
#ISCELL
  pure_quanta_power universal_gnd *
  page254_i39
#ISCELL
  pure_quanta_power universal_gnd *
  page254_i4
#CELL
  pure_quanta q_led *
  page254_i40
#CELL
  pure_quanta q_res *
  page254_i41
#ISCELL
  pure_quanta_power universal_power *
  page254_i42
#CELL
  pure_quanta q_led *
  page254_i43
#ISCELL
  pure_quanta_power universal_power *
  page254_i44
#CELL
  pure_quanta q_res *
  page254_i45
#ISCELL
  pure_quanta_power universal_gnd *
  page254_i46
#CELL
  pure_quanta mosfet_nch_dual *
  page254_i47
#ISCELL
  standard offpage *
  page254_i48
#ISCELL
  pure_quanta_power universal_gnd *
  page254_i5
#CELL
  pure_quanta q_res *
  page254_i8
#CELL
  pure_quanta q_res *
  page254_i9
#ISCELL
  pure_quanta quanta_title_block_c *
  *
#ISCELL
  standard offpage *
  page374_i1
#ISCELL
  pure_quanta_power universal_gnd *
  page374_i10
#CELL
  pure_quanta q_led *
  page374_i11
#CELL
  pure_quanta q_res *
  page374_i12
#CELL
  pure_quanta q_led *
  page374_i13
#CELL
  pure_quanta q_led *
  page374_i14
#CELL
  pure_quanta q_res *
  page374_i15
#CELL
  pure_quanta q_res *
  page374_i16
#ISCELL
  standard offpage *
  page374_i17
#CELL
  pure_quanta mosfet_nch_dual *
  page374_i18
#CELL
  pure_quanta q_led *
  page374_i19
#ISCELL
  standard offpage *
  page374_i2
#CELL
  pure_quanta q_res *
  page374_i20
#ISCELL
  pure_quanta_power universal_power *
  page374_i21
#ISCELL
  standard offpage *
  page374_i22
#CELL
  pure_quanta mosfet_nch_dual *
  page374_i23
#ISCELL
  pure_quanta_power universal_power *
  page374_i24
#ISCELL
  standard offpage *
  page374_i25
#ISCELL
  pure_quanta_power universal_power *
  page374_i26
#CELL
  pure_quanta mosfet_nch_dual *
  page374_i27
#ISCELL
  pure_quanta_power universal_gnd *
  page374_i28
#ISCELL
  pure_quanta_power universal_gnd *
  page374_i29
#CELL
  pure_quanta mosfet_nch_dual *
  page374_i3
#CELL
  pure_quanta q_led *
  page374_i30
#ISCELL
  pure_quanta_power universal_gnd *
  page374_i31
#CELL
  pure_quanta q_led *
  page374_i32
#ISCELL
  pure_quanta_power universal_power *
  page374_i33
#ISCELL
  standard offpage *
  page374_i34
#CELL
  pure_quanta mosfet_nch_dual *
  page374_i35
#CELL
  pure_quanta q_led *
  page374_i36
#CELL
  pure_quanta q_res *
  page374_i37
#CELL
  pure_quanta q_res *
  page374_i38
#ISCELL
  pure_quanta_power universal_power *
  page374_i39
#ISCELL
  pure_quanta_power universal_gnd *
  page374_i4
#ISCELL
  pure_quanta_power universal_power *
  page374_i40
#CELL
  pure_quanta q_res *
  page374_i41
#ISCELL
  pure_quanta_power universal_power *
  page374_i42
#CELL
  pure_quanta mosfet_nch_dual *
  page374_i43
#ISCELL
  pure_quanta_power universal_gnd *
  page374_i5
#CELL
  pure_quanta mosfet_nch_dual *
  page374_i6
#ISCELL
  standard offpage *
  page374_i7
#CELL
  pure_quanta mosfet_nch_dual *
  page374_i8
#ISCELL
  pure_quanta_power universal_gnd *
  page374_i9
#ISCELL
  pure_quanta quanta_title_block_c *
  *
#ISCELL
  pure_quanta_power universal_gnd *
  page375_i1
#CELL
  pure_quanta mosfet_nch_dual *
  page375_i10
#CELL
  pure_quanta mosfet_nch_dual *
  page375_i11
#ISCELL
  pure_quanta_power universal_gnd *
  page375_i12
#CELL
  pure_quanta q_led *
  page375_i13
#CELL
  pure_quanta q_led *
  page375_i14
#CELL
  pure_quanta q_res *
  page375_i15
#CELL
  pure_quanta q_res *
  page375_i16
#CELL
  pure_quanta q_led *
  page375_i17
#CELL
  pure_quanta q_res *
  page375_i18
#CELL
  pure_quanta q_led *
  page375_i19
#CELL
  pure_quanta mosfet_nch_dual *
  page375_i2
#CELL
  pure_quanta q_res *
  page375_i20
#ISCELL
  pure_quanta_power universal_power *
  page375_i21
#ISCELL
  pure_quanta_power universal_power *
  page375_i22
#ISCELL
  standard offpage *
  page375_i25
#ISCELL
  pure_quanta_power universal_power *
  page375_i26
#ISCELL
  standard offpage *
  page375_i27
#ISCELL
  pure_quanta_power universal_gnd *
  page375_i28
#CELL
  pure_quanta mosfet_nch_dual *
  page375_i29
#ISCELL
  standard offpage *
  page375_i3
#CELL
  pure_quanta mosfet_nch_dual *
  page375_i30
#ISCELL
  pure_quanta_power universal_gnd *
  page375_i31
#CELL
  pure_quanta q_led *
  page375_i33
#ISCELL
  pure_quanta_power universal_power *
  page375_i34
#CELL
  pure_quanta q_led *
  page375_i35
#CELL
  pure_quanta q_res *
  page375_i38
#ISCELL
  pure_quanta_power universal_power *
  page375_i39
#ISCELL
  standard offpage *
  page375_i4
#CELL
  pure_quanta q_res *
  page375_i40
#ISCELL
  pure_quanta_power universal_power *
  page375_i41
#CELL
  pure_quanta q_led *
  page375_i42
#ISCELL
  pure_quanta_power universal_gnd *
  page375_i43
#CELL
  pure_quanta q_res *
  page375_i44
#CELL
  pure_quanta q_res *
  page375_i45
#CELL
  pure_quanta q_res *
  page375_i46
#ISCELL
  pure_quanta_power universal_power *
  page375_i47
#ISCELL
  pure_quanta_power universal_power *
  page375_i48
#CELL
  pure_quanta q_res *
  page375_i49
#ISCELL
  standard offpage *
  page375_i5
#CELL
  pure_quanta q_res *
  page375_i50
#CELL
  pure_quanta q_res *
  page375_i51
#CELL
  pure_quanta q_led *
  page375_i52
#ISCELL
  pure_quanta_power universal_gnd *
  page375_i53
#ISCELL
  pure_quanta_power universal_power *
  page375_i54
#CELL
  pure_quanta q_res *
  page375_i55
#CELL
  pure_quanta q_led *
  page375_i56
#CELL
  pure_quanta mosfet_nch_dual *
  page375_i57
#CELL
  pure_quanta mosfet_nch_dual *
  page375_i58
#ISCELL
  pure_quanta_power universal_gnd *
  page375_i59
#ISCELL
  standard offpage *
  page375_i6
#ISCELL
  pure_quanta_power universal_power *
  page375_i60
#ISCELL
  pure_quanta_power universal_gnd *
  page375_i61
#CELL
  pure_quanta q_res *
  page375_i62
#ISCELL
  standard offpage *
  page375_i63
#CELL
  pure_quanta mosfet_nch_dual *
  page375_i7
#ISCELL
  pure_quanta_power universal_gnd *
  page375_i8
#ISCELL
  pure_quanta_power universal_gnd *
  page375_i9
#ISCELL
  mstr_misc dns *
  *
#ISCELL
  pure_quanta quanta_title_block_c *
  *
#ISCELL
  pure_quanta_power cad_note *
  *
#ISCELL
  pure_quanta_power universal_gnd *
  page369_i1
#CELL
  pure_quanta q_res *
  page369_i10
#ISCELL
  standard offpage *
  page369_i100
#ISCELL
  standard offpage *
  page369_i101
#ISCELL
  standard offpage *
  page369_i102
#ISCELL
  standard offpage *
  page369_i103
#ISCELL
  standard offpage *
  page369_i104
#ISCELL
  standard offpage *
  page369_i105
#ISCELL
  standard offpage *
  page369_i106
#CELL
  pure_quanta q_res *
  page369_i107
#CELL
  pure_quanta q_res *
  page369_i108
#CELL
  pure_quanta q_res *
  page369_i109
#ISCELL
  pure_quanta_power universal_gnd *
  page369_i11
#CELL
  pure_quanta q_res *
  page369_i110
#ISCELL
  pure_quanta_power universal_gnd *
  page369_i111
#CELL
  pure_quanta q_cap *
  page369_i112
#ISCELL
  pure_quanta_power universal_gnd *
  page369_i113
#CELL
  pure_quanta q_cap *
  page369_i114
#CELL
  pure_quanta q_res *
  page369_i115
#ISCELL
  standard offpage *
  page369_i116
#ISCELL
  standard offpage *
  page369_i117
#ISCELL
  pure_quanta_power universal_gnd *
  page369_i118
#CELL
  pure_quanta q_cap *
  page369_i119
#ISCELL
  pure_quanta_power universal_gnd *
  page369_i12
#ISCELL
  pure_quanta_power universal_gnd *
  page369_i120
#CELL
  pure_quanta q_cap *
  page369_i121
#ISCELL
  standard offpage *
  page369_i122
#ISCELL
  standard offpage *
  page369_i123
#ISCELL
  standard offpage *
  page369_i124
#ISCELL
  pure_quanta_power universal_gnd *
  page369_i125
#ISCELL
  standard offpage *
  page369_i126
#ISCELL
  standard offpage *
  page369_i127
#ISCELL
  standard offpage *
  page369_i128
#ISCELL
  standard offpage *
  page369_i129
#ISCELL
  pure_quanta_power universal_gnd *
  page369_i13
#CELL
  pure_quanta q_res *
  page369_i130
#CELL
  pure_quanta q_res *
  page369_i131
#ISCELL
  standard offpage *
  page369_i132
#ISCELL
  standard offpage *
  page369_i133
#ISCELL
  standard offpage *
  page369_i134
#ISCELL
  standard offpage *
  page369_i135
#ISCELL
  standard offpage *
  page369_i136
#ISCELL
  standard offpage *
  page369_i137
#ISCELL
  standard offpage *
  page369_i138
#ISCELL
  standard offpage *
  page369_i139
#CELL
  pure_quanta q_res *
  page369_i14
#ISCELL
  standard offpage *
  page369_i140
#ISCELL
  standard offpage *
  page369_i141
#CELL
  pure_quanta adc128d818cimtxnopb *
  page369_i142
#ISCELL
  standard offpage *
  page369_i143
#ISCELL
  standard offpage *
  page369_i144
#ISCELL
  pure_quanta_power universal_gnd *
  page369_i145
#CELL
  pure_quanta q_res *
  page369_i146
#CELL
  pure_quanta q_res *
  page369_i147
#ISCELL
  pure_quanta_power universal_gnd *
  page369_i148
#CELL
  pure_quanta q_res *
  page369_i149
#CELL
  pure_quanta q_res *
  page369_i15
#CELL
  pure_quanta q_res *
  page369_i150
#ISCELL
  pure_quanta_power universal_gnd *
  page369_i151
#ISCELL
  standard offpage *
  page369_i152
#ISCELL
  standard offpage *
  page369_i153
#ISCELL
  standard offpage *
  page369_i154
#ISCELL
  standard offpage *
  page369_i155
#ISCELL
  standard offpage *
  page369_i156
#ISCELL
  standard offpage *
  page369_i157
#ISCELL
  standard offpage *
  page369_i158
#ISCELL
  standard offpage *
  page369_i159
#CELL
  pure_quanta q_res *
  page369_i16
#CELL
  pure_quanta q_res *
  page369_i160
#ISCELL
  pure_quanta_power universal_gnd *
  page369_i161
#CELL
  pure_quanta q_cap *
  page369_i162
#ISCELL
  pure_quanta_power universal_gnd *
  page369_i163
#ISCELL
  standard offpage *
  page369_i164
#ISCELL
  standard offpage *
  page369_i165
#CELL
  pure_quanta q_cap *
  page369_i166
#CELL
  pure_quanta q_inductor *
  page369_i167
#ISCELL
  pure_quanta_power universal_power *
  page369_i168
#CELL
  pure_quanta max11617eeet *
  page369_i169
#CELL
  pure_quanta q_cap *
  page369_i17
#CELL
  pure_quanta q_res *
  page369_i170
#CELL
  pure_quanta q_res *
  page369_i18
#ISCELL
  pure_quanta_power universal_power *
  page369_i19
#ISCELL
  standard offpage *
  page369_i2
#CELL
  pure_quanta q_res *
  page369_i20
#CELL
  pure_quanta q_res *
  page369_i21
#CELL
  pure_quanta q_res *
  page369_i22
#CELL
  pure_quanta q_res *
  page369_i23
#ISCELL
  pure_quanta_power universal_gnd *
  page369_i24
#ISCELL
  pure_quanta_power universal_power *
  page369_i25
#CELL
  pure_quanta q_res *
  page369_i26
#CELL
  pure_quanta q_res *
  page369_i27
#CELL
  pure_quanta q_res *
  page369_i28
#ISCELL
  pure_quanta_power universal_power *
  page369_i29
#ISCELL
  pure_quanta_power universal_gnd *
  page369_i3
#CELL
  pure_quanta q_res *
  page369_i30
#ISCELL
  pure_quanta_power universal_gnd *
  page369_i31
#CELL
  pure_quanta q_cap *
  page369_i32
#ISCELL
  pure_quanta_power universal_gnd *
  page369_i33
#CELL
  pure_quanta q_cap *
  page369_i34
#ISCELL
  pure_quanta_power universal_gnd *
  page369_i35
#CELL
  pure_quanta q_cap *
  page369_i36
#ISCELL
  pure_quanta_power universal_gnd *
  page369_i37
#CELL
  pure_quanta q_res *
  page369_i38
#ISCELL
  pure_quanta_power universal_gnd *
  page369_i39
#CELL
  pure_quanta q_res *
  page369_i40
#CELL
  pure_quanta q_res *
  page369_i41
#CELL
  pure_quanta q_res *
  page369_i42
#ISCELL
  pure_quanta_power universal_gnd *
  page369_i43
#CELL
  pure_quanta q_cap *
  page369_i44
#ISCELL
  pure_quanta_power universal_gnd *
  page369_i45
#CELL
  pure_quanta q_cap *
  page369_i46
#ISCELL
  pure_quanta_power universal_gnd *
  page369_i47
#ISCELL
  standard offpage *
  page369_i48
#ISCELL
  standard offpage *
  page369_i49
#ISCELL
  pure_quanta_power universal_power *
  page369_i5
#ISCELL
  standard offpage *
  page369_i50
#ISCELL
  standard offpage *
  page369_i51
#CELL
  pure_quanta q_cap *
  page369_i52
#ISCELL
  standard offpage *
  page369_i53
#ISCELL
  standard offpage *
  page369_i54
#CELL
  pure_quanta q_cap *
  page369_i55
#ISCELL
  pure_quanta_power universal_gnd *
  page369_i56
#ISCELL
  standard offpage *
  page369_i57
#ISCELL
  standard offpage *
  page369_i58
#ISCELL
  standard offpage *
  page369_i59
#CELL
  pure_quanta q_res *
  page369_i6
#ISCELL
  standard offpage *
  page369_i60
#ISCELL
  standard offpage *
  page369_i61
#ISCELL
  standard offpage *
  page369_i62
#ISCELL
  standard offpage *
  page369_i63
#ISCELL
  standard offpage *
  page369_i64
#ISCELL
  standard offpage *
  page369_i65
#CELL
  pure_quanta q_res *
  page369_i66
#ISCELL
  pure_quanta_power universal_power *
  page369_i67
#CELL
  pure_quanta q_res *
  page369_i68
#CELL
  pure_quanta q_inductor *
  page369_i69
#CELL
  pure_quanta q_res *
  page369_i7
#ISCELL
  pure_quanta_power universal_gnd *
  page369_i70
#CELL
  pure_quanta q_cap *
  page369_i71
#CELL
  pure_quanta q_cap *
  page369_i72
#CELL
  pure_quanta q_res *
  page369_i73
#CELL
  pure_quanta q_res *
  page369_i74
#ISCELL
  pure_quanta_power universal_gnd *
  page369_i75
#CELL
  pure_quanta q_cap *
  page369_i76
#ISCELL
  pure_quanta_power universal_gnd *
  page369_i77
#CELL
  pure_quanta q_cap *
  page369_i78
#CELL
  pure_quanta q_res *
  page369_i79
#CELL
  pure_quanta q_res *
  page369_i8
#CELL
  pure_quanta q_res *
  page369_i80
#CELL
  pure_quanta q_res *
  page369_i81
#CELL
  pure_quanta q_res *
  page369_i82
#CELL
  pure_quanta q_res *
  page369_i83
#CELL
  pure_quanta q_cap *
  page369_i84
#ISCELL
  pure_quanta_power universal_gnd *
  page369_i85
#ISCELL
  pure_quanta_power universal_gnd *
  page369_i86
#CELL
  pure_quanta q_cap *
  page369_i87
#ISCELL
  pure_quanta_power universal_power *
  page369_i88
#ISCELL
  standard offpage *
  page369_i89
#CELL
  pure_quanta q_res *
  page369_i9
#ISCELL
  standard offpage *
  page369_i90
#ISCELL
  standard offpage *
  page369_i91
#ISCELL
  standard offpage *
  page369_i92
#ISCELL
  standard offpage *
  page369_i93
#ISCELL
  standard offpage *
  page369_i94
#ISCELL
  standard offpage *
  page369_i95
#ISCELL
  pure_quanta_power universal_gnd *
  page369_i96
#ISCELL
  pure_quanta_power universal_gnd *
  page369_i97
#CELL
  pure_quanta q_cap *
  page369_i98
#CELL
  pure_quanta q_cap *
  page369_i99
#ISCELL
  mstr_misc dns *
  *
#ISCELL
  pure_quanta quanta_title_block_c *
  *
#ISCELL
  pure_quanta_power cad_note *
  *
#ISCELL
  pure_quanta_power universal_gnd *
  page263_i114
#CELL
  pure_quanta q_cap *
  page263_i115
#ISCELL
  standard offpage *
  page263_i116
#ISCELL
  standard offpage *
  page263_i117
#ISCELL
  pure_quanta_power universal_gnd *
  page263_i118
#CELL
  pure_quanta q_res *
  page263_i119
#CELL
  pure_quanta q_res *
  page263_i12
#ISCELL
  standard offpage *
  page263_i120
#ISCELL
  standard offpage *
  page263_i121
#ISCELL
  standard offpage *
  page263_i122
#ISCELL
  standard offpage *
  page263_i123
#ISCELL
  standard offpage *
  page263_i124
#ISCELL
  standard offpage *
  page263_i125
#ISCELL
  standard offpage *
  page263_i126
#ISCELL
  standard offpage *
  page263_i127
#ISCELL
  standard offpage *
  page263_i128
#ISCELL
  standard offpage *
  page263_i129
#CELL
  pure_quanta q_res *
  page263_i13
#CELL
  pure_quanta q_cap *
  page263_i130
#CELL
  pure_quanta q_res *
  page263_i131
#ISCELL
  standard offpage *
  page263_i132
#ISCELL
  standard offpage *
  page263_i133
#ISCELL
  standard offpage *
  page263_i134
#ISCELL
  standard offpage *
  page263_i135
#ISCELL
  standard offpage *
  page263_i136
#ISCELL
  standard offpage *
  page263_i137
#CELL
  pure_quanta q_res *
  page263_i138
#CELL
  pure_quanta q_res *
  page263_i139
#ISCELL
  pure_quanta_power universal_power *
  page263_i14
#CELL
  pure_quanta q_res *
  page263_i140
#CELL
  pure_quanta q_res *
  page263_i141
#CELL
  pure_quanta adc128d818cimtxnopb *
  page263_i142
#ISCELL
  pure_quanta_power universal_gnd *
  page263_i143
#ISCELL
  standard offpage *
  page263_i144
#ISCELL
  standard offpage *
  page263_i145
#ISCELL
  standard offpage *
  page263_i146
#ISCELL
  standard offpage *
  page263_i147
#ISCELL
  standard offpage *
  page263_i148
#ISCELL
  standard offpage *
  page263_i149
#CELL
  pure_quanta q_res *
  page263_i15
#ISCELL
  standard offpage *
  page263_i150
#ISCELL
  standard offpage *
  page263_i151
#CELL
  pure_quanta q_cap *
  page263_i152
#ISCELL
  pure_quanta_power universal_gnd *
  page263_i153
#CELL
  pure_quanta q_res *
  page263_i154
#ISCELL
  pure_quanta_power universal_gnd *
  page263_i155
#CELL
  pure_quanta max11617eeet *
  page263_i156
#ISCELL
  pure_quanta_power universal_gnd *
  page263_i157
#ISCELL
  standard offpage *
  page263_i158
#ISCELL
  standard offpage *
  page263_i159
#CELL
  pure_quanta q_res *
  page263_i16
#ISCELL
  standard offpage *
  page263_i160
#ISCELL
  standard offpage *
  page263_i161
#ISCELL
  standard offpage *
  page263_i162
#ISCELL
  standard offpage *
  page263_i163
#ISCELL
  pure_quanta_power universal_gnd *
  page263_i164
#CELL
  pure_quanta q_cap *
  page263_i165
#CELL
  pure_quanta q_cap *
  page263_i166
#ISCELL
  pure_quanta_power universal_gnd *
  page263_i167
#CELL
  pure_quanta q_inductor *
  page263_i168
#ISCELL
  pure_quanta_power universal_power *
  page263_i169
#ISCELL
  pure_quanta_power universal_power *
  page263_i170
#ISCELL
  standard offpage *
  page263_i171
#ISCELL
  standard offpage *
  page263_i172
#CELL
  pure_quanta q_cap *
  page263_i173
#ISCELL
  pure_quanta_power universal_gnd *
  page263_i174
#CELL
  pure_quanta q_cap *
  page263_i175
#ISCELL
  pure_quanta_power universal_gnd *
  page263_i176
#CELL
  pure_quanta q_res *
  page263_i177
#CELL
  pure_quanta q_res *
  page263_i178
#CELL
  pure_quanta q_res *
  page263_i179
#ISCELL
  pure_quanta_power universal_gnd *
  page263_i18
#ISCELL
  pure_quanta_power universal_gnd *
  page263_i181
#ISCELL
  standard offpage *
  page263_i182
#ISCELL
  pure_quanta_power universal_power *
  page263_i183
#ISCELL
  standard offpage *
  page263_i184
#CELL
  pure_quanta q_cap *
  page263_i185
#ISCELL
  pure_quanta_power universal_gnd *
  page263_i186
#CELL
  pure_quanta q_cap *
  page263_i187
#ISCELL
  pure_quanta_power universal_gnd *
  page263_i188
#CELL
  pure_quanta q_res *
  page263_i189
#CELL
  pure_quanta q_res *
  page263_i19
#CELL
  pure_quanta q_res *
  page263_i190
#CELL
  pure_quanta q_res *
  page263_i191
#ISCELL
  pure_quanta_power universal_gnd *
  page263_i193
#CELL
  pure_quanta q_res *
  page263_i194
#ISCELL
  pure_quanta_power universal_power *
  page263_i195
#ISCELL
  standard offpage *
  page263_i196
#ISCELL
  standard offpage *
  page263_i197
#CELL
  pure_quanta q_cap *
  page263_i198
#ISCELL
  pure_quanta_power universal_gnd *
  page263_i199
#ISCELL
  pure_quanta_power universal_power *
  page263_i20
#CELL
  pure_quanta q_cap *
  page263_i200
#ISCELL
  pure_quanta_power universal_gnd *
  page263_i201
#CELL
  pure_quanta q_res *
  page263_i202
#CELL
  pure_quanta q_res *
  page263_i203
#ISCELL
  pure_quanta_power universal_gnd *
  page263_i205
#ISCELL
  standard offpage *
  page263_i206
#ISCELL
  pure_quanta_power universal_power *
  page263_i207
#ISCELL
  standard offpage *
  page263_i208
#CELL
  pure_quanta q_cap *
  page263_i209
#CELL
  pure_quanta q_res *
  page263_i21
#ISCELL
  pure_quanta_power universal_gnd *
  page263_i210
#CELL
  pure_quanta q_cap *
  page263_i211
#ISCELL
  pure_quanta_power universal_gnd *
  page263_i212
#CELL
  pure_quanta q_res *
  page263_i213
#CELL
  pure_quanta q_res *
  page263_i214
#CELL
  pure_quanta q_res *
  page263_i215
#CELL
  pure_quanta q_res *
  page263_i216
#ISCELL
  pure_quanta_power universal_gnd *
  page263_i217
#ISCELL
  pure_quanta_power universal_power *
  page263_i218
#ISCELL
  standard offpage *
  page263_i219
#CELL
  pure_quanta q_res *
  page263_i22
#ISCELL
  standard offpage *
  page263_i220
#CELL
  pure_quanta q_cap *
  page263_i221
#ISCELL
  pure_quanta_power universal_gnd *
  page263_i222
#CELL
  pure_quanta q_cap *
  page263_i223
#ISCELL
  pure_quanta_power universal_gnd *
  page263_i224
#CELL
  pure_quanta q_res *
  page263_i225
#CELL
  pure_quanta q_res *
  page263_i226
#CELL
  pure_quanta q_res *
  page263_i227
#ISCELL
  pure_quanta_power universal_gnd *
  page263_i229
#CELL
  pure_quanta q_res *
  page263_i230
#CELL
  pure_quanta q_res *
  page263_i231
#CELL
  pure_quanta q_cap *
  page263_i232
#ISCELL
  pure_quanta_power universal_power *
  page263_i233
#ISCELL
  standard offpage *
  page263_i234
#ISCELL
  standard offpage *
  page263_i235
#ISCELL
  pure_quanta_power universal_gnd *
  page263_i236
#CELL
  pure_quanta q_cap *
  page263_i237
#ISCELL
  pure_quanta_power universal_gnd *
  page263_i238
#CELL
  pure_quanta q_res *
  page263_i239
#ISCELL
  pure_quanta_power universal_gnd *
  page263_i241
#CELL
  pure_quanta q_res *
  page263_i242
#CELL
  pure_quanta q_res *
  page263_i243
#CELL
  pure_quanta q_res *
  page263_i244
#CELL
  pure_quanta q_res *
  page263_i245
#CELL
  pure_quanta q_res *
  page263_i246
#CELL
  pure_quanta q_res *
  page263_i247
#ISCELL
  pure_quanta_power universal_gnd *
  page263_i42
#CELL
  pure_quanta q_cap *
  page263_i43
#ISCELL
  pure_quanta_power universal_gnd *
  page263_i44
#CELL
  pure_quanta q_cap *
  page263_i45
#ISCELL
  pure_quanta_power universal_gnd *
  page263_i46
#ISCELL
  standard offpage *
  page263_i47
#ISCELL
  standard offpage *
  page263_i48
#ISCELL
  pure_quanta_power universal_gnd *
  page263_i49
#ISCELL
  pure_quanta_power universal_gnd *
  page263_i55
#ISCELL
  pure_quanta_power universal_gnd *
  page263_i56
#CELL
  pure_quanta q_res *
  page263_i57
#CELL
  pure_quanta q_res *
  page263_i58
#CELL
  pure_quanta q_res *
  page263_i59
#CELL
  pure_quanta q_res *
  page263_i60
#ISCELL
  pure_quanta_power universal_power *
  page263_i61
#ISCELL
  pure_quanta_power universal_power *
  page263_i66
#ISCELL
  pure_quanta_power universal_gnd *
  page263_i67
#CELL
  pure_quanta q_cap *
  page263_i68
#CELL
  pure_quanta q_inductor *
  page263_i69
#CELL
  pure_quanta q_cap *
  page263_i76
#CELL
  pure_quanta q_cap *
  page263_i77
#ISCELL
  standard offpage *
  page263_i78
#ISCELL
  standard offpage *
  page263_i79
#ISCELL
  pure_quanta_power universal_gnd *
  page263_i9
#ISCELL
  pure_quanta quanta_title_block_c *
  *
#ISCELL
  pure_quanta_power universal_gnd *
  page264_i16
#CELL
  pure_quanta q_res *
  page264_i17
#ISCELL
  standard offpage *
  page264_i18
#ISCELL
  standard offpage *
  page264_i2
#ISCELL
  pure_quanta_power universal_gnd *
  page264_i23
#CELL
  pure_quanta q_res *
  page264_i24
#CELL
  pure_quanta q_res *
  page264_i25
#CELL
  pure_quanta q_res *
  page264_i26
#CELL
  pure_quanta q_res *
  page264_i27
#ISCELL
  pure_quanta_power universal_gnd *
  page264_i28
#ISCELL
  pure_quanta_power universal_power *
  page264_i29
#ISCELL
  standard offpage *
  page264_i3
#CELL
  pure_quanta q_res *
  page264_i30
#ISCELL
  pure_quanta_power universal_power *
  page264_i31
#ISCELL
  pure_quanta_power universal_gnd *
  page264_i32
#CELL
  pure_quanta bss138dw7f *
  page264_i33
#ISCELL
  pure_quanta_power universal_gnd *
  page264_i34
#ISCELL
  pure_quanta_power universal_gnd *
  page264_i35
#CELL
  pure_quanta bss138dw7f *
  page264_i36
#ISCELL
  pure_quanta_power universal_gnd *
  page264_i37
#ISCELL
  pure_quanta_power universal_power *
  page264_i38
#CELL
  pure_quanta q_res *
  page264_i39
#ISCELL
  pure_quanta_power universal_power *
  page264_i40
#CELL
  pure_quanta q_res *
  page264_i41
#ISCELL
  pure_quanta_power p1v0_aux *
  page264_i42
#CELL
  pure_quanta q_res *
  page264_i43
#ISCELL
  standard offpage *
  page264_i44
#ISCELL
  pure_quanta_power p1v0_aux *
  page264_i45
#ISCELL
  standard offpage *
  page264_i46
#CELL
  pure_quanta q_cap *
  page264_i47
#ISCELL
  pure_quanta_power p1v0_aux *
  page264_i48
#CELL
  pure_quanta q_cap *
  page264_i49
#CELL
  pure_quanta q_res *
  page264_i5
#ISCELL
  pure_quanta_power universal_gnd *
  page264_i50
#CELL
  pure_quanta q_res *
  page264_i51
#ISCELL
  pure_quanta_power p1v0_aux *
  page264_i52
#ISCELL
  pure_quanta_power universal_power *
  page264_i53
#CELL
  pure_quanta q_res_4p_12 *
  page264_i54
#ISCELL
  pure_quanta_power universal_power *
  page264_i55
#ISCELL
  pure_quanta_power universal_power *
  page264_i56
#ISCELL
  pure_quanta_power universal_power *
  page264_i57
#CELL
  pure_quanta q_res_4p_12 *
  page264_i58
#CELL
  pure_quanta q_res *
  page264_i6
#ISCELL
  pure_quanta_power universal_gnd *
  page264_i7
#CELL
  pure_quanta sn74lvc1g11dckr *
  page264_i8
#ISCELL
  pure_quanta quanta_title_block_c *
  *
#ISCELL
  pure_quanta_power universal_gnd *
  page265_i1
#ISCELL
  pure_quanta_power universal_gnd *
  page265_i10
#ISCELL
  pure_quanta_power universal_gnd *
  page265_i11
#CELL
  pure_quanta tdr_3p *
  page265_i12
#CELL
  pure_quanta tdr_3p *
  page265_i13
#ISCELL
  pure_quanta_power universal_gnd *
  page265_i14
#CELL
  pure_quanta tdr_3p *
  page265_i15
#CELL
  pure_quanta tdr_3p *
  page265_i16
#ISCELL
  pure_quanta_power universal_gnd *
  page265_i17
#CELL
  pure_quanta tdr_3p *
  page265_i18
#ISCELL
  pure_quanta_power universal_gnd *
  page265_i19
#CELL
  pure_quanta tdr_3p *
  page265_i2
#CELL
  pure_quanta tdr_3p *
  page265_i20
#ISCELL
  pure_quanta_power universal_gnd *
  page265_i21
#CELL
  pure_quanta tdr_3p *
  page265_i22
#ISCELL
  pure_quanta_power universal_gnd *
  page265_i23
#ISCELL
  pure_quanta_power universal_gnd *
  page265_i24
#CELL
  pure_quanta tdr_3p *
  page265_i25
#ISCELL
  pure_quanta_power universal_gnd *
  page265_i26
#ISCELL
  pure_quanta_power universal_gnd *
  page265_i27
#ISCELL
  pure_quanta_power universal_gnd *
  page265_i28
#CELL
  pure_quanta tp_tdr_4p_fts *
  page265_i29
#ISCELL
  pure_quanta_power universal_gnd *
  page265_i3
#CELL
  pure_quanta tp_tdr_4p_fts *
  page265_i30
#CELL
  pure_quanta tp_tdr_4p_fts *
  page265_i31
#ISCELL
  pure_quanta_power universal_gnd *
  page265_i32
#ISCELL
  pure_quanta_power universal_gnd *
  page265_i33
#ISCELL
  pure_quanta_power universal_gnd *
  page265_i34
#CELL
  pure_quanta tp_tdr_4p_fts *
  page265_i35
#CELL
  pure_quanta tp_tdr_4p_fts *
  page265_i36
#CELL
  pure_quanta tp_tdr_4p_fts *
  page265_i37
#CELL
  pure_quanta tdr_3p *
  page265_i38
#ISCELL
  pure_quanta_power universal_gnd *
  page265_i39
#ISCELL
  pure_quanta_power universal_gnd *
  page265_i4
#CELL
  pure_quanta tdr_3p *
  page265_i40
#ISCELL
  pure_quanta_power universal_gnd *
  page265_i41
#CELL
  pure_quanta tdr_3p *
  page265_i42
#ISCELL
  pure_quanta_power universal_gnd *
  page265_i43
#CELL
  pure_quanta tdr_3p *
  page265_i44
#ISCELL
  pure_quanta_power universal_gnd *
  page265_i45
#ISCELL
  pure_quanta_power universal_gnd *
  page265_i46
#CELL
  pure_quanta tp_tdr_4p_fts *
  page265_i47
#CELL
  pure_quanta tp_tdr_4p_fts *
  page265_i48
#CELL
  pure_quanta tp_tdr_4p_fts *
  page265_i49
#CELL
  pure_quanta tdr_3p *
  page265_i5
#ISCELL
  pure_quanta_power universal_gnd *
  page265_i50
#ISCELL
  pure_quanta_power universal_gnd *
  page265_i51
#CELL
  pure_quanta tp_tdr_4p_fts *
  page265_i52
#CELL
  pure_quanta tp_tdr_4p_fts *
  page265_i53
#ISCELL
  pure_quanta_power universal_gnd *
  page265_i54
#ISCELL
  pure_quanta_power universal_gnd *
  page265_i55
#CELL
  pure_quanta tp_tdr_4p_fts *
  page265_i56
#ISCELL
  pure_quanta_power universal_gnd *
  page265_i57
#CELL
  pure_quanta tp_tdr_4p_fts *
  page265_i58
#ISCELL
  pure_quanta_power universal_gnd *
  page265_i59
#ISCELL
  pure_quanta_power universal_gnd *
  page265_i6
#CELL
  pure_quanta tp_tdr_4p_fts *
  page265_i60
#CELL
  pure_quanta tp_tdr_4p_fts *
  page265_i61
#CELL
  pure_quanta tp_tdr_4p_fts *
  page265_i62
#ISCELL
  pure_quanta_power universal_gnd *
  page265_i63
#ISCELL
  pure_quanta_power universal_gnd *
  page265_i64
#ISCELL
  pure_quanta_power universal_gnd *
  page265_i65
#CELL
  pure_quanta tp_tdr_4p_fts *
  page265_i66
#ISCELL
  pure_quanta_power universal_gnd *
  page265_i67
#CELL
  pure_quanta tp_tdr_4p_fts *
  page265_i68
#ISCELL
  pure_quanta_power universal_gnd *
  page265_i69
#ISCELL
  pure_quanta_power universal_gnd *
  page265_i7
#CELL
  pure_quanta tp_tdr_4p_fts *
  page265_i70
#ISCELL
  pure_quanta_power universal_gnd *
  page265_i71
#ISCELL
  pure_quanta_power universal_gnd *
  page265_i72
#CELL
  pure_quanta tp_tdr_4p_fts *
  page265_i73
#CELL
  pure_quanta tp_tdr_4p_fts *
  page265_i74
#ISCELL
  pure_quanta_power universal_gnd *
  page265_i75
#CELL
  pure_quanta tp_tdr_4p_fts *
  page265_i76
#ISCELL
  pure_quanta_power universal_gnd *
  page265_i77
#CELL
  pure_quanta tp_tdr_4p_fts *
  page265_i78
#CELL
  pure_quanta tp_tdr_4p_fts *
  page265_i79
#CELL
  pure_quanta tdr_3p *
  page265_i8
#ISCELL
  pure_quanta_power universal_gnd *
  page265_i80
#ISCELL
  pure_quanta_power universal_gnd *
  page265_i81
#CELL
  pure_quanta tp_tdr_4p_fts *
  page265_i82
#ISCELL
  pure_quanta_power universal_gnd *
  page265_i83
#CELL
  pure_quanta tp_tdr_4p_fts *
  page265_i84
#ISCELL
  pure_quanta_power universal_gnd *
  page265_i85
#ISCELL
  pure_quanta_power universal_gnd *
  page265_i86
#CELL
  pure_quanta tp_tdr_4p_fts *
  page265_i87
#ISCELL
  pure_quanta_power universal_gnd *
  page265_i88
#CELL
  pure_quanta tp_tdr_4p_fts *
  page265_i89
#CELL
  pure_quanta tdr_3p *
  page265_i9
#CELL
  pure_quanta tp_tdr_4p_fts *
  page265_i90
#ISCELL
  pure_quanta_power universal_gnd *
  page265_i91
#CELL
  pure_quanta tp_tdr_4p_fts *
  page265_i92
#ISCELL
  pure_quanta_power universal_gnd *
  page265_i93
#CELL
  pure_quanta tp_tdr_4p_fts *
  page265_i94
#ISCELL
  pure_quanta_power universal_gnd *
  page265_i95
#CELL
  pure_quanta tp_tdr_4p_fts *
  page265_i96
#ISCELL
  pure_quanta quanta_title_block_c *
  *
#ISCELL
  pure_quanta_power universal_gnd *
  page266_i1
#CELL
  pure_quanta tp_tdr_4p_fts *
  page266_i10
#ISCELL
  pure_quanta_power universal_gnd *
  page266_i11
#CELL
  pure_quanta tp_tdr_4p_fts *
  page266_i12
#CELL
  pure_quanta tp_tdr_4p_fts *
  page266_i13
#ISCELL
  pure_quanta_power universal_gnd *
  page266_i14
#CELL
  pure_quanta tp_tdr_4p_fts *
  page266_i15
#CELL
  pure_quanta tp_tdr_4p_fts *
  page266_i16
#CELL
  pure_quanta tp_tdr_4p_fts *
  page266_i17
#ISCELL
  pure_quanta_power universal_gnd *
  page266_i18
#ISCELL
  pure_quanta_power universal_gnd *
  page266_i19
#CELL
  pure_quanta tp_tdr_4p_fts *
  page266_i2
#ISCELL
  pure_quanta_power universal_gnd *
  page266_i20
#ISCELL
  pure_quanta_power universal_gnd *
  page266_i3
#CELL
  pure_quanta tp_tdr_4p_fts *
  page266_i37
#CELL
  pure_quanta tp_tdr_4p_fts *
  page266_i38
#ISCELL
  pure_quanta_power universal_gnd *
  page266_i39
#CELL
  pure_quanta tp_tdr_4p_fts *
  page266_i4
#ISCELL
  pure_quanta_power universal_gnd *
  page266_i40
#ISCELL
  pure_quanta_power universal_gnd *
  page266_i5
#ISCELL
  pure_quanta_power universal_gnd *
  page266_i6
#CELL
  pure_quanta tp_tdr_4p_fts *
  page266_i7
#CELL
  pure_quanta tp_tdr_4p_fts *
  page266_i8
#ISCELL
  pure_quanta_power universal_gnd *
  page266_i9
#ISCELL
  mstr_misc dns *
  *
#ISCELL
  pure_quanta quanta_title_block_c *
  *
#ISCELL
  pure_quanta_power universal_gnd *
  page267_i17
#ISCELL
  pure_quanta_power universal_gnd *
  page267_i21
#CELL
  pure_quanta q_res *
  page267_i22
#ISCELL
  standard offpage *
  page267_i23
#CELL
  pure_quanta q_res *
  page267_i24
#ISCELL
  standard offpage *
  page267_i25
#ISCELL
  standard offpage *
  page267_i26
#CELL
  pure_quanta q_cap *
  page267_i27
#ISCELL
  pure_quanta_power universal_gnd *
  page267_i29
#CELL
  pure_quanta q_cap *
  page267_i30
#ISCELL
  standard offpage *
  page267_i31
#ISCELL
  standard offpage *
  page267_i32
#CELL
  pure_quanta q_res *
  page267_i34
#ISCELL
  pure_quanta_power universal_power *
  page267_i35
#CELL
  pure_quanta q_res *
  page267_i36
#CELL
  pure_quanta q_res *
  page267_i37
#ISCELL
  pure_quanta_power universal_gnd *
  page267_i38
#CELL
  pure_quanta q_res *
  page267_i39
#ISCELL
  pure_quanta_power universal_power *
  page267_i41
#ISCELL
  pure_quanta_power gnd *
  page267_i42
#ISCELL
  pure_quanta_power universal_power *
  page267_i45
#CELL
  pure_quanta q_cap *
  page267_i46
#CELL
  pure_quanta q_res *
  page267_i47
#CELL
  pure_quanta q_res *
  page267_i48
#ISCELL
  pure_quanta_power universal_gnd *
  page267_i49
#CELL
  pure_quanta q_cap *
  page267_i50
#CELL
  pure_quanta q_res *
  page267_i51
#CELL
  pure_quanta q_res *
  page267_i52
#CELL
  pure_quanta q_res *
  page267_i53
#CELL
  pure_quanta q_res *
  page267_i54
#ISCELL
  pure_quanta_power universal_power *
  page267_i55
#CELL
  pure_quanta q_res *
  page267_i56
#ISCELL
  pure_quanta_power universal_gnd *
  page267_i57
#CELL
  pure_quanta mp5990gma1111z *
  page267_i58
#CELL
  pure_quanta q_cap *
  page267_i59
#ISCELL
  standard offpage *
  page267_i60
#ISCELL
  standard offpage *
  page267_i61
#ISCELL
  standard offpage *
  page267_i62
#CELL
  pure_quanta q_res *
  page267_i63
#ISCELL
  pure_quanta_power universal_power *
  page267_i64
#CELL
  pure_quanta q_res *
  page267_i65
#ISCELL
  pure_quanta_power universal_gnd *
  page267_i66
#ISCELL
  standard offpage *
  page267_i67
#ISCELL
  standard offpage *
  page267_i68
#ISCELL
  pure_quanta_power universal_gnd *
  page267_i69
#CELL
  pure_quanta q_res *
  page267_i70
#CELL
  pure_quanta q_res *
  page267_i71
#CELL
  pure_quanta q_cap *
  page267_i72
#ISCELL
  standard offpage *
  page267_i73
#ISCELL
  pure_quanta_power universal_gnd *
  page267_i74
#CELL
  pure_quanta q_cap *
  page267_i75
#ISCELL
  standard offpage *
  page267_i76
#ISCELL
  pure_quanta_power universal_gnd *
  page267_i77
#CELL
  pure_quanta q_cap *
  page267_i78
#CELL
  pure_quanta q_res *
  page267_i79
#CELL
  pure_quanta q_res *
  page267_i80
#CELL
  pure_quanta q_res *
  page267_i81
#ISCELL
  standard offpage *
  page267_i82
#ISCELL
  pure_quanta_power universal_gnd *
  page267_i83
#CELL
  pure_quanta q_cap *
  page267_i84
#CELL
  pure_quanta q_res *
  page267_i85
#CELL
  pure_quanta q_res *
  page267_i86
#ISCELL
  pure_quanta_power universal_gnd *
  page267_i87
#ISCELL
  pure_quanta_power gnd *
  page267_i88
#CELL
  pure_quanta ss15p3sm386a *
  page267_i89
#ISCELL
  pure_quanta_power universal_power *
  page267_i90
#CELL
  pure_quanta q_res *
  page267_i91
#ISCELL
  pure_quanta_power universal_power *
  page267_i92
#ISCELL
  standard offpage *
  page267_i94
#ISCELL
  standard offpage *
  page267_i95
#ISCELL
  standard offpage *
  page267_i96
#CELL
  pure_quanta q_res *
  page267_i99
#ISCELL
  mstr_misc dns *
  *
#ISCELL
  pure_quanta quanta_title_block_c *
  *
#ISCELL
  pure_quanta_power universal_gnd *
  page301_i1
#ISCELL
  standard offpage *
  page301_i10
#CELL
  pure_quanta q_res *
  page301_i11
#CELL
  pure_quanta q_cap *
  page301_i12
#CELL
  pure_quanta q_res *
  page301_i13
#ISCELL
  standard offpage *
  page301_i14
#CELL
  pure_quanta q_res *
  page301_i15
#CELL
  pure_quanta mp5991gluz *
  page301_i16
#CELL
  pure_quanta q_res *
  page301_i17
#ISCELL
  pure_quanta_power universal_power *
  page301_i18
#ISCELL
  pure_quanta_power universal_gnd *
  page301_i19
#CELL
  pure_quanta q_cap *
  page301_i2
#CELL
  pure_quanta q_cap *
  page301_i20
#CELL
  pure_quanta q_res *
  page301_i21
#ISCELL
  pure_quanta_power universal_power *
  page301_i22
#ISCELL
  pure_quanta_power universal_gnd *
  page301_i23
#CELL
  pure_quanta q_cap *
  page301_i24
#ISCELL
  standard offpage *
  page301_i25
#ISCELL
  standard offpage *
  page301_i26
#ISCELL
  pure_quanta_power universal_gnd *
  page301_i27
#ISCELL
  standard offpage *
  page301_i28
#CELL
  pure_quanta q_res *
  page301_i29
#ISCELL
  pure_quanta_power universal_gnd *
  page301_i3
#CELL
  pure_quanta q_cap *
  page301_i30
#CELL
  pure_quanta q_res *
  page301_i31
#ISCELL
  standard offpage *
  page301_i32
#CELL
  pure_quanta q_res *
  page301_i33
#CELL
  pure_quanta q_res *
  page301_i34
#CELL
  pure_quanta mp5991gluz *
  page301_i35
#ISCELL
  pure_quanta_power universal_power *
  page301_i36
#ISCELL
  pure_quanta_power universal_gnd *
  page301_i37
#CELL
  pure_quanta q_cap *
  page301_i38
#CELL
  pure_quanta q_res *
  page301_i39
#CELL
  pure_quanta q_cap *
  page301_i4
#CELL
  pure_quanta q_res *
  page301_i40
#ISCELL
  pure_quanta_power universal_power *
  page301_i41
#ISCELL
  standard offpage *
  page301_i42
#ISCELL
  standard offpage *
  page301_i43
#ISCELL
  standard offpage *
  page301_i44
#ISCELL
  standard offpage *
  page301_i45
#ISCELL
  standard offpage *
  page301_i46
#CELL
  pure_quanta q_cap *
  page301_i47
#ISCELL
  pure_quanta_power universal_gnd *
  page301_i48
#CELL
  pure_quanta q_res *
  page301_i49
#CELL
  pure_quanta q_res *
  page301_i5
#CELL
  pure_quanta q_res *
  page301_i50
#ISCELL
  pure_quanta_power universal_power *
  page301_i51
#ISCELL
  standard offpage *
  page301_i52
#ISCELL
  standard offpage *
  page301_i53
#ISCELL
  standard offpage *
  page301_i54
#ISCELL
  standard offpage *
  page301_i55
#ISCELL
  standard offpage *
  page301_i56
#ISCELL
  pure_quanta_power universal_power *
  page301_i6
#ISCELL
  standard offpage *
  page301_i7
#ISCELL
  pure_quanta_power universal_gnd *
  page301_i8
#ISCELL
  standard offpage *
  page301_i9
#ISCELL
  mstr_misc dns *
  *
#ISCELL
  pure_quanta quanta_title_block_c *
  *
#ISCELL
  pure_quanta_power universal_gnd *
  page325_i1
#ISCELL
  standard offpage *
  page325_i10
#CELL
  pure_quanta q_res *
  page325_i11
#CELL
  pure_quanta q_cap *
  page325_i12
#CELL
  pure_quanta q_res *
  page325_i13
#CELL
  pure_quanta q_res *
  page325_i14
#ISCELL
  standard offpage *
  page325_i15
#CELL
  pure_quanta q_res *
  page325_i16
#CELL
  pure_quanta mp5991gluz *
  page325_i17
#ISCELL
  pure_quanta_power universal_power *
  page325_i18
#ISCELL
  pure_quanta_power universal_gnd *
  page325_i19
#CELL
  pure_quanta q_cap *
  page325_i2
#CELL
  pure_quanta q_cap *
  page325_i20
#CELL
  pure_quanta q_res *
  page325_i21
#ISCELL
  standard offpage *
  page325_i22
#ISCELL
  pure_quanta_power universal_gnd *
  page325_i23
#CELL
  pure_quanta q_cap *
  page325_i24
#ISCELL
  pure_quanta_power universal_gnd *
  page325_i25
#ISCELL
  standard offpage *
  page325_i26
#ISCELL
  standard offpage *
  page325_i27
#CELL
  pure_quanta q_res *
  page325_i28
#ISCELL
  pure_quanta_power universal_power *
  page325_i29
#ISCELL
  pure_quanta_power universal_gnd *
  page325_i3
#CELL
  pure_quanta q_cap *
  page325_i30
#CELL
  pure_quanta q_res *
  page325_i31
#ISCELL
  standard offpage *
  page325_i32
#CELL
  pure_quanta q_res *
  page325_i33
#CELL
  pure_quanta q_res *
  page325_i34
#CELL
  pure_quanta mp5991gluz *
  page325_i35
#ISCELL
  pure_quanta_power universal_power *
  page325_i36
#ISCELL
  pure_quanta_power universal_gnd *
  page325_i37
#CELL
  pure_quanta q_cap *
  page325_i38
#CELL
  pure_quanta q_res *
  page325_i39
#CELL
  pure_quanta q_cap *
  page325_i4
#CELL
  pure_quanta q_res *
  page325_i40
#ISCELL
  pure_quanta_power universal_power *
  page325_i41
#ISCELL
  standard offpage *
  page325_i42
#ISCELL
  standard offpage *
  page325_i43
#ISCELL
  standard offpage *
  page325_i44
#ISCELL
  standard offpage *
  page325_i45
#ISCELL
  standard offpage *
  page325_i46
#CELL
  pure_quanta q_cap *
  page325_i47
#ISCELL
  pure_quanta_power universal_gnd *
  page325_i48
#CELL
  pure_quanta q_res *
  page325_i49
#ISCELL
  standard offpage *
  page325_i5
#CELL
  pure_quanta q_res *
  page325_i50
#ISCELL
  pure_quanta_power universal_power *
  page325_i51
#ISCELL
  standard offpage *
  page325_i52
#ISCELL
  standard offpage *
  page325_i53
#ISCELL
  standard offpage *
  page325_i54
#ISCELL
  standard offpage *
  page325_i55
#ISCELL
  standard offpage *
  page325_i56
#CELL
  pure_quanta q_res *
  page325_i6
#ISCELL
  pure_quanta_power universal_power *
  page325_i7
#ISCELL
  pure_quanta_power universal_gnd *
  page325_i8
#ISCELL
  standard offpage *
  page325_i9
#ISCELL
  pure_quanta quanta_title_block_c *
  *
#ISCELL
  mstr_misc dns *
  *
#ISCELL
  pure_quanta quanta_title_block_c *
  *
#ISCELL
  pure_quanta_power bom_note *
  *
#CELL
  pure_quanta q_res *
  page302_i15
#CELL
  pure_quanta q_res *
  page302_i16
#CELL
  pure_quanta q_res *
  page302_i17
#CELL
  pure_quanta q_res *
  page302_i18
#ISCELL
  standard offpage *
  page302_i19
#ISCELL
  standard offpage *
  page302_i20
#ISCELL
  standard offpage *
  page302_i21
#ISCELL
  standard offpage *
  page302_i22
#ISCELL
  standard offpage *
  page302_i23
#ISCELL
  standard offpage *
  page302_i24
#ISCELL
  standard offpage *
  page302_i25
#ISCELL
  standard offpage *
  page302_i26
#CELL
  pure_quanta q_res *
  page302_i27
#CELL
  pure_quanta q_res *
  page302_i28
#CELL
  pure_quanta mosfet_nch_1d3s *
  page302_i29
#ISCELL
  standard offpage *
  page302_i30
#ISCELL
  standard offpage *
  page302_i31
#ISCELL
  standard offpage *
  page302_i32
#ISCELL
  standard offpage *
  page302_i33
#ISCELL
  standard offpage *
  page302_i34
#ISCELL
  standard offpage *
  page302_i35
#ISCELL
  standard offpage *
  page302_i36
#ISCELL
  standard offpage *
  page302_i37
#ISCELL
  standard offpage *
  page302_i38
#ISCELL
  standard offpage *
  page302_i39
#ISCELL
  standard offpage *
  page302_i40
#ISCELL
  standard offpage *
  page302_i41
#ISCELL
  standard offpage *
  page302_i42
#ISCELL
  standard offpage *
  page302_i43
#ISCELL
  standard offpage *
  page302_i44
#CELL
  pure_quanta q_res *
  page302_i45
#CELL
  pure_quanta mosfet_nch_1d3s *
  page302_i46
#CELL
  pure_quanta q_res *
  page302_i47
#ISCELL
  standard offpage *
  page302_i48
#ISCELL
  standard offpage *
  page302_i49
#CELL
  pure_quanta q_res *
  page302_i5
#ISCELL
  standard offpage *
  page302_i50
#ISCELL
  standard offpage *
  page302_i51
#CELL
  pure_quanta q_sp_res4p *
  page302_i52
#CELL
  pure_quanta q_sp_res4p *
  page302_i53
#CELL
  pure_quanta q_sp_res4p *
  page302_i54
#CELL
  pure_quanta q_sp_res4p *
  page302_i55
#ISCELL
  pure_quanta_power universal_power *
  page302_i56
#ISCELL
  standard offpage *
  page302_i57
#ISCELL
  pure_quanta_power gnd *
  page302_i59
#CELL
  pure_quanta q_res *
  page302_i6
#CELL
  pure_quanta q_res *
  page302_i60
#CELL
  pure_quanta mosfet_nch_1d3s *
  page302_i61
#CELL
  pure_quanta q_res *
  page302_i62
#CELL
  pure_quanta q_cap *
  page302_i63
#CELL
  pure_quanta mosfet_nch_1d3s *
  page302_i64
#ISCELL
  standard offpage *
  page302_i65
#ISCELL
  standard offpage *
  page302_i66
#ISCELL
  standard offpage *
  page302_i67
#ISCELL
  standard offpage *
  page302_i68
#ISCELL
  standard offpage *
  page302_i69
#CELL
  pure_quanta q_res *
  page302_i7
#CELL
  pure_quanta q_cap *
  page302_i70
#CELL
  pure_quanta q_res *
  page302_i71
#CELL
  pure_quanta ss15p3sm386a *
  page302_i72
#ISCELL
  pure_quanta_power universal_power *
  page302_i73
#CELL
  pure_quanta q_res *
  page302_i74
#CELL
  pure_quanta mosfet_nch_1d3s *
  page302_i75
#ISCELL
  standard offpage *
  page302_i76
#ISCELL
  pure_quanta_power universal_power *
  page302_i77
#ISCELL
  pure_quanta_power universal_power *
  page302_i78
#CELL
  pure_quanta mosfet_nch_1d3s *
  page302_i79
#CELL
  pure_quanta q_res *
  page302_i8
#CELL
  pure_quanta mosfet_nch_1d3s *
  page302_i80
#CELL
  pure_quanta q_sp_res4p *
  page302_i81
#CELL
  pure_quanta q_res *
  page302_i82
#CELL
  pure_quanta q_res *
  page302_i83
#CELL
  pure_quanta q_res *
  page302_i84
#CELL
  pure_quanta q_res *
  page302_i85
#CELL
  pure_quanta q_res *
  page302_i86
#CELL
  pure_quanta q_res *
  page302_i87
#CELL
  pure_quanta q_res *
  page302_i88
#CELL
  pure_quanta q_res *
  page302_i89
#CELL
  pure_quanta q_res *
  page302_i90
#CELL
  pure_quanta q_res *
  page302_i91
#ISCELL
  mstr_misc dns *
  *
#ISCELL
  pure_quanta quanta_title_block_c *
  *
#CELL
  pure_quanta metr3904g *
  page371_i1
#CELL
  pure_quanta q_res *
  page371_i10
#ISCELL
  pure_quanta_power universal_power *
  page371_i100
#CELL
  pure_quanta lm4040aim3x25nopb *
  page371_i101
#ISCELL
  standard offpage *
  page371_i102
#CELL
  pure_quanta q_res *
  page371_i103
#CELL
  pure_quanta ap331awg7 *
  page371_i104
#ISCELL
  standard offpage *
  page371_i105
#ISCELL
  pure_quanta_power gnd *
  page371_i106
#CELL
  pure_quanta q_cap *
  page371_i107
#CELL
  pure_quanta q_res *
  page371_i108
#ISCELL
  pure_quanta_power universal_power *
  page371_i109
#ISCELL
  standard offpage *
  page371_i11
#CELL
  pure_quanta q_cap *
  page371_i110
#ISCELL
  pure_quanta_power universal_power *
  page371_i112
#CELL
  pure_quanta q_res *
  page371_i113
#ISCELL
  standard offpage *
  page371_i12
#ISCELL
  standard offpage *
  page371_i13
#ISCELL
  standard offpage *
  page371_i15
#ISCELL
  standard offpage *
  page371_i16
#ISCELL
  standard offpage *
  page371_i17
#ISCELL
  standard offpage *
  page371_i18
#CELL
  pure_quanta q_res *
  page371_i2
#ISCELL
  standard offpage *
  page371_i20
#ISCELL
  standard offpage *
  page371_i21
#ISCELL
  standard offpage *
  page371_i22
#ISCELL
  pure_quanta_power universal_gnd *
  page371_i24
#ISCELL
  pure_quanta_power universal_power *
  page371_i25
#ISCELL
  pure_quanta_power universal_gnd *
  page371_i26
#ISCELL
  pure_quanta_power universal_gnd *
  page371_i27
#CELL
  pure_quanta q_cap *
  page371_i28
#ISCELL
  pure_quanta_power universal_power *
  page371_i29
#CELL
  pure_quanta q_res *
  page371_i3
#ISCELL
  standard offpage *
  page371_i30
#ISCELL
  standard offpage *
  page371_i31
#ISCELL
  standard offpage *
  page371_i32
#ISCELL
  standard offpage *
  page371_i33
#ISCELL
  pure_quanta_power universal_power *
  page371_i34
#ISCELL
  standard offpage *
  page371_i35
#ISCELL
  standard offpage *
  page371_i36
#ISCELL
  standard offpage *
  page371_i37
#ISCELL
  standard offpage *
  page371_i38
#CELL
  pure_quanta q_res *
  page371_i39
#CELL
  pure_quanta q_cap *
  page371_i4
#CELL
  pure_quanta q_res *
  page371_i40
#CELL
  pure_quanta sconn21_9193031121lf *
  page371_i42
#ISCELL
  standard offpage *
  page371_i44
#CELL
  pure_quanta q_res *
  page371_i45
#CELL
  pure_quanta q_res *
  page371_i46
#ISCELL
  pure_quanta_power universal_power *
  page371_i47
#ISCELL
  standard offpage *
  page371_i48
#ISCELL
  standard offpage *
  page371_i49
#ISCELL
  pure_quanta_power universal_gnd *
  page371_i5
#CELL
  pure_quanta lt6700cs61trpbf *
  page371_i50
#CELL
  pure_quanta q_res *
  page371_i55
#CELL
  pure_quanta q_res *
  page371_i56
#CELL
  pure_quanta q_res *
  page371_i57
#CELL
  pure_quanta q_res *
  page371_i58
#ISCELL
  standard offpage *
  page371_i59
#CELL
  pure_quanta q_cap *
  page371_i6
#ISCELL
  pure_quanta_power gnd *
  page371_i60
#ISCELL
  pure_quanta_power gnd *
  page371_i61
#CELL
  pure_quanta q_res *
  page371_i63
#ISCELL
  pure_quanta_power universal_power *
  page371_i64
#ISCELL
  standard offpage *
  page371_i65
#CELL
  pure_quanta q_res *
  page371_i66
#ISCELL
  pure_quanta_power gnd *
  page371_i67
#CELL
  pure_quanta mosfet_nch_gds_esd_protected *
  page371_i68
#ISCELL
  pure_quanta_power gnd *
  page371_i69
#ISCELL
  pure_quanta_power universal_power *
  page371_i7
#CELL
  pure_quanta q_res *
  page371_i70
#ISCELL
  pure_quanta_power universal_power *
  page371_i71
#CELL
  pure_quanta q_res *
  page371_i72
#CELL
  pure_quanta q_res *
  page371_i73
#CELL
  pure_quanta q_res *
  page371_i74
#ISCELL
  standard offpage *
  page371_i75
#CELL
  pure_quanta q_res *
  page371_i76
#ISCELL
  pure_quanta_power universal_power *
  page371_i77
#ISCELL
  pure_quanta_power universal_power *
  page371_i78
#CELL
  pure_quanta q_res *
  page371_i79
#CELL
  pure_quanta nct7718w *
  page371_i8
#ISCELL
  pure_quanta_power universal_gnd *
  page371_i80
#CELL
  pure_quanta q_res *
  page371_i81
#CELL
  pure_quanta q_res *
  page371_i82
#ISCELL
  pure_quanta_power universal_gnd *
  page371_i83
#CELL
  pure_quanta q_res *
  page371_i84
#ISCELL
  pure_quanta_power universal_power *
  page371_i85
#ISCELL
  pure_quanta_power universal_gnd *
  page371_i86
#CELL
  pure_quanta q_cap *
  page371_i87
#ISCELL
  pure_quanta_power universal_gnd *
  page371_i88
#CELL
  pure_quanta q_cap *
  page371_i89
#ISCELL
  pure_quanta_power universal_gnd *
  page371_i9
#ISCELL
  pure_quanta_power universal_gnd *
  page371_i90
#ISCELL
  pure_quanta_power universal_power *
  page371_i93
#ISCELL
  pure_quanta_power universal_gnd *
  page371_i94
#CELL
  pure_quanta q_cap *
  page371_i95
#CELL
  pure_quanta q_res *
  page371_i96
#CELL
  pure_quanta q_res *
  page371_i98
#ISCELL
  standard offpage *
  page371_i99
#ISCELL
  mstr_misc dns *
  *
#ISCELL
  pure_quanta quanta_title_block_c *
  *
#CELL
  pure_quanta zener_ac *
  page372_i1
#CELL
  pure_quanta q_res *
  page372_i10
#ISCELL
  pure_quanta_power gnd *
  page372_i100
#ISCELL
  standard offpage *
  page372_i101
#ISCELL
  standard offpage *
  page372_i102
#CELL
  pure_quanta conn3_210hp1030br1 *
  page372_i103
#CELL
  pure_quanta q_res *
  page372_i104
#CELL
  pure_quanta mosfet_nch_gds_esd_protected *
  page372_i11
#ISCELL
  pure_quanta_power gnd *
  page372_i12
#CELL
  pure_quanta q_res *
  page372_i13
#ISCELL
  pure_quanta_power gnd *
  page372_i14
#CELL
  pure_quanta q_res *
  page372_i16
#ISCELL
  pure_quanta_power gnd *
  page372_i17
#CELL
  pure_quanta conn3_210hp1030br1 *
  page372_i18
#CELL
  pure_quanta q_res *
  page372_i19
#ISCELL
  standard offpage *
  page372_i2
#ISCELL
  standard offpage *
  page372_i20
#CELL
  pure_quanta q_cap *
  page372_i22
#ISCELL
  standard offpage *
  page372_i23
#ISCELL
  pure_quanta_power universal_gnd *
  page372_i24
#ISCELL
  pure_quanta_power gnd *
  page372_i25
#ISCELL
  pure_quanta_power universal_gnd *
  page372_i26
#CELL
  pure_quanta q_res *
  page372_i27
#ISCELL
  pure_quanta_power universal_gnd *
  page372_i28
#CELL
  pure_quanta q_res *
  page372_i29
#CELL
  pure_quanta zener_ac *
  page372_i3
#CELL
  pure_quanta q_res *
  page372_i30
#ISCELL
  pure_quanta_power universal_power *
  page372_i31
#ISCELL
  pure_quanta_power universal_gnd *
  page372_i32
#CELL
  pure_quanta q_res *
  page372_i33
#CELL
  pure_quanta q_res *
  page372_i35
#ISCELL
  pure_quanta_power universal_power *
  page372_i36
#ISCELL
  pure_quanta_power universal_gnd *
  page372_i39
#ISCELL
  pure_quanta_power gnd *
  page372_i4
#ISCELL
  standard offpage *
  page372_i40
#ISCELL
  pure_quanta_power universal_gnd *
  page372_i41
#CELL
  pure_quanta mosfet_n *
  page372_i42
#CELL
  pure_quanta q_res *
  page372_i43
#ISCELL
  pure_quanta_power universal_power *
  page372_i44
#CELL
  pure_quanta q_res *
  page372_i45
#CELL
  pure_quanta q_res *
  page372_i46
#ISCELL
  pure_quanta_power universal_power *
  page372_i47
#ISCELL
  standard offpage *
  page372_i48
#CELL
  pure_quanta lt6700cs61trpbf *
  page372_i49
#ISCELL
  pure_quanta_power universal_power *
  page372_i5
#ISCELL
  pure_quanta_power universal_gnd *
  page372_i50
#CELL
  pure_quanta lm4040aim3x25nopb *
  page372_i51
#CELL
  pure_quanta q_res *
  page372_i52
#ISCELL
  pure_quanta_power universal_power *
  page372_i53
#ISCELL
  pure_quanta_power universal_gnd *
  page372_i54
#CELL
  pure_quanta q_res *
  page372_i55
#CELL
  pure_quanta q_res *
  page372_i56
#ISCELL
  pure_quanta_power universal_power *
  page372_i57
#ISCELL
  pure_quanta_power universal_gnd *
  page372_i58
#CELL
  pure_quanta q_cap *
  page372_i59
#CELL
  pure_quanta q_fuse *
  page372_i6
#ISCELL
  pure_quanta_power universal_gnd *
  page372_i60
#CELL
  pure_quanta q_cap *
  page372_i61
#ISCELL
  pure_quanta_power universal_gnd *
  page372_i62
#CELL
  pure_quanta q_res *
  page372_i63
#ISCELL
  pure_quanta_power universal_power *
  page372_i64
#ISCELL
  pure_quanta_power universal_gnd *
  page372_i65
#CELL
  pure_quanta q_cap *
  page372_i66
#CELL
  pure_quanta q_res *
  page372_i67
#ISCELL
  standard offpage *
  page372_i68
#CELL
  pure_quanta q_res *
  page372_i69
#ISCELL
  pure_quanta_power universal_gnd *
  page372_i7
#ISCELL
  pure_quanta_power universal_power *
  page372_i70
#CELL
  pure_quanta ap331awg7 *
  page372_i71
#CELL
  pure_quanta q_res *
  page372_i72
#ISCELL
  pure_quanta_power universal_power *
  page372_i73
#ISCELL
  pure_quanta_power universal_gnd *
  page372_i74
#CELL
  pure_quanta q_res *
  page372_i75
#CELL
  pure_quanta q_res *
  page372_i76
#ISCELL
  pure_quanta_power universal_power *
  page372_i77
#ISCELL
  pure_quanta_power universal_gnd *
  page372_i78
#CELL
  pure_quanta q_cap *
  page372_i79
#ISCELL
  standard offpage *
  page372_i8
#CELL
  pure_quanta ap331awg7 *
  page372_i80
#CELL
  pure_quanta q_res *
  page372_i81
#ISCELL
  pure_quanta_power universal_gnd *
  page372_i82
#ISCELL
  pure_quanta_power universal_power *
  page372_i83
#CELL
  pure_quanta q_cap *
  page372_i84
#CELL
  pure_quanta q_res *
  page372_i85
#ISCELL
  standard offpage *
  page372_i86
#ISCELL
  pure_quanta_power universal_power *
  page372_i88
#ISCELL
  pure_quanta_power universal_gnd *
  page372_i89
#CELL
  pure_quanta q_cap *
  page372_i9
#ISCELL
  pure_quanta_power universal_gnd *
  page372_i90
#ISCELL
  pure_quanta_power universal_gnd *
  page372_i91
#CELL
  pure_quanta q_cap *
  page372_i92
#CELL
  pure_quanta lm4040aim3x25nopb *
  page372_i93
#ISCELL
  pure_quanta_power universal_gnd *
  page372_i95
#CELL
  pure_quanta q_cap *
  page372_i96
#CELL
  pure_quanta q_res *
  page372_i97
#ISCELL
  pure_quanta_power universal_power *
  page372_i98
#CELL
  pure_quanta q_cap *
  page372_i99
#ISCELL
  mstr_misc dns *
  *
#ISCELL
  pure_quanta quanta_title_block_c *
  *
#ISCELL
  pure_quanta_power universal_power *
  page315_i1
#CELL
  pure_quanta q_cap *
  page315_i10
#ISCELL
  pure_quanta_power gnd *
  page315_i11
#CELL
  pure_quanta q_res *
  page315_i12
#CELL
  pure_quanta q_cap *
  page315_i13
#ISCELL
  pure_quanta_power gnd *
  page315_i14
#CELL
  pure_quanta q_res *
  page315_i15
#ISCELL
  pure_quanta_power gnd *
  page315_i17
#CELL
  pure_quanta mpq8626gdz *
  page315_i18
#CELL
  pure_quanta q_cap *
  page315_i19
#CELL
  pure_quanta q_res *
  page315_i2
#ISCELL
  pure_quanta_power gnd *
  page315_i20
#CELL
  pure_quanta q_cap *
  page315_i21
#ISCELL
  pure_quanta_power gnd *
  page315_i22
#CELL
  pure_quanta q_res *
  page315_i23
#ISCELL
  pure_quanta_power gnd *
  page315_i24
#CELL
  pure_quanta q_inductor *
  page315_i25
#CELL
  pure_quanta q_cap *
  page315_i26
#CELL
  pure_quanta q_cap *
  page315_i27
#CELL
  pure_quanta q_res *
  page315_i28
#CELL
  pure_quanta q_cap *
  page315_i29
#ISCELL
  pure_quanta_power gnd *
  page315_i3
#CELL
  pure_quanta q_cap *
  page315_i30
#CELL
  pure_quanta q_res *
  page315_i32
#ISCELL
  pure_quanta_power universal_power *
  page315_i33
#CELL
  pure_quanta q_cap *
  page315_i34
#ISCELL
  pure_quanta_power gnd *
  page315_i35
#CELL
  pure_quanta q_cap *
  page315_i36
#CELL
  pure_quanta q_cap *
  page315_i37
#ISCELL
  pure_quanta_power universal_power *
  page315_i38
#ISCELL
  standard offpage *
  page315_i39
#ISCELL
  pure_quanta_power gnd *
  page315_i4
#CELL
  pure_quanta q_res *
  page315_i40
#CELL
  pure_quanta q_cap *
  page315_i41
#ISCELL
  pure_quanta_power gnd *
  page315_i42
#ISCELL
  standard offpage *
  page315_i43
#CELL
  pure_quanta q_res *
  page315_i44
#CELL
  pure_quanta q_res *
  page315_i45
#CELL
  pure_quanta q_cap *
  page315_i5
#ISCELL
  pure_quanta_power universal_power *
  page315_i6
#CELL
  pure_quanta q_inductor *
  page315_i7
#CELL
  pure_quanta q_cap *
  page315_i8
#ISCELL
  pure_quanta_power gnd *
  page315_i9
#ISCELL
  mstr_misc dns *
  *
#ISCELL
  pure_quanta quanta_title_block_c *
  *
#ISCELL
  pure_quanta_power gnd *
  page380_i1
#CELL
  pure_quanta q_cap *
  page380_i10
#CELL
  pure_quanta q_res *
  page380_i11
#CELL
  pure_quanta q_cap *
  page380_i12
#ISCELL
  pure_quanta_power universal_power *
  page380_i13
#ISCELL
  pure_quanta_power gnd *
  page380_i14
#ISCELL
  pure_quanta_power gnd *
  page380_i15
#CELL
  pure_quanta mpq8626gdz *
  page380_i16
#CELL
  pure_quanta q_cap *
  page380_i17
#CELL
  pure_quanta q_cap *
  page380_i18
#CELL
  pure_quanta q_res *
  page380_i19
#CELL
  pure_quanta q_inductor *
  page380_i2
#ISCELL
  pure_quanta_power gnd *
  page380_i20
#CELL
  pure_quanta q_res *
  page380_i21
#ISCELL
  pure_quanta_power gnd *
  page380_i22
#CELL
  pure_quanta q_cap *
  page380_i23
#CELL
  pure_quanta q_inductor *
  page380_i24
#CELL
  pure_quanta q_cap *
  page380_i26
#CELL
  pure_quanta q_res *
  page380_i27
#CELL
  pure_quanta q_cap *
  page380_i28
#CELL
  pure_quanta q_cap *
  page380_i29
#CELL
  pure_quanta q_cap *
  page380_i3
#ISCELL
  pure_quanta_power gnd *
  page380_i30
#ISCELL
  pure_quanta_power universal_power *
  page380_i31
#CELL
  pure_quanta q_cap *
  page380_i32
#CELL
  pure_quanta q_cap *
  page380_i33
#ISCELL
  pure_quanta_power universal_power *
  page380_i34
#CELL
  pure_quanta q_cap *
  page380_i35
#ISCELL
  pure_quanta_power gnd *
  page380_i36
#ISCELL
  pure_quanta_power universal_power *
  page380_i37
#CELL
  pure_quanta q_res *
  page380_i38
#ISCELL
  standard offpage *
  page380_i39
#ISCELL
  pure_quanta_power gnd *
  page380_i4
#CELL
  pure_quanta q_res *
  page380_i40
#CELL
  pure_quanta q_cap *
  page380_i41
#ISCELL
  pure_quanta_power gnd *
  page380_i42
#ISCELL
  standard offpage *
  page380_i43
#CELL
  pure_quanta q_res *
  page380_i44
#CELL
  pure_quanta q_res *
  page380_i45
#ISCELL
  pure_quanta_power gnd *
  page380_i5
#CELL
  pure_quanta q_res *
  page380_i6
#CELL
  pure_quanta q_cap *
  page380_i7
#ISCELL
  pure_quanta_power gnd *
  page380_i8
#ISCELL
  mstr_misc dns *
  *
#ISCELL
  pure_quanta quanta_title_block_c *
  *
#ISCELL
  pure_quanta_power bom_note *
  *
#CELL
  pure_quanta q_res *
  page271_i10
#CELL
  pure_quanta q_cap *
  page271_i11
#ISCELL
  pure_quanta_power universal_gnd *
  page271_i13
#CELL
  pure_quanta q_res *
  page271_i14
#ISCELL
  pure_quanta_power universal_gnd *
  page271_i18
#ISCELL
  pure_quanta_power universal_gnd *
  page271_i21
#CELL
  pure_quanta q_cap *
  page271_i22
#ISCELL
  pure_quanta_power universal_power *
  page271_i23
#CELL
  pure_quanta q_res *
  page271_i25
#ISCELL
  pure_quanta_power universal_power *
  page271_i26
#CELL
  pure_quanta isl28022frzt *
  page271_i28
#CELL
  pure_quanta q_res *
  page271_i29
#ISCELL
  pure_quanta_power universal_gnd *
  page271_i3
#CELL
  pure_quanta q_res *
  page271_i30
#ISCELL
  standard offpage *
  page271_i31
#ISCELL
  standard offpage *
  page271_i5
#ISCELL
  standard offpage *
  page271_i6
#CELL
  pure_quanta q_res *
  page271_i9
#ISCELL
  pure_quanta quanta_title_block_c *
  *
#ISCELL
  standard tap *
  page381_i10
#ISCELL
  standard tap *
  page381_i11
#ISCELL
  standard tap *
  page381_i12
#ISCELL
  standard tap *
  page381_i13
#ISCELL
  standard tap *
  page381_i14
#ISCELL
  standard tap *
  page381_i15
#ISCELL
  standard tap *
  page381_i16
#ISCELL
  standard tap *
  page381_i17
#ISCELL
  standard tap *
  page381_i18
#ISCELL
  standard tap *
  page381_i19
#ISCELL
  standard tap *
  page381_i20
#ISCELL
  standard offpage *
  page381_i21
#ISCELL
  standard offpage *
  page381_i22
#ISCELL
  standard tap *
  page381_i23
#ISCELL
  standard tap *
  page381_i24
#ISCELL
  standard offpage *
  page381_i25
#ISCELL
  standard offpage *
  page381_i26
#ISCELL
  standard tap *
  page381_i27
#ISCELL
  standard tap *
  page381_i28
#ISCELL
  standard tap *
  page381_i29
#CELL
  pure_quanta pt5161lrs *
  page381_i3
#ISCELL
  standard tap *
  page381_i30
#ISCELL
  standard tap *
  page381_i31
#ISCELL
  standard tap *
  page381_i32
#ISCELL
  standard tap *
  page381_i33
#ISCELL
  standard tap *
  page381_i34
#ISCELL
  standard tap *
  page381_i35
#ISCELL
  standard tap *
  page381_i36
#ISCELL
  standard tap *
  page381_i37
#ISCELL
  standard tap *
  page381_i38
#ISCELL
  standard tap *
  page381_i39
#CELL
  pure_quanta pt5161lrs *
  page381_i4
#ISCELL
  standard tap *
  page381_i40
#ISCELL
  standard tap *
  page381_i5
#ISCELL
  standard tap *
  page381_i6
#ISCELL
  standard tap *
  page381_i7
#ISCELL
  standard tap *
  page381_i8
#ISCELL
  standard tap *
  page381_i9
#ISCELL
  pure_quanta quanta_title_block_c *
  *
#ISCELL
  standard tap *
  page382_i10
#ISCELL
  standard tap *
  page382_i11
#ISCELL
  standard tap *
  page382_i12
#ISCELL
  standard tap *
  page382_i13
#ISCELL
  standard tap *
  page382_i14
#ISCELL
  standard tap *
  page382_i15
#ISCELL
  standard tap *
  page382_i16
#ISCELL
  standard tap *
  page382_i17
#CELL
  pure_quanta pt5161lrs *
  page382_i2
#ISCELL
  standard tap *
  page382_i20
#ISCELL
  standard tap *
  page382_i21
#ISCELL
  standard offpage *
  page382_i22
#ISCELL
  standard offpage *
  page382_i23
#ISCELL
  standard tap *
  page382_i24
#ISCELL
  standard tap *
  page382_i25
#ISCELL
  standard tap *
  page382_i26
#ISCELL
  standard tap *
  page382_i27
#ISCELL
  standard tap *
  page382_i28
#ISCELL
  standard tap *
  page382_i29
#CELL
  pure_quanta pt5161lrs *
  page382_i3
#ISCELL
  standard tap *
  page382_i30
#ISCELL
  standard tap *
  page382_i31
#ISCELL
  standard tap *
  page382_i32
#ISCELL
  standard tap *
  page382_i33
#ISCELL
  standard tap *
  page382_i34
#ISCELL
  standard tap *
  page382_i35
#ISCELL
  standard tap *
  page382_i36
#ISCELL
  standard tap *
  page382_i37
#ISCELL
  standard tap *
  page382_i38
#ISCELL
  standard tap *
  page382_i39
#ISCELL
  standard tap *
  page382_i4
#ISCELL
  standard offpage *
  page382_i42
#ISCELL
  standard offpage *
  page382_i43
#ISCELL
  standard tap *
  page382_i5
#ISCELL
  standard tap *
  page382_i6
#ISCELL
  standard tap *
  page382_i7
#ISCELL
  standard tap *
  page382_i8
#ISCELL
  standard tap *
  page382_i9
#ISCELL
  pure_quanta quanta_title_block_c *
  *
#ISCELL
  standard tap *
  page383_i10
#ISCELL
  standard tap *
  page383_i11
#ISCELL
  standard tap *
  page383_i12
#ISCELL
  standard tap *
  page383_i13
#ISCELL
  standard tap *
  page383_i14
#ISCELL
  standard tap *
  page383_i15
#ISCELL
  standard tap *
  page383_i16
#ISCELL
  standard tap *
  page383_i17
#ISCELL
  standard tap *
  page383_i18
#ISCELL
  standard tap *
  page383_i19
#ISCELL
  standard tap *
  page383_i20
#ISCELL
  standard offpage *
  page383_i21
#ISCELL
  standard offpage *
  page383_i22
#ISCELL
  standard tap *
  page383_i23
#ISCELL
  standard tap *
  page383_i24
#ISCELL
  standard tap *
  page383_i25
#ISCELL
  standard offpage *
  page383_i26
#ISCELL
  standard offpage *
  page383_i27
#ISCELL
  standard tap *
  page383_i28
#ISCELL
  standard tap *
  page383_i29
#CELL
  pure_quanta pt5161lrs *
  page383_i3
#ISCELL
  standard tap *
  page383_i30
#ISCELL
  standard tap *
  page383_i31
#ISCELL
  standard tap *
  page383_i32
#ISCELL
  standard tap *
  page383_i33
#ISCELL
  standard tap *
  page383_i34
#ISCELL
  standard tap *
  page383_i35
#ISCELL
  standard tap *
  page383_i36
#ISCELL
  standard tap *
  page383_i37
#ISCELL
  standard tap *
  page383_i38
#ISCELL
  standard tap *
  page383_i39
#CELL
  pure_quanta pt5161lrs *
  page383_i4
#ISCELL
  standard tap *
  page383_i40
#ISCELL
  standard tap *
  page383_i5
#ISCELL
  standard tap *
  page383_i6
#ISCELL
  standard tap *
  page383_i7
#ISCELL
  standard tap *
  page383_i8
#ISCELL
  standard tap *
  page383_i9
#ISCELL
  pure_quanta quanta_title_block_c *
  *
#CELL
  pure_quanta pt5161lrs *
  page384_i1
#ISCELL
  standard tap *
  page384_i10
#CELL
  pure_quanta q_cap_diffbus *
  page384_i100
#CELL
  pure_quanta q_cap_diffbus *
  page384_i101
#CELL
  pure_quanta q_cap_diffbus *
  page384_i102
#ISCELL
  standard tap *
  page384_i103
#ISCELL
  standard tap *
  page384_i104
#ISCELL
  standard tap *
  page384_i105
#ISCELL
  standard tap *
  page384_i106
#ISCELL
  standard tap *
  page384_i107
#ISCELL
  standard tap *
  page384_i108
#ISCELL
  standard tap *
  page384_i109
#ISCELL
  standard tap *
  page384_i11
#ISCELL
  standard tap *
  page384_i110
#ISCELL
  standard tap *
  page384_i111
#ISCELL
  standard tap *
  page384_i112
#ISCELL
  standard tap *
  page384_i113
#ISCELL
  standard tap *
  page384_i114
#ISCELL
  standard tap *
  page384_i115
#ISCELL
  standard tap *
  page384_i116
#ISCELL
  standard tap *
  page384_i117
#CELL
  pure_quanta q_cap_diffbus *
  page384_i118
#CELL
  pure_quanta q_cap_diffbus *
  page384_i119
#ISCELL
  standard tap *
  page384_i12
#CELL
  pure_quanta q_cap_diffbus *
  page384_i120
#CELL
  pure_quanta q_cap_diffbus *
  page384_i121
#CELL
  pure_quanta q_cap_diffbus *
  page384_i122
#CELL
  pure_quanta q_cap_diffbus *
  page384_i123
#CELL
  pure_quanta q_cap_diffbus *
  page384_i124
#CELL
  pure_quanta q_cap_diffbus *
  page384_i125
#CELL
  pure_quanta q_cap_diffbus *
  page384_i126
#CELL
  pure_quanta q_cap_diffbus *
  page384_i127
#ISCELL
  standard tap *
  page384_i128
#CELL
  pure_quanta q_cap_diffbus *
  page384_i129
#ISCELL
  standard tap *
  page384_i13
#CELL
  pure_quanta q_cap_diffbus *
  page384_i130
#ISCELL
  standard tap *
  page384_i131
#ISCELL
  standard tap *
  page384_i132
#ISCELL
  standard tap *
  page384_i133
#ISCELL
  standard tap *
  page384_i134
#ISCELL
  standard tap *
  page384_i135
#ISCELL
  standard tap *
  page384_i136
#ISCELL
  standard tap *
  page384_i137
#ISCELL
  standard tap *
  page384_i138
#ISCELL
  standard tap *
  page384_i139
#ISCELL
  standard tap *
  page384_i14
#ISCELL
  standard tap *
  page384_i140
#ISCELL
  standard tap *
  page384_i141
#ISCELL
  standard tap *
  page384_i142
#ISCELL
  standard offpage *
  page384_i143
#ISCELL
  standard offpage *
  page384_i144
#ISCELL
  standard tap *
  page384_i15
#ISCELL
  standard tap *
  page384_i16
#ISCELL
  standard tap *
  page384_i19
#CELL
  pure_quanta pt5161lrs *
  page384_i2
#ISCELL
  standard tap *
  page384_i20
#ISCELL
  standard offpage *
  page384_i21
#ISCELL
  standard offpage *
  page384_i22
#ISCELL
  standard offpage *
  page384_i23
#ISCELL
  standard offpage *
  page384_i24
#ISCELL
  standard tap *
  page384_i25
#ISCELL
  standard tap *
  page384_i26
#ISCELL
  standard tap *
  page384_i27
#ISCELL
  standard tap *
  page384_i28
#ISCELL
  standard tap *
  page384_i29
#ISCELL
  standard tap *
  page384_i3
#ISCELL
  standard tap *
  page384_i30
#ISCELL
  standard tap *
  page384_i31
#ISCELL
  standard tap *
  page384_i32
#ISCELL
  standard tap *
  page384_i33
#ISCELL
  standard tap *
  page384_i34
#ISCELL
  standard tap *
  page384_i35
#ISCELL
  standard tap *
  page384_i36
#ISCELL
  standard tap *
  page384_i37
#ISCELL
  standard tap *
  page384_i38
#ISCELL
  standard tap *
  page384_i39
#ISCELL
  standard tap *
  page384_i4
#ISCELL
  standard tap *
  page384_i40
#ISCELL
  standard offpage *
  page384_i41
#ISCELL
  standard offpage *
  page384_i42
#ISCELL
  standard tap *
  page384_i43
#ISCELL
  standard tap *
  page384_i44
#ISCELL
  standard tap *
  page384_i45
#ISCELL
  standard tap *
  page384_i46
#ISCELL
  standard tap *
  page384_i47
#ISCELL
  standard tap *
  page384_i48
#ISCELL
  standard tap *
  page384_i49
#ISCELL
  standard tap *
  page384_i5
#ISCELL
  standard tap *
  page384_i50
#ISCELL
  standard tap *
  page384_i51
#ISCELL
  standard tap *
  page384_i52
#ISCELL
  standard tap *
  page384_i53
#ISCELL
  standard tap *
  page384_i54
#ISCELL
  standard tap *
  page384_i55
#ISCELL
  standard tap *
  page384_i56
#ISCELL
  standard tap *
  page384_i57
#ISCELL
  standard tap *
  page384_i58
#CELL
  pure_quanta q_cap_diffbus *
  page384_i59
#ISCELL
  standard tap *
  page384_i6
#CELL
  pure_quanta q_cap_diffbus *
  page384_i60
#CELL
  pure_quanta q_cap_diffbus *
  page384_i61
#CELL
  pure_quanta q_cap_diffbus *
  page384_i62
#CELL
  pure_quanta q_cap_diffbus *
  page384_i63
#CELL
  pure_quanta q_cap_diffbus *
  page384_i64
#CELL
  pure_quanta q_cap_diffbus *
  page384_i65
#CELL
  pure_quanta q_cap_diffbus *
  page384_i66
#ISCELL
  standard tap *
  page384_i67
#ISCELL
  standard tap *
  page384_i68
#ISCELL
  standard tap *
  page384_i69
#ISCELL
  standard tap *
  page384_i7
#ISCELL
  standard tap *
  page384_i70
#CELL
  pure_quanta q_cap_diffbus *
  page384_i71
#CELL
  pure_quanta q_cap_diffbus *
  page384_i72
#CELL
  pure_quanta q_cap_diffbus *
  page384_i73
#CELL
  pure_quanta q_cap_diffbus *
  page384_i74
#CELL
  pure_quanta q_cap_diffbus *
  page384_i75
#CELL
  pure_quanta q_cap_diffbus *
  page384_i76
#CELL
  pure_quanta q_cap_diffbus *
  page384_i77
#CELL
  pure_quanta q_cap_diffbus *
  page384_i78
#ISCELL
  standard tap *
  page384_i79
#ISCELL
  standard tap *
  page384_i8
#ISCELL
  standard tap *
  page384_i80
#ISCELL
  standard tap *
  page384_i81
#ISCELL
  standard tap *
  page384_i82
#ISCELL
  standard tap *
  page384_i83
#ISCELL
  standard tap *
  page384_i84
#ISCELL
  standard tap *
  page384_i85
#ISCELL
  standard tap *
  page384_i86
#ISCELL
  standard tap *
  page384_i87
#ISCELL
  standard tap *
  page384_i88
#ISCELL
  standard offpage *
  page384_i89
#ISCELL
  standard tap *
  page384_i9
#ISCELL
  standard offpage *
  page384_i90
#ISCELL
  standard tap *
  page384_i91
#ISCELL
  standard tap *
  page384_i92
#ISCELL
  standard offpage *
  page384_i93
#ISCELL
  standard offpage *
  page384_i94
#ISCELL
  standard tap *
  page384_i95
#ISCELL
  standard tap *
  page384_i96
#ISCELL
  standard tap *
  page384_i97
#ISCELL
  standard tap *
  page384_i98
#CELL
  pure_quanta q_cap_diffbus *
  page384_i99
#ISCELL
  mstr_misc dns *
  *
#ISCELL
  pure_quanta quanta_title_block_c *
  *
#ISCELL
  standard offpage *
  page385_i100
#ISCELL
  pure_quanta_power p1v0 *
  page385_i101
#ISCELL
  standard offpage *
  page385_i102
#ISCELL
  standard offpage *
  page385_i103
#CELL
  pure_quanta q_res *
  page385_i111
#ISCELL
  pure_quanta_power universal_gnd *
  page385_i112
#ISCELL
  standard offpage *
  page385_i113
#CELL
  pure_quanta q_res *
  page385_i114
#ISCELL
  pure_quanta_power gnd *
  page385_i115
#CELL
  pure_quanta q_res *
  page385_i116
#ISCELL
  pure_quanta_power p1v0 *
  page385_i117
#ISCELL
  standard offpage *
  page385_i118
#CELL
  pure_quanta q_res *
  page385_i119
#ISCELL
  pure_quanta_power universal_gnd *
  page385_i120
#CELL
  pure_quanta q_res *
  page385_i121
#ISCELL
  standard offpage *
  page385_i122
#CELL
  pure_quanta q_res *
  page385_i123
#ISCELL
  pure_quanta_power gnd *
  page385_i128
#ISCELL
  standard offpage *
  page385_i133
#ISCELL
  standard offpage *
  page385_i134
#ISCELL
  standard offpage *
  page385_i135
#ISCELL
  standard offpage *
  page385_i136
#ISCELL
  standard offpage *
  page385_i137
#ISCELL
  standard offpage *
  page385_i138
#ISCELL
  standard offpage *
  page385_i139
#CELL
  pure_quanta q_res *
  page385_i143
#ISCELL
  pure_quanta_power p1v0 *
  page385_i144
#CELL
  pure_quanta q_res *
  page385_i145
#CELL
  pure_quanta q_res *
  page385_i146
#CELL
  pure_quanta q_res *
  page385_i147
#ISCELL
  standard offpage *
  page385_i21
#ISCELL
  standard offpage *
  page385_i22
#ISCELL
  pure_quanta_power universal_gnd *
  page385_i23
#CELL
  pure_quanta q_res *
  page385_i25
#ISCELL
  pure_quanta_power p1v0 *
  page385_i26
#CELL
  pure_quanta q_res *
  page385_i27
#CELL
  pure_quanta q_res *
  page385_i28
#CELL
  pure_quanta q_res *
  page385_i29
#CELL
  pure_quanta q_res *
  page385_i30
#CELL
  pure_quanta q_res *
  page385_i31
#ISCELL
  pure_quanta_power p1v0 *
  page385_i32
#ISCELL
  standard offpage *
  page385_i33
#ISCELL
  standard offpage *
  page385_i34
#ISCELL
  pure_quanta_power universal_gnd *
  page385_i35
#ISCELL
  pure_quanta_power universal_gnd *
  page385_i36
#CELL
  pure_quanta q_res *
  page385_i37
#CELL
  pure_quanta q_res *
  page385_i38
#CELL
  pure_quanta q_res *
  page385_i39
#CELL
  pure_quanta q_res *
  page385_i40
#CELL
  pure_quanta q_res *
  page385_i41
#CELL
  pure_quanta q_res *
  page385_i42
#ISCELL
  standard offpage *
  page385_i43
#ISCELL
  standard offpage *
  page385_i44
#ISCELL
  standard offpage *
  page385_i45
#ISCELL
  standard offpage *
  page385_i46
#ISCELL
  standard offpage *
  page385_i47
#ISCELL
  standard offpage *
  page385_i48
#CELL
  pure_quanta q_res *
  page385_i49
#CELL
  pure_quanta q_res *
  page385_i50
#ISCELL
  standard offpage *
  page385_i51
#ISCELL
  standard offpage *
  page385_i52
#CELL
  pure_quanta pt5161lrs *
  page385_i53
#ISCELL
  standard offpage *
  page385_i54
#ISCELL
  standard offpage *
  page385_i55
#ISCELL
  standard offpage *
  page385_i56
#CELL
  pure_quanta q_res *
  page385_i57
#CELL
  pure_quanta q_res *
  page385_i58
#ISCELL
  pure_quanta_power universal_gnd *
  page385_i59
#CELL
  pure_quanta q_res *
  page385_i60
#CELL
  pure_quanta q_res *
  page385_i61
#CELL
  pure_quanta q_res *
  page385_i62
#CELL
  pure_quanta q_res *
  page385_i63
#ISCELL
  standard offpage *
  page385_i64
#ISCELL
  standard offpage *
  page385_i65
#ISCELL
  standard offpage *
  page385_i66
#ISCELL
  standard offpage *
  page385_i67
#ISCELL
  standard offpage *
  page385_i68
#ISCELL
  standard offpage *
  page385_i69
#ISCELL
  pure_quanta_power universal_gnd *
  page385_i70
#CELL
  pure_quanta q_res *
  page385_i71
#CELL
  pure_quanta q_res *
  page385_i72
#ISCELL
  standard offpage *
  page385_i73
#ISCELL
  pure_quanta_power p1v0 *
  page385_i74
#ISCELL
  pure_quanta_power universal_gnd *
  page385_i75
#CELL
  pure_quanta q_res *
  page385_i76
#CELL
  pure_quanta q_res *
  page385_i77
#ISCELL
  standard offpage *
  page385_i79
#ISCELL
  standard offpage *
  page385_i80
#ISCELL
  standard offpage *
  page385_i82
#ISCELL
  standard offpage *
  page385_i83
#ISCELL
  standard offpage *
  page385_i84
#ISCELL
  pure_quanta_power universal_gnd *
  page385_i85
#CELL
  pure_quanta q_res *
  page385_i86
#CELL
  pure_quanta q_res *
  page385_i87
#CELL
  pure_quanta q_res *
  page385_i88
#CELL
  pure_quanta q_res *
  page385_i89
#CELL
  pure_quanta q_res *
  page385_i90
#CELL
  pure_quanta q_res *
  page385_i91
#ISCELL
  pure_quanta_power p1v0 *
  page385_i92
#ISCELL
  pure_quanta_power gnd *
  page385_i93
#ISCELL
  pure_quanta_power gnd *
  page385_i94
#ISCELL
  standard offpage *
  page385_i95
#CELL
  pure_quanta q_res *
  page385_i96
#CELL
  pure_quanta q_res *
  page385_i97
#CELL
  pure_quanta q_res *
  page385_i98
#ISCELL
  standard offpage *
  page385_i99
#ISCELL
  mstr_misc dns *
  *
#ISCELL
  pure_quanta quanta_title_block_c *
  *
#ISCELL
  pure_quanta_power universal_gnd *
  page386_i1
#ISCELL
  pure_quanta_power universal_gnd *
  page386_i10
#ISCELL
  pure_quanta_power p1v0 *
  page386_i11
#ISCELL
  pure_quanta_power universal_gnd *
  page386_i12
#CELL
  pure_quanta q_res *
  page386_i13
#ISCELL
  pure_quanta_power universal_gnd *
  page386_i14
#CELL
  pure_quanta q_res *
  page386_i15
#ISCELL
  pure_quanta_power universal_gnd *
  page386_i16
#CELL
  pure_quanta pt5161lrs *
  page386_i17
#CELL
  pure_quanta q_res *
  page386_i18
#CELL
  pure_quanta q_res *
  page386_i19
#CELL
  pure_quanta pt5161lrs *
  page386_i3
#ISCELL
  pure_quanta_power p1v0 *
  page386_i5
#ISCELL
  pure_quanta_power p1v0 *
  page386_i6
#ISCELL
  pure_quanta_power p1v0 *
  page386_i7
#ISCELL
  pure_quanta_power vcc_core *
  page386_i8
#ISCELL
  pure_quanta_power vcc_core *
  page386_i9
#ISCELL
  pure_quanta quanta_title_block_c *
  *
#ISCELL
  pure_quanta_power p1v0 *
  page387_i20
#CELL
  pure_quanta q_cap *
  page387_i21
#ISCELL
  pure_quanta_power universal_gnd *
  page387_i22
#ISCELL
  pure_quanta_power universal_gnd *
  page387_i23
#CELL
  pure_quanta q_res *
  page387_i24
#ISCELL
  pure_quanta_power universal_gnd *
  page387_i25
#ISCELL
  pure_quanta_power universal_gnd *
  page387_i26
#CELL
  pure_quanta m24m02drmn6tp *
  page387_i3
#ISCELL
  standard offpage *
  page387_i4
#ISCELL
  standard offpage *
  page387_i5
#CELL
  pure_quanta q_res *
  page387_i6
#CELL
  pure_quanta q_res *
  page387_i7
#ISCELL
  mstr_misc dns *
  *
#ISCELL
  pure_quanta quanta_title_block_c *
  *
#ISCELL
  pure_quanta_power cad_note *
  *
#CELL
  pure_quanta q_res *
  page388_i10
#CELL
  pure_quanta q_capp *
  page388_i100
#CELL
  pure_quanta q_cap *
  page388_i101
#CELL
  pure_quanta q_capp *
  page388_i102
#CELL
  pure_quanta q_cap *
  page388_i103
#CELL
  pure_quanta q_cap *
  page388_i104
#CELL
  pure_quanta q_cap *
  page388_i105
#CELL
  pure_quanta q_cap *
  page388_i106
#CELL
  pure_quanta q_res *
  page388_i11
#CELL
  pure_quanta q_inductor *
  page388_i12
#CELL
  pure_quanta q_cap *
  page388_i13
#CELL
  pure_quanta q_cap *
  page388_i14
#ISCELL
  pure_quanta_power p1v0 *
  page388_i15
#CELL
  pure_quanta q_cap *
  page388_i16
#CELL
  pure_quanta q_cap *
  page388_i17
#CELL
  pure_quanta q_cap *
  page388_i18
#CELL
  pure_quanta q_cap *
  page388_i19
#ISCELL
  pure_quanta_power universal_gnd *
  page388_i20
#ISCELL
  pure_quanta_power universal_gnd *
  page388_i21
#CELL
  pure_quanta q_cap *
  page388_i22
#CELL
  pure_quanta q_cap *
  page388_i23
#CELL
  pure_quanta q_cap *
  page388_i24
#CELL
  pure_quanta q_cap *
  page388_i25
#CELL
  pure_quanta q_cap *
  page388_i26
#CELL
  pure_quanta q_cap *
  page388_i27
#CELL
  pure_quanta q_cap *
  page388_i28
#CELL
  pure_quanta q_cap *
  page388_i29
#ISCELL
  pure_quanta_power p1v0 *
  page388_i3
#CELL
  pure_quanta q_inductor *
  page388_i30
#ISCELL
  pure_quanta_power vcc_core *
  page388_i31
#CELL
  pure_quanta q_cap *
  page388_i32
#ISCELL
  pure_quanta_power vcc_core *
  page388_i33
#ISCELL
  pure_quanta_power universal_gnd *
  page388_i35
#CELL
  pure_quanta q_cap *
  page388_i36
#CELL
  pure_quanta q_cap *
  page388_i38
#CELL
  pure_quanta q_cap *
  page388_i39
#CELL
  pure_quanta q_res *
  page388_i4
#CELL
  pure_quanta q_cap *
  page388_i40
#CELL
  pure_quanta q_cap *
  page388_i41
#CELL
  pure_quanta q_cap *
  page388_i42
#CELL
  pure_quanta q_cap *
  page388_i43
#CELL
  pure_quanta q_cap *
  page388_i44
#CELL
  pure_quanta q_cap *
  page388_i45
#CELL
  pure_quanta q_cap *
  page388_i46
#CELL
  pure_quanta q_cap *
  page388_i48
#CELL
  pure_quanta q_cap *
  page388_i49
#CELL
  pure_quanta q_res *
  page388_i5
#CELL
  pure_quanta q_cap *
  page388_i50
#CELL
  pure_quanta q_cap *
  page388_i51
#CELL
  pure_quanta q_cap *
  page388_i52
#CELL
  pure_quanta q_cap *
  page388_i53
#CELL
  pure_quanta q_cap *
  page388_i54
#CELL
  pure_quanta q_cap *
  page388_i55
#CELL
  pure_quanta q_cap *
  page388_i56
#CELL
  pure_quanta q_cap *
  page388_i57
#CELL
  pure_quanta q_cap *
  page388_i58
#CELL
  pure_quanta q_cap *
  page388_i59
#ISCELL
  pure_quanta_power p1v0 *
  page388_i6
#CELL
  pure_quanta q_cap *
  page388_i60
#ISCELL
  pure_quanta_power universal_gnd *
  page388_i61
#CELL
  pure_quanta q_cap *
  page388_i62
#ISCELL
  pure_quanta_power universal_gnd *
  page388_i63
#CELL
  pure_quanta q_cap *
  page388_i65
#CELL
  pure_quanta q_cap *
  page388_i66
#CELL
  pure_quanta q_cap *
  page388_i67
#ISCELL
  pure_quanta_power vcc_core *
  page388_i68
#CELL
  pure_quanta q_cap *
  page388_i69
#ISCELL
  pure_quanta_power universal_gnd *
  page388_i7
#CELL
  pure_quanta q_cap *
  page388_i70
#CELL
  pure_quanta q_cap *
  page388_i71
#CELL
  pure_quanta q_cap *
  page388_i72
#CELL
  pure_quanta q_cap *
  page388_i73
#CELL
  pure_quanta q_cap *
  page388_i74
#CELL
  pure_quanta q_cap *
  page388_i75
#CELL
  pure_quanta q_cap *
  page388_i76
#CELL
  pure_quanta q_cap *
  page388_i77
#CELL
  pure_quanta q_cap *
  page388_i78
#CELL
  pure_quanta q_cap *
  page388_i79
#CELL
  pure_quanta q_cap *
  page388_i8
#CELL
  pure_quanta q_cap *
  page388_i80
#CELL
  pure_quanta q_cap *
  page388_i81
#CELL
  pure_quanta q_cap *
  page388_i82
#CELL
  pure_quanta q_cap *
  page388_i83
#CELL
  pure_quanta q_cap *
  page388_i84
#CELL
  pure_quanta q_cap *
  page388_i85
#ISCELL
  pure_quanta_power universal_gnd *
  page388_i86
#CELL
  pure_quanta q_cap *
  page388_i87
#CELL
  pure_quanta q_inductor *
  page388_i88
#CELL
  pure_quanta q_res *
  page388_i89
#CELL
  pure_quanta q_cap *
  page388_i9
#CELL
  pure_quanta q_cap *
  page388_i90
#CELL
  pure_quanta q_cap *
  page388_i91
#CELL
  pure_quanta q_cap *
  page388_i93
#CELL
  pure_quanta q_cap *
  page388_i94
#CELL
  pure_quanta q_cap *
  page388_i95
#CELL
  pure_quanta q_cap *
  page388_i96
#CELL
  pure_quanta q_capp *
  page388_i97
#CELL
  pure_quanta q_capp *
  page388_i98
#CELL
  pure_quanta q_capp *
  page388_i99
#ISCELL
  pure_quanta quanta_title_block_c *
  *
#ISCELL
  pure_quanta quanta_title_block_c *
  *
#ISCELL
  pure_quanta quanta_title_block_c *
  *
#ISCELL
  pure_quanta quanta_title_block_c *
  *
#CELL
  pure_quanta pt5161lrs *
  page404_i1
#ISCELL
  standard tap *
  page404_i10
#ISCELL
  standard tap *
  page404_i11
#ISCELL
  standard tap *
  page404_i12
#ISCELL
  standard tap *
  page404_i13
#ISCELL
  standard tap *
  page404_i14
#ISCELL
  standard tap *
  page404_i15
#ISCELL
  standard tap *
  page404_i16
#ISCELL
  standard tap *
  page404_i17
#ISCELL
  standard offpage *
  page404_i18
#ISCELL
  standard offpage *
  page404_i19
#ISCELL
  standard tap *
  page404_i2
#ISCELL
  standard tap *
  page404_i20
#ISCELL
  standard tap *
  page404_i21
#ISCELL
  standard tap *
  page404_i22
#ISCELL
  standard tap *
  page404_i23
#ISCELL
  standard tap *
  page404_i24
#ISCELL
  standard tap *
  page404_i25
#ISCELL
  standard tap *
  page404_i26
#ISCELL
  standard tap *
  page404_i27
#ISCELL
  standard tap *
  page404_i28
#ISCELL
  standard tap *
  page404_i29
#ISCELL
  standard tap *
  page404_i3
#ISCELL
  standard tap *
  page404_i30
#ISCELL
  standard tap *
  page404_i31
#ISCELL
  standard tap *
  page404_i32
#ISCELL
  standard tap *
  page404_i33
#ISCELL
  standard tap *
  page404_i34
#ISCELL
  standard tap *
  page404_i35
#ISCELL
  standard offpage *
  page404_i36
#ISCELL
  standard offpage *
  page404_i37
#CELL
  pure_quanta pt5161lrs *
  page404_i38
#ISCELL
  standard tap *
  page404_i4
#ISCELL
  standard tap *
  page404_i5
#ISCELL
  standard tap *
  page404_i6
#ISCELL
  standard tap *
  page404_i7
#ISCELL
  standard tap *
  page404_i8
#ISCELL
  standard tap *
  page404_i9
#ISCELL
  pure_quanta quanta_title_block_c *
  *
#CELL
  pure_quanta pt5161lrs *
  page405_i1
#ISCELL
  standard tap *
  page405_i10
#ISCELL
  standard tap *
  page405_i11
#ISCELL
  standard tap *
  page405_i12
#ISCELL
  standard tap *
  page405_i13
#ISCELL
  standard tap *
  page405_i14
#ISCELL
  standard tap *
  page405_i15
#ISCELL
  standard tap *
  page405_i16
#ISCELL
  standard tap *
  page405_i17
#ISCELL
  standard offpage *
  page405_i18
#ISCELL
  standard offpage *
  page405_i19
#ISCELL
  standard tap *
  page405_i2
#ISCELL
  standard tap *
  page405_i20
#ISCELL
  standard tap *
  page405_i21
#ISCELL
  standard tap *
  page405_i22
#ISCELL
  standard tap *
  page405_i23
#ISCELL
  standard tap *
  page405_i24
#ISCELL
  standard tap *
  page405_i25
#ISCELL
  standard tap *
  page405_i26
#ISCELL
  standard tap *
  page405_i27
#ISCELL
  standard tap *
  page405_i28
#ISCELL
  standard tap *
  page405_i29
#ISCELL
  standard tap *
  page405_i3
#ISCELL
  standard tap *
  page405_i30
#ISCELL
  standard tap *
  page405_i31
#ISCELL
  standard tap *
  page405_i32
#ISCELL
  standard tap *
  page405_i33
#ISCELL
  standard tap *
  page405_i34
#ISCELL
  standard tap *
  page405_i35
#ISCELL
  standard offpage *
  page405_i36
#ISCELL
  standard offpage *
  page405_i37
#CELL
  pure_quanta pt5161lrs *
  page405_i38
#ISCELL
  standard tap *
  page405_i4
#ISCELL
  standard tap *
  page405_i5
#ISCELL
  standard tap *
  page405_i6
#ISCELL
  standard tap *
  page405_i7
#ISCELL
  standard tap *
  page405_i8
#ISCELL
  standard tap *
  page405_i9
#ISCELL
  pure_quanta quanta_title_block_c *
  *
#CELL
  pure_quanta pt5161lrs *
  page406_i1
#ISCELL
  standard tap *
  page406_i10
#ISCELL
  standard tap *
  page406_i11
#ISCELL
  standard tap *
  page406_i12
#ISCELL
  standard tap *
  page406_i13
#ISCELL
  standard tap *
  page406_i14
#ISCELL
  standard tap *
  page406_i15
#ISCELL
  standard tap *
  page406_i16
#ISCELL
  standard tap *
  page406_i17
#ISCELL
  standard offpage *
  page406_i18
#ISCELL
  standard offpage *
  page406_i19
#ISCELL
  standard tap *
  page406_i2
#ISCELL
  standard tap *
  page406_i20
#ISCELL
  standard tap *
  page406_i21
#ISCELL
  standard tap *
  page406_i22
#ISCELL
  standard tap *
  page406_i23
#ISCELL
  standard tap *
  page406_i24
#ISCELL
  standard tap *
  page406_i25
#ISCELL
  standard tap *
  page406_i26
#ISCELL
  standard tap *
  page406_i27
#ISCELL
  standard tap *
  page406_i28
#ISCELL
  standard tap *
  page406_i29
#ISCELL
  standard tap *
  page406_i3
#ISCELL
  standard tap *
  page406_i30
#ISCELL
  standard tap *
  page406_i31
#ISCELL
  standard tap *
  page406_i32
#ISCELL
  standard tap *
  page406_i33
#ISCELL
  standard tap *
  page406_i34
#ISCELL
  standard tap *
  page406_i35
#ISCELL
  standard offpage *
  page406_i36
#ISCELL
  standard offpage *
  page406_i37
#CELL
  pure_quanta pt5161lrs *
  page406_i38
#ISCELL
  standard tap *
  page406_i4
#ISCELL
  standard tap *
  page406_i5
#ISCELL
  standard tap *
  page406_i6
#ISCELL
  standard tap *
  page406_i7
#ISCELL
  standard tap *
  page406_i8
#ISCELL
  standard tap *
  page406_i9
#ISCELL
  pure_quanta quanta_title_block_c *
  *
#ISCELL
  standard offpage *
  page407_i1
#ISCELL
  standard tap *
  page407_i10
#ISCELL
  standard tap *
  page407_i100
#ISCELL
  standard tap *
  page407_i101
#CELL
  pure_quanta q_cap_diffbus *
  page407_i102
#CELL
  pure_quanta q_cap_diffbus *
  page407_i103
#CELL
  pure_quanta q_cap_diffbus *
  page407_i104
#CELL
  pure_quanta q_cap_diffbus *
  page407_i105
#ISCELL
  standard tap *
  page407_i106
#ISCELL
  standard tap *
  page407_i107
#ISCELL
  standard tap *
  page407_i108
#ISCELL
  standard tap *
  page407_i109
#ISCELL
  standard tap *
  page407_i11
#ISCELL
  standard tap *
  page407_i110
#ISCELL
  standard tap *
  page407_i111
#ISCELL
  standard tap *
  page407_i112
#ISCELL
  standard tap *
  page407_i113
#ISCELL
  standard tap *
  page407_i114
#ISCELL
  standard tap *
  page407_i115
#ISCELL
  standard tap *
  page407_i116
#ISCELL
  standard tap *
  page407_i117
#ISCELL
  standard tap *
  page407_i118
#ISCELL
  standard tap *
  page407_i119
#ISCELL
  standard tap *
  page407_i12
#ISCELL
  standard tap *
  page407_i120
#ISCELL
  standard tap *
  page407_i121
#ISCELL
  standard tap *
  page407_i122
#ISCELL
  standard tap *
  page407_i123
#ISCELL
  standard tap *
  page407_i124
#ISCELL
  standard tap *
  page407_i125
#ISCELL
  standard offpage *
  page407_i126
#ISCELL
  standard offpage *
  page407_i127
#ISCELL
  standard tap *
  page407_i128
#ISCELL
  standard tap *
  page407_i129
#ISCELL
  standard tap *
  page407_i13
#ISCELL
  standard tap *
  page407_i130
#ISCELL
  standard tap *
  page407_i131
#ISCELL
  standard tap *
  page407_i132
#ISCELL
  standard tap *
  page407_i133
#ISCELL
  standard tap *
  page407_i134
#ISCELL
  standard tap *
  page407_i135
#ISCELL
  standard tap *
  page407_i136
#ISCELL
  standard tap *
  page407_i137
#ISCELL
  standard tap *
  page407_i138
#ISCELL
  standard tap *
  page407_i139
#ISCELL
  standard tap *
  page407_i14
#ISCELL
  standard offpage *
  page407_i140
#ISCELL
  standard offpage *
  page407_i141
#CELL
  pure_quanta pt5161lrs *
  page407_i142
#CELL
  pure_quanta q_cap_diffbus *
  page407_i15
#CELL
  pure_quanta q_cap_diffbus *
  page407_i16
#ISCELL
  standard tap *
  page407_i17
#CELL
  pure_quanta q_cap_diffbus *
  page407_i18
#CELL
  pure_quanta q_cap_diffbus *
  page407_i19
#ISCELL
  standard offpage *
  page407_i2
#CELL
  pure_quanta q_cap_diffbus *
  page407_i20
#CELL
  pure_quanta q_cap_diffbus *
  page407_i21
#CELL
  pure_quanta q_cap_diffbus *
  page407_i22
#CELL
  pure_quanta q_cap_diffbus *
  page407_i23
#CELL
  pure_quanta q_cap_diffbus *
  page407_i24
#CELL
  pure_quanta q_cap_diffbus *
  page407_i25
#CELL
  pure_quanta q_cap_diffbus *
  page407_i26
#CELL
  pure_quanta q_cap_diffbus *
  page407_i27
#ISCELL
  standard tap *
  page407_i28
#ISCELL
  standard tap *
  page407_i29
#ISCELL
  standard tap *
  page407_i3
#ISCELL
  standard tap *
  page407_i30
#ISCELL
  standard tap *
  page407_i31
#ISCELL
  standard tap *
  page407_i32
#ISCELL
  standard tap *
  page407_i33
#ISCELL
  standard tap *
  page407_i34
#ISCELL
  standard tap *
  page407_i35
#ISCELL
  standard tap *
  page407_i36
#ISCELL
  standard tap *
  page407_i37
#ISCELL
  standard tap *
  page407_i38
#ISCELL
  standard tap *
  page407_i39
#ISCELL
  standard tap *
  page407_i4
#ISCELL
  standard tap *
  page407_i40
#ISCELL
  standard tap *
  page407_i41
#ISCELL
  standard tap *
  page407_i42
#CELL
  pure_quanta pt5161lrs *
  page407_i43
#CELL
  pure_quanta q_cap_diffbus *
  page407_i44
#CELL
  pure_quanta q_cap_diffbus *
  page407_i45
#CELL
  pure_quanta q_cap_diffbus *
  page407_i46
#CELL
  pure_quanta q_cap_diffbus *
  page407_i47
#ISCELL
  standard tap *
  page407_i48
#ISCELL
  standard tap *
  page407_i49
#ISCELL
  standard tap *
  page407_i5
#ISCELL
  standard tap *
  page407_i50
#ISCELL
  standard tap *
  page407_i51
#ISCELL
  standard tap *
  page407_i52
#ISCELL
  standard tap *
  page407_i53
#ISCELL
  standard tap *
  page407_i54
#ISCELL
  standard tap *
  page407_i55
#ISCELL
  standard offpage *
  page407_i56
#ISCELL
  standard offpage *
  page407_i57
#ISCELL
  standard offpage *
  page407_i58
#ISCELL
  standard offpage *
  page407_i59
#ISCELL
  standard tap *
  page407_i6
#ISCELL
  standard tap *
  page407_i60
#ISCELL
  standard tap *
  page407_i61
#ISCELL
  standard tap *
  page407_i62
#ISCELL
  standard tap *
  page407_i63
#ISCELL
  standard tap *
  page407_i64
#ISCELL
  standard tap *
  page407_i65
#ISCELL
  standard tap *
  page407_i66
#ISCELL
  standard tap *
  page407_i67
#ISCELL
  standard tap *
  page407_i68
#ISCELL
  standard tap *
  page407_i69
#ISCELL
  standard tap *
  page407_i7
#ISCELL
  standard tap *
  page407_i70
#ISCELL
  standard tap *
  page407_i71
#ISCELL
  standard offpage *
  page407_i72
#ISCELL
  standard offpage *
  page407_i73
#ISCELL
  standard tap *
  page407_i74
#ISCELL
  standard tap *
  page407_i75
#ISCELL
  standard tap *
  page407_i76
#ISCELL
  standard tap *
  page407_i77
#ISCELL
  standard tap *
  page407_i78
#ISCELL
  standard tap *
  page407_i79
#ISCELL
  standard tap *
  page407_i8
#ISCELL
  standard tap *
  page407_i80
#ISCELL
  standard tap *
  page407_i81
#ISCELL
  standard tap *
  page407_i82
#ISCELL
  standard tap *
  page407_i83
#ISCELL
  standard tap *
  page407_i84
#ISCELL
  standard tap *
  page407_i85
#CELL
  pure_quanta q_cap_diffbus *
  page407_i86
#CELL
  pure_quanta q_cap_diffbus *
  page407_i87
#CELL
  pure_quanta q_cap_diffbus *
  page407_i88
#CELL
  pure_quanta q_cap_diffbus *
  page407_i89
#ISCELL
  standard tap *
  page407_i9
#CELL
  pure_quanta q_cap_diffbus *
  page407_i90
#CELL
  pure_quanta q_cap_diffbus *
  page407_i91
#CELL
  pure_quanta q_cap_diffbus *
  page407_i92
#CELL
  pure_quanta q_cap_diffbus *
  page407_i93
#CELL
  pure_quanta q_cap_diffbus *
  page407_i94
#CELL
  pure_quanta q_cap_diffbus *
  page407_i95
#CELL
  pure_quanta q_cap_diffbus *
  page407_i96
#CELL
  pure_quanta q_cap_diffbus *
  page407_i97
#ISCELL
  standard tap *
  page407_i98
#ISCELL
  standard tap *
  page407_i99
#ISCELL
  mstr_misc dns *
  *
#ISCELL
  pure_quanta quanta_title_block_c *
  *
#ISCELL
  standard offpage *
  page408_i1
#CELL
  pure_quanta q_res *
  page408_i10
#ISCELL
  pure_quanta_power p1v0 *
  page408_i100
#ISCELL
  standard offpage *
  page408_i101
#CELL
  pure_quanta q_res *
  page408_i102
#ISCELL
  standard offpage *
  page408_i103
#ISCELL
  standard offpage *
  page408_i105
#ISCELL
  standard offpage *
  page408_i106
#ISCELL
  standard offpage *
  page408_i107
#CELL
  pure_quanta q_res *
  page408_i11
#CELL
  pure_quanta q_res *
  page408_i115
#CELL
  pure_quanta q_res *
  page408_i116
#CELL
  pure_quanta q_res *
  page408_i119
#ISCELL
  pure_quanta_power p1v0 *
  page408_i12
#ISCELL
  pure_quanta_power gnd *
  page408_i120
#CELL
  pure_quanta q_res *
  page408_i121
#CELL
  pure_quanta q_res *
  page408_i122
#ISCELL
  pure_quanta_power p1v0 *
  page408_i123
#ISCELL
  standard offpage *
  page408_i124
#ISCELL
  standard offpage *
  page408_i125
#ISCELL
  standard offpage *
  page408_i126
#ISCELL
  standard offpage *
  page408_i127
#ISCELL
  standard offpage *
  page408_i13
#ISCELL
  standard offpage *
  page408_i14
#CELL
  pure_quanta q_res *
  page408_i15
#ISCELL
  pure_quanta_power universal_gnd *
  page408_i16
#ISCELL
  pure_quanta_power universal_gnd *
  page408_i17
#CELL
  pure_quanta q_res *
  page408_i18
#CELL
  pure_quanta q_res *
  page408_i19
#ISCELL
  standard offpage *
  page408_i2
#CELL
  pure_quanta q_res *
  page408_i20
#CELL
  pure_quanta q_res *
  page408_i21
#CELL
  pure_quanta q_res *
  page408_i22
#ISCELL
  standard offpage *
  page408_i23
#ISCELL
  standard offpage *
  page408_i24
#ISCELL
  standard offpage *
  page408_i25
#ISCELL
  standard offpage *
  page408_i26
#ISCELL
  standard offpage *
  page408_i27
#ISCELL
  standard offpage *
  page408_i28
#CELL
  pure_quanta q_res *
  page408_i29
#ISCELL
  pure_quanta_power universal_gnd *
  page408_i3
#CELL
  pure_quanta q_res *
  page408_i30
#ISCELL
  standard offpage *
  page408_i31
#ISCELL
  standard offpage *
  page408_i32
#ISCELL
  standard offpage *
  page408_i33
#ISCELL
  standard offpage *
  page408_i34
#ISCELL
  standard offpage *
  page408_i35
#CELL
  pure_quanta q_res *
  page408_i36
#CELL
  pure_quanta q_res *
  page408_i37
#ISCELL
  pure_quanta_power universal_gnd *
  page408_i38
#CELL
  pure_quanta q_res *
  page408_i39
#CELL
  pure_quanta q_res *
  page408_i40
#CELL
  pure_quanta q_res *
  page408_i41
#CELL
  pure_quanta q_res *
  page408_i42
#ISCELL
  standard offpage *
  page408_i43
#ISCELL
  standard offpage *
  page408_i44
#ISCELL
  standard offpage *
  page408_i45
#ISCELL
  standard offpage *
  page408_i46
#ISCELL
  standard offpage *
  page408_i47
#ISCELL
  standard offpage *
  page408_i48
#ISCELL
  pure_quanta_power universal_gnd *
  page408_i49
#CELL
  pure_quanta q_res *
  page408_i5
#CELL
  pure_quanta q_res *
  page408_i50
#CELL
  pure_quanta q_res *
  page408_i51
#ISCELL
  standard offpage *
  page408_i52
#ISCELL
  pure_quanta_power p1v0 *
  page408_i53
#ISCELL
  pure_quanta_power universal_gnd *
  page408_i54
#CELL
  pure_quanta q_res *
  page408_i55
#CELL
  pure_quanta q_res *
  page408_i56
#ISCELL
  standard offpage *
  page408_i58
#ISCELL
  standard offpage *
  page408_i59
#ISCELL
  pure_quanta_power p1v0 *
  page408_i6
#ISCELL
  standard offpage *
  page408_i61
#ISCELL
  standard offpage *
  page408_i62
#ISCELL
  pure_quanta_power universal_gnd *
  page408_i63
#CELL
  pure_quanta q_res *
  page408_i64
#CELL
  pure_quanta q_res *
  page408_i65
#CELL
  pure_quanta q_res *
  page408_i66
#CELL
  pure_quanta q_res *
  page408_i67
#CELL
  pure_quanta q_res *
  page408_i68
#CELL
  pure_quanta q_res *
  page408_i69
#CELL
  pure_quanta q_res *
  page408_i7
#ISCELL
  pure_quanta_power p1v0 *
  page408_i70
#ISCELL
  pure_quanta_power gnd *
  page408_i71
#ISCELL
  pure_quanta_power gnd *
  page408_i72
#CELL
  pure_quanta q_res *
  page408_i73
#CELL
  pure_quanta q_res *
  page408_i74
#ISCELL
  standard offpage *
  page408_i75
#ISCELL
  standard offpage *
  page408_i76
#ISCELL
  standard offpage *
  page408_i77
#CELL
  pure_quanta q_res *
  page408_i78
#ISCELL
  standard offpage *
  page408_i79
#CELL
  pure_quanta q_res *
  page408_i8
#ISCELL
  standard offpage *
  page408_i80
#ISCELL
  pure_quanta_power p1v0 *
  page408_i81
#ISCELL
  standard offpage *
  page408_i82
#CELL
  pure_quanta pt5161lrs *
  page408_i83
#CELL
  pure_quanta q_res *
  page408_i84
#ISCELL
  pure_quanta_power universal_gnd *
  page408_i88
#CELL
  pure_quanta q_res *
  page408_i9
#CELL
  pure_quanta q_res *
  page408_i94
#ISCELL
  pure_quanta_power universal_gnd *
  page408_i95
#ISCELL
  standard offpage *
  page408_i96
#ISCELL
  pure_quanta_power gnd *
  page408_i97
#CELL
  pure_quanta q_res *
  page408_i98
#CELL
  pure_quanta q_res *
  page408_i99
#ISCELL
  mstr_misc dns *
  *
#ISCELL
  pure_quanta quanta_title_block_c *
  *
#ISCELL
  pure_quanta_power vcc_core *
  page409_i10
#ISCELL
  pure_quanta_power universal_gnd *
  page409_i11
#ISCELL
  pure_quanta_power universal_gnd *
  page409_i12
#CELL
  pure_quanta q_res *
  page409_i13
#ISCELL
  pure_quanta_power universal_gnd *
  page409_i14
#CELL
  pure_quanta q_res *
  page409_i15
#ISCELL
  pure_quanta_power universal_gnd *
  page409_i16
#CELL
  pure_quanta pt5161lrs *
  page409_i17
#CELL
  pure_quanta q_res *
  page409_i18
#CELL
  pure_quanta q_res *
  page409_i19
#ISCELL
  pure_quanta_power p1v0 *
  page409_i2
#ISCELL
  pure_quanta_power universal_gnd *
  page409_i3
#CELL
  pure_quanta pt5161lrs *
  page409_i5
#ISCELL
  pure_quanta_power p1v0 *
  page409_i6
#ISCELL
  pure_quanta_power p1v0 *
  page409_i7
#ISCELL
  pure_quanta_power p1v0 *
  page409_i8
#ISCELL
  pure_quanta_power vcc_core *
  page409_i9
#ISCELL
  pure_quanta quanta_title_block_c *
  *
#ISCELL
  standard offpage *
  page410_i1
#ISCELL
  standard offpage *
  page410_i2
#CELL
  pure_quanta q_res *
  page410_i20
#ISCELL
  pure_quanta_power universal_gnd *
  page410_i21
#ISCELL
  pure_quanta_power universal_gnd *
  page410_i22
#ISCELL
  pure_quanta_power p1v0 *
  page410_i23
#CELL
  pure_quanta q_cap *
  page410_i24
#ISCELL
  pure_quanta_power universal_gnd *
  page410_i25
#ISCELL
  pure_quanta_power universal_gnd *
  page410_i26
#CELL
  pure_quanta m24m02drmn6tp *
  page410_i5
#CELL
  pure_quanta q_res *
  page410_i6
#CELL
  pure_quanta q_res *
  page410_i7
#ISCELL
  mstr_misc dns *
  *
#ISCELL
  pure_quanta quanta_title_block_c *
  *
#ISCELL
  pure_quanta_power cad_note *
  *
#CELL
  pure_quanta q_res *
  page411_i10
#CELL
  pure_quanta q_inductor *
  page411_i11
#CELL
  pure_quanta q_cap *
  page411_i12
#ISCELL
  pure_quanta_power p1v0 *
  page411_i13
#ISCELL
  pure_quanta_power p1v0 *
  page411_i14
#CELL
  pure_quanta q_cap *
  page411_i15
#CELL
  pure_quanta q_cap *
  page411_i16
#CELL
  pure_quanta q_cap *
  page411_i17
#CELL
  pure_quanta q_cap *
  page411_i18
#CELL
  pure_quanta q_cap *
  page411_i19
#CELL
  pure_quanta q_res *
  page411_i2
#CELL
  pure_quanta q_cap *
  page411_i20
#CELL
  pure_quanta q_cap *
  page411_i21
#CELL
  pure_quanta q_cap *
  page411_i22
#ISCELL
  pure_quanta_power universal_gnd *
  page411_i23
#CELL
  pure_quanta q_cap *
  page411_i24
#CELL
  pure_quanta q_cap *
  page411_i25
#CELL
  pure_quanta q_cap *
  page411_i26
#CELL
  pure_quanta q_cap *
  page411_i27
#CELL
  pure_quanta q_cap *
  page411_i28
#ISCELL
  pure_quanta_power vcc_core *
  page411_i29
#ISCELL
  pure_quanta_power vcc_core *
  page411_i30
#ISCELL
  pure_quanta_power universal_gnd *
  page411_i31
#CELL
  pure_quanta q_cap *
  page411_i32
#CELL
  pure_quanta q_cap *
  page411_i34
#CELL
  pure_quanta q_res *
  page411_i36
#CELL
  pure_quanta q_cap *
  page411_i37
#CELL
  pure_quanta q_cap *
  page411_i38
#CELL
  pure_quanta q_cap *
  page411_i39
#CELL
  pure_quanta q_res *
  page411_i4
#CELL
  pure_quanta q_cap *
  page411_i40
#CELL
  pure_quanta q_cap *
  page411_i41
#CELL
  pure_quanta q_cap *
  page411_i42
#CELL
  pure_quanta q_cap *
  page411_i43
#CELL
  pure_quanta q_cap *
  page411_i44
#CELL
  pure_quanta q_cap *
  page411_i45
#CELL
  pure_quanta q_cap *
  page411_i46
#CELL
  pure_quanta q_cap *
  page411_i47
#CELL
  pure_quanta q_cap *
  page411_i48
#CELL
  pure_quanta q_cap *
  page411_i49
#CELL
  pure_quanta q_cap *
  page411_i5
#CELL
  pure_quanta q_cap *
  page411_i50
#CELL
  pure_quanta q_cap *
  page411_i51
#CELL
  pure_quanta q_cap *
  page411_i52
#CELL
  pure_quanta q_cap *
  page411_i53
#ISCELL
  pure_quanta_power universal_gnd *
  page411_i54
#CELL
  pure_quanta q_cap *
  page411_i55
#CELL
  pure_quanta q_cap *
  page411_i58
#CELL
  pure_quanta q_cap *
  page411_i59
#ISCELL
  pure_quanta_power universal_gnd *
  page411_i6
#CELL
  pure_quanta q_cap *
  page411_i61
#ISCELL
  pure_quanta_power universal_gnd *
  page411_i62
#CELL
  pure_quanta q_inductor *
  page411_i63
#CELL
  pure_quanta q_cap *
  page411_i64
#CELL
  pure_quanta q_cap *
  page411_i65
#ISCELL
  pure_quanta_power vcc_core *
  page411_i66
#CELL
  pure_quanta q_cap *
  page411_i67
#CELL
  pure_quanta q_cap *
  page411_i68
#CELL
  pure_quanta q_cap *
  page411_i69
#CELL
  pure_quanta q_cap *
  page411_i7
#CELL
  pure_quanta q_cap *
  page411_i70
#CELL
  pure_quanta q_cap *
  page411_i71
#CELL
  pure_quanta q_cap *
  page411_i72
#CELL
  pure_quanta q_cap *
  page411_i73
#CELL
  pure_quanta q_cap *
  page411_i74
#CELL
  pure_quanta q_cap *
  page411_i75
#CELL
  pure_quanta q_cap *
  page411_i76
#CELL
  pure_quanta q_cap *
  page411_i77
#CELL
  pure_quanta q_cap *
  page411_i78
#CELL
  pure_quanta q_cap *
  page411_i79
#ISCELL
  pure_quanta_power p1v0 *
  page411_i8
#ISCELL
  pure_quanta_power universal_gnd *
  page411_i80
#CELL
  pure_quanta q_cap *
  page411_i81
#CELL
  pure_quanta q_cap *
  page411_i82
#CELL
  pure_quanta q_cap *
  page411_i83
#CELL
  pure_quanta q_cap *
  page411_i84
#CELL
  pure_quanta q_cap *
  page411_i85
#CELL
  pure_quanta q_cap *
  page411_i86
#CELL
  pure_quanta q_cap *
  page411_i87
#CELL
  pure_quanta q_inductor *
  page411_i88
#CELL
  pure_quanta q_res *
  page411_i89
#ISCELL
  pure_quanta_power universal_gnd *
  page411_i9
#CELL
  pure_quanta q_cap *
  page411_i90
#CELL
  pure_quanta q_cap *
  page411_i91
#CELL
  pure_quanta q_cap *
  page411_i92
#CELL
  pure_quanta q_cap *
  page411_i93
#CELL
  pure_quanta q_cap *
  page411_i94
#CELL
  pure_quanta q_capp *
  page411_i95
#CELL
  pure_quanta q_capp *
  page411_i96
#CELL
  pure_quanta q_cap *
  page411_i97
#ISCELL
  pure_quanta quanta_title_block_c *
  *
#ISCELL
  pure_quanta quanta_title_block_c *
  *
#ISCELL
  pure_quanta quanta_title_block_c *
  *
#ISCELL
  pure_quanta quanta_title_block_c *
  *
#ISCELL
  standard tap *
  page415_i1
#ISCELL
  standard tap *
  page415_i10
#ISCELL
  standard tap *
  page415_i11
#ISCELL
  standard tap *
  page415_i12
#ISCELL
  standard tap *
  page415_i13
#ISCELL
  standard tap *
  page415_i14
#ISCELL
  standard tap *
  page415_i15
#ISCELL
  standard tap *
  page415_i16
#ISCELL
  standard offpage *
  page415_i17
#ISCELL
  standard offpage *
  page415_i18
#ISCELL
  standard tap *
  page415_i19
#ISCELL
  standard tap *
  page415_i2
#ISCELL
  standard tap *
  page415_i20
#ISCELL
  standard tap *
  page415_i21
#ISCELL
  standard tap *
  page415_i22
#ISCELL
  standard tap *
  page415_i23
#ISCELL
  standard tap *
  page415_i24
#ISCELL
  standard tap *
  page415_i25
#ISCELL
  standard tap *
  page415_i26
#ISCELL
  standard tap *
  page415_i27
#ISCELL
  standard tap *
  page415_i28
#ISCELL
  standard tap *
  page415_i29
#ISCELL
  standard tap *
  page415_i3
#ISCELL
  standard tap *
  page415_i30
#ISCELL
  standard tap *
  page415_i31
#ISCELL
  standard tap *
  page415_i32
#ISCELL
  standard tap *
  page415_i33
#ISCELL
  standard tap *
  page415_i34
#ISCELL
  standard offpage *
  page415_i35
#ISCELL
  standard offpage *
  page415_i36
#CELL
  pure_quanta pt5161lrs *
  page415_i37
#CELL
  pure_quanta pt5161lrs *
  page415_i38
#ISCELL
  standard tap *
  page415_i4
#ISCELL
  standard tap *
  page415_i5
#ISCELL
  standard tap *
  page415_i6
#ISCELL
  standard tap *
  page415_i7
#ISCELL
  standard tap *
  page415_i8
#ISCELL
  standard tap *
  page415_i9
#ISCELL
  pure_quanta quanta_title_block_c *
  *
#CELL
  pure_quanta pt5161lrs *
  page416_i1
#ISCELL
  standard tap *
  page416_i10
#ISCELL
  standard tap *
  page416_i11
#ISCELL
  standard tap *
  page416_i12
#ISCELL
  standard tap *
  page416_i13
#ISCELL
  standard tap *
  page416_i14
#ISCELL
  standard tap *
  page416_i15
#ISCELL
  standard tap *
  page416_i16
#ISCELL
  standard tap *
  page416_i17
#ISCELL
  standard offpage *
  page416_i18
#ISCELL
  standard offpage *
  page416_i19
#ISCELL
  standard tap *
  page416_i2
#ISCELL
  standard tap *
  page416_i20
#ISCELL
  standard tap *
  page416_i21
#ISCELL
  standard tap *
  page416_i22
#ISCELL
  standard tap *
  page416_i23
#ISCELL
  standard tap *
  page416_i24
#ISCELL
  standard tap *
  page416_i25
#ISCELL
  standard tap *
  page416_i26
#ISCELL
  standard tap *
  page416_i27
#ISCELL
  standard tap *
  page416_i28
#ISCELL
  standard tap *
  page416_i29
#ISCELL
  standard tap *
  page416_i3
#ISCELL
  standard tap *
  page416_i30
#ISCELL
  standard tap *
  page416_i31
#ISCELL
  standard tap *
  page416_i32
#ISCELL
  standard tap *
  page416_i33
#ISCELL
  standard tap *
  page416_i34
#ISCELL
  standard tap *
  page416_i35
#ISCELL
  standard offpage *
  page416_i36
#ISCELL
  standard offpage *
  page416_i37
#CELL
  pure_quanta pt5161lrs *
  page416_i38
#ISCELL
  standard tap *
  page416_i4
#ISCELL
  standard tap *
  page416_i5
#ISCELL
  standard tap *
  page416_i6
#ISCELL
  standard tap *
  page416_i7
#ISCELL
  standard tap *
  page416_i8
#ISCELL
  standard tap *
  page416_i9
#ISCELL
  pure_quanta quanta_title_block_c *
  *
#CELL
  pure_quanta pt5161lrs *
  page417_i1
#ISCELL
  standard tap *
  page417_i10
#ISCELL
  standard tap *
  page417_i11
#ISCELL
  standard tap *
  page417_i12
#ISCELL
  standard tap *
  page417_i13
#ISCELL
  standard tap *
  page417_i14
#ISCELL
  standard tap *
  page417_i15
#ISCELL
  standard tap *
  page417_i16
#ISCELL
  standard tap *
  page417_i17
#ISCELL
  standard offpage *
  page417_i18
#ISCELL
  standard offpage *
  page417_i19
#ISCELL
  standard tap *
  page417_i2
#ISCELL
  standard tap *
  page417_i20
#ISCELL
  standard tap *
  page417_i21
#ISCELL
  standard tap *
  page417_i22
#ISCELL
  standard tap *
  page417_i23
#ISCELL
  standard tap *
  page417_i24
#ISCELL
  standard tap *
  page417_i25
#ISCELL
  standard tap *
  page417_i26
#ISCELL
  standard tap *
  page417_i27
#ISCELL
  standard tap *
  page417_i28
#ISCELL
  standard tap *
  page417_i29
#ISCELL
  standard tap *
  page417_i3
#ISCELL
  standard tap *
  page417_i30
#ISCELL
  standard tap *
  page417_i31
#ISCELL
  standard tap *
  page417_i32
#ISCELL
  standard tap *
  page417_i33
#ISCELL
  standard tap *
  page417_i34
#ISCELL
  standard tap *
  page417_i35
#ISCELL
  standard offpage *
  page417_i36
#ISCELL
  standard offpage *
  page417_i37
#CELL
  pure_quanta pt5161lrs *
  page417_i38
#ISCELL
  standard tap *
  page417_i4
#ISCELL
  standard tap *
  page417_i5
#ISCELL
  standard tap *
  page417_i6
#ISCELL
  standard tap *
  page417_i7
#ISCELL
  standard tap *
  page417_i8
#ISCELL
  standard tap *
  page417_i9
#ISCELL
  pure_quanta quanta_title_block_c *
  *
#ISCELL
  standard offpage *
  page418_i1
#ISCELL
  standard tap *
  page418_i10
#CELL
  pure_quanta q_cap_diffbus *
  page418_i100
#CELL
  pure_quanta q_cap_diffbus *
  page418_i101
#ISCELL
  standard tap *
  page418_i102
#ISCELL
  standard tap *
  page418_i103
#CELL
  pure_quanta q_cap_diffbus *
  page418_i104
#CELL
  pure_quanta q_cap_diffbus *
  page418_i105
#ISCELL
  standard tap *
  page418_i106
#ISCELL
  standard tap *
  page418_i107
#ISCELL
  standard tap *
  page418_i108
#ISCELL
  standard tap *
  page418_i109
#ISCELL
  standard tap *
  page418_i11
#ISCELL
  standard tap *
  page418_i110
#ISCELL
  standard tap *
  page418_i111
#ISCELL
  standard tap *
  page418_i112
#ISCELL
  standard tap *
  page418_i113
#ISCELL
  standard tap *
  page418_i114
#ISCELL
  standard tap *
  page418_i115
#ISCELL
  standard tap *
  page418_i116
#ISCELL
  standard tap *
  page418_i117
#ISCELL
  standard tap *
  page418_i118
#ISCELL
  standard tap *
  page418_i119
#ISCELL
  standard tap *
  page418_i12
#ISCELL
  standard tap *
  page418_i120
#ISCELL
  standard tap *
  page418_i121
#ISCELL
  standard tap *
  page418_i122
#ISCELL
  standard tap *
  page418_i123
#ISCELL
  standard tap *
  page418_i124
#ISCELL
  standard tap *
  page418_i125
#ISCELL
  standard tap *
  page418_i126
#ISCELL
  standard tap *
  page418_i127
#ISCELL
  standard offpage *
  page418_i128
#ISCELL
  standard offpage *
  page418_i129
#ISCELL
  standard tap *
  page418_i13
#ISCELL
  standard tap *
  page418_i130
#ISCELL
  standard tap *
  page418_i131
#ISCELL
  standard tap *
  page418_i132
#ISCELL
  standard tap *
  page418_i133
#ISCELL
  standard tap *
  page418_i134
#ISCELL
  standard tap *
  page418_i135
#ISCELL
  standard tap *
  page418_i136
#ISCELL
  standard tap *
  page418_i137
#ISCELL
  standard tap *
  page418_i138
#ISCELL
  standard tap *
  page418_i139
#ISCELL
  standard tap *
  page418_i14
#ISCELL
  standard offpage *
  page418_i140
#ISCELL
  standard offpage *
  page418_i141
#CELL
  pure_quanta pt5161lrs *
  page418_i142
#ISCELL
  standard tap *
  page418_i15
#ISCELL
  standard tap *
  page418_i16
#CELL
  pure_quanta q_cap_diffbus *
  page418_i17
#CELL
  pure_quanta q_cap_diffbus *
  page418_i18
#CELL
  pure_quanta q_cap_diffbus *
  page418_i19
#ISCELL
  standard offpage *
  page418_i2
#CELL
  pure_quanta q_cap_diffbus *
  page418_i20
#ISCELL
  standard tap *
  page418_i21
#ISCELL
  standard tap *
  page418_i22
#ISCELL
  standard tap *
  page418_i23
#ISCELL
  standard tap *
  page418_i24
#CELL
  pure_quanta q_cap_diffbus *
  page418_i25
#CELL
  pure_quanta q_cap_diffbus *
  page418_i26
#CELL
  pure_quanta q_cap_diffbus *
  page418_i27
#CELL
  pure_quanta q_cap_diffbus *
  page418_i28
#CELL
  pure_quanta q_cap_diffbus *
  page418_i29
#ISCELL
  standard tap *
  page418_i3
#CELL
  pure_quanta q_cap_diffbus *
  page418_i30
#CELL
  pure_quanta q_cap_diffbus *
  page418_i31
#CELL
  pure_quanta q_cap_diffbus *
  page418_i32
#CELL
  pure_quanta q_cap_diffbus *
  page418_i33
#CELL
  pure_quanta q_cap_diffbus *
  page418_i34
#ISCELL
  standard tap *
  page418_i35
#ISCELL
  standard tap *
  page418_i36
#ISCELL
  standard tap *
  page418_i37
#ISCELL
  standard tap *
  page418_i38
#ISCELL
  standard tap *
  page418_i39
#ISCELL
  standard tap *
  page418_i4
#ISCELL
  standard tap *
  page418_i40
#ISCELL
  standard tap *
  page418_i41
#ISCELL
  standard tap *
  page418_i42
#ISCELL
  standard tap *
  page418_i43
#ISCELL
  standard tap *
  page418_i44
#ISCELL
  standard tap *
  page418_i45
#ISCELL
  standard tap *
  page418_i46
#CELL
  pure_quanta pt5161lrs *
  page418_i47
#CELL
  pure_quanta q_cap_diffbus *
  page418_i48
#CELL
  pure_quanta q_cap_diffbus *
  page418_i49
#ISCELL
  standard tap *
  page418_i5
#ISCELL
  standard tap *
  page418_i50
#ISCELL
  standard tap *
  page418_i51
#ISCELL
  standard tap *
  page418_i52
#ISCELL
  standard tap *
  page418_i53
#ISCELL
  standard tap *
  page418_i54
#ISCELL
  standard tap *
  page418_i55
#ISCELL
  standard tap *
  page418_i56
#ISCELL
  standard tap *
  page418_i57
#ISCELL
  standard offpage *
  page418_i58
#ISCELL
  standard offpage *
  page418_i59
#ISCELL
  standard tap *
  page418_i6
#ISCELL
  standard offpage *
  page418_i60
#ISCELL
  standard offpage *
  page418_i61
#ISCELL
  standard tap *
  page418_i62
#ISCELL
  standard tap *
  page418_i63
#ISCELL
  standard tap *
  page418_i64
#ISCELL
  standard tap *
  page418_i65
#ISCELL
  standard tap *
  page418_i66
#ISCELL
  standard tap *
  page418_i67
#ISCELL
  standard tap *
  page418_i68
#ISCELL
  standard tap *
  page418_i69
#ISCELL
  standard tap *
  page418_i7
#ISCELL
  standard tap *
  page418_i70
#ISCELL
  standard tap *
  page418_i71
#ISCELL
  standard offpage *
  page418_i72
#ISCELL
  standard offpage *
  page418_i73
#ISCELL
  standard tap *
  page418_i74
#ISCELL
  standard tap *
  page418_i75
#ISCELL
  standard tap *
  page418_i76
#ISCELL
  standard tap *
  page418_i77
#ISCELL
  standard tap *
  page418_i78
#ISCELL
  standard tap *
  page418_i79
#ISCELL
  standard tap *
  page418_i8
#ISCELL
  standard tap *
  page418_i80
#ISCELL
  standard tap *
  page418_i81
#ISCELL
  standard tap *
  page418_i82
#ISCELL
  standard tap *
  page418_i83
#ISCELL
  standard tap *
  page418_i84
#ISCELL
  standard tap *
  page418_i85
#ISCELL
  standard tap *
  page418_i86
#ISCELL
  standard tap *
  page418_i87
#CELL
  pure_quanta q_cap_diffbus *
  page418_i88
#CELL
  pure_quanta q_cap_diffbus *
  page418_i89
#ISCELL
  standard tap *
  page418_i9
#CELL
  pure_quanta q_cap_diffbus *
  page418_i90
#CELL
  pure_quanta q_cap_diffbus *
  page418_i91
#CELL
  pure_quanta q_cap_diffbus *
  page418_i92
#CELL
  pure_quanta q_cap_diffbus *
  page418_i93
#CELL
  pure_quanta q_cap_diffbus *
  page418_i94
#CELL
  pure_quanta q_cap_diffbus *
  page418_i95
#CELL
  pure_quanta q_cap_diffbus *
  page418_i96
#CELL
  pure_quanta q_cap_diffbus *
  page418_i97
#CELL
  pure_quanta q_cap_diffbus *
  page418_i98
#CELL
  pure_quanta q_cap_diffbus *
  page418_i99
#ISCELL
  mstr_misc dns *
  *
#ISCELL
  pure_quanta quanta_title_block_c *
  *
#ISCELL
  standard offpage *
  page419_i1
#CELL
  pure_quanta q_res *
  page419_i10
#ISCELL
  pure_quanta_power universal_gnd *
  page419_i100
#ISCELL
  standard offpage *
  page419_i101
#CELL
  pure_quanta q_res *
  page419_i102
#ISCELL
  standard offpage *
  page419_i103
#ISCELL
  standard offpage *
  page419_i105
#ISCELL
  standard offpage *
  page419_i106
#ISCELL
  standard offpage *
  page419_i107
#CELL
  pure_quanta q_res *
  page419_i11
#CELL
  pure_quanta q_res *
  page419_i116
#CELL
  pure_quanta q_res *
  page419_i117
#CELL
  pure_quanta q_res *
  page419_i118
#ISCELL
  pure_quanta_power gnd *
  page419_i119
#ISCELL
  pure_quanta_power p1v0 *
  page419_i12
#CELL
  pure_quanta q_res *
  page419_i120
#CELL
  pure_quanta q_res *
  page419_i121
#ISCELL
  pure_quanta_power p1v0 *
  page419_i122
#ISCELL
  standard offpage *
  page419_i125
#ISCELL
  standard offpage *
  page419_i126
#ISCELL
  standard offpage *
  page419_i127
#ISCELL
  standard offpage *
  page419_i128
#ISCELL
  standard offpage *
  page419_i13
#ISCELL
  standard offpage *
  page419_i14
#ISCELL
  pure_quanta_power universal_gnd *
  page419_i15
#ISCELL
  pure_quanta_power universal_gnd *
  page419_i16
#CELL
  pure_quanta q_res *
  page419_i17
#CELL
  pure_quanta q_res *
  page419_i18
#CELL
  pure_quanta q_res *
  page419_i19
#ISCELL
  standard offpage *
  page419_i2
#CELL
  pure_quanta q_res *
  page419_i20
#CELL
  pure_quanta q_res *
  page419_i21
#CELL
  pure_quanta q_res *
  page419_i22
#ISCELL
  standard offpage *
  page419_i23
#ISCELL
  standard offpage *
  page419_i24
#ISCELL
  standard offpage *
  page419_i25
#ISCELL
  standard offpage *
  page419_i26
#ISCELL
  standard offpage *
  page419_i27
#ISCELL
  standard offpage *
  page419_i28
#CELL
  pure_quanta q_res *
  page419_i29
#ISCELL
  pure_quanta_power universal_gnd *
  page419_i3
#CELL
  pure_quanta q_res *
  page419_i30
#ISCELL
  standard offpage *
  page419_i31
#ISCELL
  standard offpage *
  page419_i32
#ISCELL
  standard offpage *
  page419_i33
#ISCELL
  standard offpage *
  page419_i34
#ISCELL
  standard offpage *
  page419_i35
#CELL
  pure_quanta q_res *
  page419_i36
#CELL
  pure_quanta q_res *
  page419_i37
#ISCELL
  pure_quanta_power universal_gnd *
  page419_i38
#CELL
  pure_quanta q_res *
  page419_i39
#CELL
  pure_quanta q_res *
  page419_i40
#CELL
  pure_quanta q_res *
  page419_i41
#CELL
  pure_quanta q_res *
  page419_i42
#ISCELL
  standard offpage *
  page419_i43
#ISCELL
  standard offpage *
  page419_i44
#ISCELL
  standard offpage *
  page419_i45
#ISCELL
  standard offpage *
  page419_i46
#ISCELL
  standard offpage *
  page419_i47
#ISCELL
  standard offpage *
  page419_i48
#ISCELL
  pure_quanta_power universal_gnd *
  page419_i49
#CELL
  pure_quanta q_res *
  page419_i5
#CELL
  pure_quanta q_res *
  page419_i50
#CELL
  pure_quanta q_res *
  page419_i51
#ISCELL
  standard offpage *
  page419_i52
#ISCELL
  pure_quanta_power p1v0 *
  page419_i53
#ISCELL
  pure_quanta_power universal_gnd *
  page419_i54
#CELL
  pure_quanta q_res *
  page419_i55
#CELL
  pure_quanta q_res *
  page419_i56
#ISCELL
  standard offpage *
  page419_i58
#ISCELL
  standard offpage *
  page419_i59
#ISCELL
  pure_quanta_power p1v0 *
  page419_i6
#ISCELL
  standard offpage *
  page419_i60
#ISCELL
  standard offpage *
  page419_i62
#ISCELL
  standard offpage *
  page419_i63
#ISCELL
  pure_quanta_power universal_gnd *
  page419_i64
#CELL
  pure_quanta q_res *
  page419_i65
#CELL
  pure_quanta q_res *
  page419_i66
#CELL
  pure_quanta q_res *
  page419_i67
#CELL
  pure_quanta q_res *
  page419_i68
#CELL
  pure_quanta q_res *
  page419_i69
#CELL
  pure_quanta q_res *
  page419_i7
#CELL
  pure_quanta q_res *
  page419_i70
#ISCELL
  pure_quanta_power p1v0 *
  page419_i71
#ISCELL
  pure_quanta_power gnd *
  page419_i72
#ISCELL
  pure_quanta_power gnd *
  page419_i73
#ISCELL
  standard offpage *
  page419_i74
#ISCELL
  standard offpage *
  page419_i75
#CELL
  pure_quanta q_res *
  page419_i76
#CELL
  pure_quanta q_res *
  page419_i77
#CELL
  pure_quanta q_res *
  page419_i78
#ISCELL
  standard offpage *
  page419_i79
#CELL
  pure_quanta q_res *
  page419_i8
#ISCELL
  standard offpage *
  page419_i80
#ISCELL
  pure_quanta_power p1v0 *
  page419_i81
#ISCELL
  standard offpage *
  page419_i82
#CELL
  pure_quanta pt5161lrs *
  page419_i83
#CELL
  pure_quanta q_res *
  page419_i84
#ISCELL
  pure_quanta_power universal_gnd *
  page419_i88
#CELL
  pure_quanta q_res *
  page419_i9
#ISCELL
  pure_quanta_power gnd *
  page419_i94
#CELL
  pure_quanta q_res *
  page419_i95
#CELL
  pure_quanta q_res *
  page419_i96
#ISCELL
  pure_quanta_power p1v0 *
  page419_i97
#ISCELL
  standard offpage *
  page419_i98
#CELL
  pure_quanta q_res *
  page419_i99
#ISCELL
  mstr_misc dns *
  *
#ISCELL
  pure_quanta quanta_title_block_c *
  *
#ISCELL
  pure_quanta_power vcc_core *
  page420_i10
#ISCELL
  pure_quanta_power universal_gnd *
  page420_i11
#ISCELL
  pure_quanta_power universal_gnd *
  page420_i12
#CELL
  pure_quanta q_res *
  page420_i13
#CELL
  pure_quanta q_res *
  page420_i14
#ISCELL
  pure_quanta_power universal_gnd *
  page420_i15
#ISCELL
  pure_quanta_power universal_gnd *
  page420_i16
#CELL
  pure_quanta pt5161lrs *
  page420_i17
#CELL
  pure_quanta q_res *
  page420_i18
#CELL
  pure_quanta q_res *
  page420_i19
#ISCELL
  pure_quanta_power p1v0 *
  page420_i2
#ISCELL
  pure_quanta_power p1v0 *
  page420_i3
#ISCELL
  pure_quanta_power universal_gnd *
  page420_i4
#CELL
  pure_quanta pt5161lrs *
  page420_i6
#ISCELL
  pure_quanta_power p1v0 *
  page420_i7
#ISCELL
  pure_quanta_power p1v0 *
  page420_i8
#ISCELL
  pure_quanta_power vcc_core *
  page420_i9
#ISCELL
  pure_quanta quanta_title_block_c *
  *
#ISCELL
  standard offpage *
  page421_i1
#CELL
  pure_quanta q_res *
  page421_i18
#ISCELL
  pure_quanta_power universal_gnd *
  page421_i19
#ISCELL
  standard offpage *
  page421_i2
#ISCELL
  pure_quanta_power universal_gnd *
  page421_i20
#ISCELL
  pure_quanta_power universal_gnd *
  page421_i21
#ISCELL
  pure_quanta_power p1v0 *
  page421_i22
#CELL
  pure_quanta q_cap *
  page421_i23
#ISCELL
  pure_quanta_power universal_gnd *
  page421_i24
#CELL
  pure_quanta q_res *
  page421_i3
#CELL
  pure_quanta q_res *
  page421_i4
#CELL
  pure_quanta m24m02drmn6tp *
  page421_i5
#ISCELL
  mstr_misc dns *
  *
#ISCELL
  pure_quanta quanta_title_block_c *
  *
#ISCELL
  pure_quanta_power cad_note *
  *
#CELL
  pure_quanta q_cap *
  page422_i10
#ISCELL
  pure_quanta_power p1v0 *
  page422_i11
#CELL
  pure_quanta q_cap *
  page422_i12
#CELL
  pure_quanta q_cap *
  page422_i13
#ISCELL
  pure_quanta_power universal_gnd *
  page422_i14
#CELL
  pure_quanta q_cap *
  page422_i15
#CELL
  pure_quanta q_cap *
  page422_i16
#CELL
  pure_quanta q_cap *
  page422_i17
#CELL
  pure_quanta q_cap *
  page422_i18
#CELL
  pure_quanta q_cap *
  page422_i19
#CELL
  pure_quanta q_cap *
  page422_i20
#CELL
  pure_quanta q_res *
  page422_i21
#CELL
  pure_quanta q_res *
  page422_i22
#CELL
  pure_quanta q_inductor *
  page422_i23
#ISCELL
  pure_quanta_power p1v0 *
  page422_i24
#CELL
  pure_quanta q_cap *
  page422_i25
#CELL
  pure_quanta q_cap *
  page422_i26
#CELL
  pure_quanta q_cap *
  page422_i27
#ISCELL
  pure_quanta_power universal_gnd *
  page422_i28
#CELL
  pure_quanta q_cap *
  page422_i29
#ISCELL
  pure_quanta_power p1v0 *
  page422_i3
#CELL
  pure_quanta q_inductor *
  page422_i30
#ISCELL
  pure_quanta_power vcc_core *
  page422_i31
#ISCELL
  pure_quanta_power vcc_core *
  page422_i33
#CELL
  pure_quanta q_cap *
  page422_i34
#CELL
  pure_quanta q_cap *
  page422_i35
#CELL
  pure_quanta q_cap *
  page422_i36
#ISCELL
  pure_quanta_power universal_gnd *
  page422_i38
#CELL
  pure_quanta q_cap *
  page422_i39
#CELL
  pure_quanta q_res *
  page422_i4
#CELL
  pure_quanta q_cap *
  page422_i40
#CELL
  pure_quanta q_cap *
  page422_i41
#CELL
  pure_quanta q_cap *
  page422_i42
#CELL
  pure_quanta q_cap *
  page422_i43
#CELL
  pure_quanta q_cap *
  page422_i44
#CELL
  pure_quanta q_cap *
  page422_i45
#CELL
  pure_quanta q_cap *
  page422_i46
#CELL
  pure_quanta q_cap *
  page422_i47
#CELL
  pure_quanta q_cap *
  page422_i48
#CELL
  pure_quanta q_cap *
  page422_i49
#CELL
  pure_quanta q_res *
  page422_i5
#CELL
  pure_quanta q_cap *
  page422_i50
#CELL
  pure_quanta q_cap *
  page422_i51
#CELL
  pure_quanta q_cap *
  page422_i52
#CELL
  pure_quanta q_cap *
  page422_i54
#CELL
  pure_quanta q_cap *
  page422_i55
#CELL
  pure_quanta q_cap *
  page422_i56
#CELL
  pure_quanta q_cap *
  page422_i57
#CELL
  pure_quanta q_cap *
  page422_i58
#CELL
  pure_quanta q_cap *
  page422_i59
#CELL
  pure_quanta q_cap *
  page422_i6
#CELL
  pure_quanta q_cap *
  page422_i60
#CELL
  pure_quanta q_cap *
  page422_i61
#CELL
  pure_quanta q_cap *
  page422_i62
#CELL
  pure_quanta q_cap *
  page422_i63
#CELL
  pure_quanta q_cap *
  page422_i64
#CELL
  pure_quanta q_cap *
  page422_i65
#CELL
  pure_quanta q_cap *
  page422_i66
#ISCELL
  pure_quanta_power universal_gnd *
  page422_i67
#CELL
  pure_quanta q_cap *
  page422_i68
#CELL
  pure_quanta q_cap *
  page422_i69
#CELL
  pure_quanta q_cap *
  page422_i7
#ISCELL
  pure_quanta_power universal_gnd *
  page422_i71
#CELL
  pure_quanta q_cap *
  page422_i72
#CELL
  pure_quanta q_cap *
  page422_i73
#CELL
  pure_quanta q_cap *
  page422_i74
#CELL
  pure_quanta q_cap *
  page422_i75
#ISCELL
  pure_quanta_power vcc_core *
  page422_i76
#CELL
  pure_quanta q_cap *
  page422_i77
#CELL
  pure_quanta q_cap *
  page422_i78
#CELL
  pure_quanta q_cap *
  page422_i79
#ISCELL
  pure_quanta_power universal_gnd *
  page422_i8
#CELL
  pure_quanta q_cap *
  page422_i80
#CELL
  pure_quanta q_cap *
  page422_i81
#CELL
  pure_quanta q_cap *
  page422_i82
#CELL
  pure_quanta q_cap *
  page422_i83
#CELL
  pure_quanta q_cap *
  page422_i84
#ISCELL
  pure_quanta_power universal_gnd *
  page422_i85
#CELL
  pure_quanta q_cap *
  page422_i86
#CELL
  pure_quanta q_cap *
  page422_i87
#CELL
  pure_quanta q_inductor *
  page422_i88
#CELL
  pure_quanta q_res *
  page422_i89
#CELL
  pure_quanta q_cap *
  page422_i9
#CELL
  pure_quanta q_cap *
  page422_i90
#CELL
  pure_quanta q_cap *
  page422_i91
#CELL
  pure_quanta q_cap *
  page422_i92
#CELL
  pure_quanta q_cap *
  page422_i93
#CELL
  pure_quanta q_capp *
  page422_i94
#CELL
  pure_quanta q_capp *
  page422_i95
#CELL
  pure_quanta q_cap *
  page422_i96
#ISCELL
  pure_quanta quanta_title_block_c *
  *
#ISCELL
  pure_quanta quanta_title_block_c *
  *
#ISCELL
  pure_quanta quanta_title_block_c *
  *
#ISCELL
  pure_quanta quanta_title_block_c *
  *
#CELL
  pure_quanta pt5161lrs *
  page426_i1
#ISCELL
  standard tap *
  page426_i10
#ISCELL
  standard tap *
  page426_i11
#ISCELL
  standard tap *
  page426_i12
#ISCELL
  standard tap *
  page426_i13
#ISCELL
  standard tap *
  page426_i14
#ISCELL
  standard tap *
  page426_i15
#ISCELL
  standard tap *
  page426_i16
#ISCELL
  standard tap *
  page426_i17
#ISCELL
  standard offpage *
  page426_i18
#ISCELL
  standard offpage *
  page426_i19
#ISCELL
  standard tap *
  page426_i2
#ISCELL
  standard tap *
  page426_i20
#ISCELL
  standard tap *
  page426_i21
#ISCELL
  standard tap *
  page426_i22
#ISCELL
  standard tap *
  page426_i23
#ISCELL
  standard tap *
  page426_i24
#ISCELL
  standard tap *
  page426_i25
#ISCELL
  standard tap *
  page426_i26
#ISCELL
  standard tap *
  page426_i27
#ISCELL
  standard tap *
  page426_i28
#ISCELL
  standard tap *
  page426_i29
#ISCELL
  standard tap *
  page426_i3
#ISCELL
  standard tap *
  page426_i30
#ISCELL
  standard tap *
  page426_i31
#ISCELL
  standard tap *
  page426_i32
#ISCELL
  standard tap *
  page426_i33
#ISCELL
  standard offpage *
  page426_i34
#ISCELL
  standard offpage *
  page426_i35
#ISCELL
  standard tap *
  page426_i36
#ISCELL
  standard tap *
  page426_i37
#CELL
  pure_quanta pt5161lrs *
  page426_i38
#ISCELL
  standard tap *
  page426_i4
#ISCELL
  standard tap *
  page426_i5
#ISCELL
  standard tap *
  page426_i6
#ISCELL
  standard tap *
  page426_i7
#ISCELL
  standard tap *
  page426_i8
#ISCELL
  standard tap *
  page426_i9
#ISCELL
  pure_quanta quanta_title_block_c *
  *
#CELL
  pure_quanta pt5161lrs *
  page427_i1
#ISCELL
  standard tap *
  page427_i10
#ISCELL
  standard tap *
  page427_i11
#ISCELL
  standard tap *
  page427_i12
#ISCELL
  standard tap *
  page427_i13
#ISCELL
  standard tap *
  page427_i14
#ISCELL
  standard tap *
  page427_i15
#ISCELL
  standard tap *
  page427_i16
#ISCELL
  standard tap *
  page427_i17
#ISCELL
  standard offpage *
  page427_i18
#ISCELL
  standard offpage *
  page427_i19
#ISCELL
  standard tap *
  page427_i2
#ISCELL
  standard tap *
  page427_i20
#ISCELL
  standard tap *
  page427_i21
#ISCELL
  standard tap *
  page427_i22
#ISCELL
  standard tap *
  page427_i23
#ISCELL
  standard tap *
  page427_i24
#ISCELL
  standard tap *
  page427_i25
#ISCELL
  standard tap *
  page427_i26
#ISCELL
  standard tap *
  page427_i27
#ISCELL
  standard tap *
  page427_i28
#ISCELL
  standard tap *
  page427_i29
#ISCELL
  standard tap *
  page427_i3
#ISCELL
  standard tap *
  page427_i30
#ISCELL
  standard tap *
  page427_i31
#ISCELL
  standard tap *
  page427_i32
#ISCELL
  standard tap *
  page427_i33
#ISCELL
  standard tap *
  page427_i34
#ISCELL
  standard tap *
  page427_i35
#ISCELL
  standard offpage *
  page427_i36
#ISCELL
  standard offpage *
  page427_i37
#CELL
  pure_quanta pt5161lrs *
  page427_i38
#ISCELL
  standard tap *
  page427_i4
#ISCELL
  standard tap *
  page427_i5
#ISCELL
  standard tap *
  page427_i6
#ISCELL
  standard tap *
  page427_i7
#ISCELL
  standard tap *
  page427_i8
#ISCELL
  standard tap *
  page427_i9
#ISCELL
  pure_quanta quanta_title_block_c *
  *
#CELL
  pure_quanta pt5161lrs *
  page428_i1
#ISCELL
  standard tap *
  page428_i10
#ISCELL
  standard tap *
  page428_i11
#ISCELL
  standard tap *
  page428_i12
#ISCELL
  standard tap *
  page428_i13
#ISCELL
  standard tap *
  page428_i14
#ISCELL
  standard tap *
  page428_i15
#ISCELL
  standard tap *
  page428_i16
#ISCELL
  standard tap *
  page428_i17
#ISCELL
  standard offpage *
  page428_i18
#ISCELL
  standard offpage *
  page428_i19
#ISCELL
  standard tap *
  page428_i2
#ISCELL
  standard tap *
  page428_i20
#ISCELL
  standard tap *
  page428_i21
#ISCELL
  standard tap *
  page428_i22
#ISCELL
  standard tap *
  page428_i23
#ISCELL
  standard tap *
  page428_i24
#ISCELL
  standard tap *
  page428_i25
#ISCELL
  standard tap *
  page428_i26
#ISCELL
  standard tap *
  page428_i27
#ISCELL
  standard tap *
  page428_i28
#ISCELL
  standard tap *
  page428_i29
#ISCELL
  standard tap *
  page428_i3
#ISCELL
  standard tap *
  page428_i30
#ISCELL
  standard tap *
  page428_i31
#ISCELL
  standard tap *
  page428_i32
#ISCELL
  standard tap *
  page428_i33
#ISCELL
  standard tap *
  page428_i34
#ISCELL
  standard tap *
  page428_i35
#ISCELL
  standard offpage *
  page428_i36
#ISCELL
  standard offpage *
  page428_i37
#CELL
  pure_quanta pt5161lrs *
  page428_i38
#ISCELL
  standard tap *
  page428_i4
#ISCELL
  standard tap *
  page428_i5
#ISCELL
  standard tap *
  page428_i6
#ISCELL
  standard tap *
  page428_i7
#ISCELL
  standard tap *
  page428_i8
#ISCELL
  standard tap *
  page428_i9
#ISCELL
  pure_quanta quanta_title_block_c *
  *
#ISCELL
  standard offpage *
  page429_i1
#ISCELL
  standard tap *
  page429_i10
#CELL
  pure_quanta q_cap_diffbus *
  page429_i100
#CELL
  pure_quanta q_cap_diffbus *
  page429_i101
#CELL
  pure_quanta q_cap_diffbus *
  page429_i102
#CELL
  pure_quanta q_cap_diffbus *
  page429_i103
#CELL
  pure_quanta q_cap_diffbus *
  page429_i104
#CELL
  pure_quanta q_cap_diffbus *
  page429_i105
#ISCELL
  standard tap *
  page429_i106
#ISCELL
  standard tap *
  page429_i107
#ISCELL
  standard tap *
  page429_i108
#ISCELL
  standard tap *
  page429_i109
#ISCELL
  standard tap *
  page429_i11
#ISCELL
  standard tap *
  page429_i110
#ISCELL
  standard tap *
  page429_i111
#ISCELL
  standard tap *
  page429_i112
#ISCELL
  standard tap *
  page429_i113
#ISCELL
  standard tap *
  page429_i114
#ISCELL
  standard tap *
  page429_i115
#ISCELL
  standard tap *
  page429_i116
#ISCELL
  standard tap *
  page429_i117
#ISCELL
  standard tap *
  page429_i118
#ISCELL
  standard tap *
  page429_i119
#ISCELL
  standard tap *
  page429_i12
#ISCELL
  standard tap *
  page429_i120
#ISCELL
  standard tap *
  page429_i121
#ISCELL
  standard offpage *
  page429_i122
#ISCELL
  standard offpage *
  page429_i123
#ISCELL
  standard tap *
  page429_i124
#ISCELL
  standard tap *
  page429_i125
#ISCELL
  standard tap *
  page429_i126
#ISCELL
  standard tap *
  page429_i127
#ISCELL
  standard tap *
  page429_i128
#ISCELL
  standard tap *
  page429_i129
#ISCELL
  standard tap *
  page429_i13
#ISCELL
  standard tap *
  page429_i130
#ISCELL
  standard tap *
  page429_i131
#ISCELL
  standard tap *
  page429_i132
#ISCELL
  standard tap *
  page429_i133
#ISCELL
  standard tap *
  page429_i134
#ISCELL
  standard tap *
  page429_i135
#ISCELL
  standard tap *
  page429_i136
#ISCELL
  standard tap *
  page429_i137
#ISCELL
  standard offpage *
  page429_i138
#ISCELL
  standard offpage *
  page429_i139
#ISCELL
  standard tap *
  page429_i14
#ISCELL
  standard tap *
  page429_i140
#ISCELL
  standard tap *
  page429_i141
#CELL
  pure_quanta pt5161lrs *
  page429_i142
#ISCELL
  standard tap *
  page429_i15
#ISCELL
  standard tap *
  page429_i16
#ISCELL
  standard tap *
  page429_i17
#ISCELL
  standard tap *
  page429_i18
#CELL
  pure_quanta q_cap_diffbus *
  page429_i19
#ISCELL
  standard offpage *
  page429_i2
#CELL
  pure_quanta q_cap_diffbus *
  page429_i20
#CELL
  pure_quanta q_cap_diffbus *
  page429_i21
#CELL
  pure_quanta q_cap_diffbus *
  page429_i22
#CELL
  pure_quanta q_cap_diffbus *
  page429_i23
#CELL
  pure_quanta q_cap_diffbus *
  page429_i24
#ISCELL
  standard tap *
  page429_i25
#ISCELL
  standard tap *
  page429_i26
#ISCELL
  standard tap *
  page429_i27
#ISCELL
  standard tap *
  page429_i28
#ISCELL
  standard tap *
  page429_i29
#ISCELL
  standard tap *
  page429_i3
#ISCELL
  standard tap *
  page429_i30
#CELL
  pure_quanta q_cap_diffbus *
  page429_i31
#CELL
  pure_quanta q_cap_diffbus *
  page429_i32
#CELL
  pure_quanta q_cap_diffbus *
  page429_i33
#CELL
  pure_quanta q_cap_diffbus *
  page429_i34
#CELL
  pure_quanta q_cap_diffbus *
  page429_i35
#CELL
  pure_quanta q_cap_diffbus *
  page429_i36
#CELL
  pure_quanta q_cap_diffbus *
  page429_i37
#CELL
  pure_quanta q_cap_diffbus *
  page429_i38
#CELL
  pure_quanta q_cap_diffbus *
  page429_i39
#ISCELL
  standard tap *
  page429_i4
#CELL
  pure_quanta q_cap_diffbus *
  page429_i40
#ISCELL
  standard tap *
  page429_i41
#ISCELL
  standard tap *
  page429_i42
#ISCELL
  standard tap *
  page429_i43
#ISCELL
  standard tap *
  page429_i44
#ISCELL
  standard tap *
  page429_i45
#ISCELL
  standard tap *
  page429_i46
#ISCELL
  standard tap *
  page429_i47
#ISCELL
  standard tap *
  page429_i48
#ISCELL
  standard tap *
  page429_i49
#ISCELL
  standard tap *
  page429_i5
#ISCELL
  standard tap *
  page429_i50
#CELL
  pure_quanta pt5161lrs *
  page429_i51
#ISCELL
  standard tap *
  page429_i52
#ISCELL
  standard tap *
  page429_i53
#ISCELL
  standard tap *
  page429_i54
#ISCELL
  standard tap *
  page429_i55
#ISCELL
  standard tap *
  page429_i56
#ISCELL
  standard tap *
  page429_i57
#ISCELL
  standard offpage *
  page429_i58
#ISCELL
  standard offpage *
  page429_i59
#ISCELL
  standard tap *
  page429_i6
#ISCELL
  standard offpage *
  page429_i60
#ISCELL
  standard offpage *
  page429_i61
#ISCELL
  standard tap *
  page429_i62
#ISCELL
  standard tap *
  page429_i63
#ISCELL
  standard tap *
  page429_i64
#ISCELL
  standard tap *
  page429_i65
#ISCELL
  standard tap *
  page429_i66
#ISCELL
  standard tap *
  page429_i67
#ISCELL
  standard tap *
  page429_i68
#ISCELL
  standard tap *
  page429_i69
#ISCELL
  standard tap *
  page429_i7
#ISCELL
  standard tap *
  page429_i70
#ISCELL
  standard tap *
  page429_i71
#ISCELL
  standard offpage *
  page429_i72
#ISCELL
  standard offpage *
  page429_i73
#ISCELL
  standard tap *
  page429_i74
#ISCELL
  standard tap *
  page429_i75
#ISCELL
  standard tap *
  page429_i76
#ISCELL
  standard tap *
  page429_i77
#ISCELL
  standard tap *
  page429_i78
#ISCELL
  standard tap *
  page429_i79
#ISCELL
  standard tap *
  page429_i8
#ISCELL
  standard tap *
  page429_i80
#ISCELL
  standard tap *
  page429_i81
#ISCELL
  standard tap *
  page429_i82
#ISCELL
  standard tap *
  page429_i83
#ISCELL
  standard tap *
  page429_i84
#ISCELL
  standard tap *
  page429_i85
#ISCELL
  standard tap *
  page429_i86
#ISCELL
  standard tap *
  page429_i87
#ISCELL
  standard tap *
  page429_i88
#ISCELL
  standard tap *
  page429_i89
#ISCELL
  standard tap *
  page429_i9
#CELL
  pure_quanta q_cap_diffbus *
  page429_i90
#CELL
  pure_quanta q_cap_diffbus *
  page429_i91
#CELL
  pure_quanta q_cap_diffbus *
  page429_i92
#CELL
  pure_quanta q_cap_diffbus *
  page429_i93
#CELL
  pure_quanta q_cap_diffbus *
  page429_i94
#CELL
  pure_quanta q_cap_diffbus *
  page429_i95
#CELL
  pure_quanta q_cap_diffbus *
  page429_i96
#CELL
  pure_quanta q_cap_diffbus *
  page429_i97
#CELL
  pure_quanta q_cap_diffbus *
  page429_i98
#CELL
  pure_quanta q_cap_diffbus *
  page429_i99
#ISCELL
  mstr_misc dns *
  *
#ISCELL
  pure_quanta quanta_title_block_c *
  *
#ISCELL
  standard offpage *
  page430_i1
#CELL
  pure_quanta q_res *
  page430_i10
#ISCELL
  pure_quanta_power universal_gnd *
  page430_i100
#CELL
  pure_quanta q_res *
  page430_i101
#CELL
  pure_quanta q_res *
  page430_i102
#ISCELL
  standard offpage *
  page430_i103
#ISCELL
  standard offpage *
  page430_i104
#CELL
  pure_quanta q_res *
  page430_i11
#CELL
  pure_quanta q_res *
  page430_i112
#CELL
  pure_quanta q_res *
  page430_i113
#ISCELL
  pure_quanta_power gnd *
  page430_i115
#CELL
  pure_quanta q_res *
  page430_i117
#CELL
  pure_quanta q_res *
  page430_i118
#CELL
  pure_quanta q_res *
  page430_i119
#ISCELL
  pure_quanta_power p1v0 *
  page430_i12
#ISCELL
  pure_quanta_power p1v0 *
  page430_i120
#ISCELL
  standard offpage *
  page430_i121
#ISCELL
  standard offpage *
  page430_i123
#ISCELL
  standard offpage *
  page430_i125
#ISCELL
  standard offpage *
  page430_i126
#ISCELL
  standard offpage *
  page430_i127
#ISCELL
  standard offpage *
  page430_i128
#ISCELL
  standard offpage *
  page430_i13
#ISCELL
  standard offpage *
  page430_i14
#CELL
  pure_quanta q_res *
  page430_i15
#ISCELL
  pure_quanta_power universal_gnd *
  page430_i16
#ISCELL
  pure_quanta_power universal_gnd *
  page430_i17
#CELL
  pure_quanta q_res *
  page430_i18
#CELL
  pure_quanta q_res *
  page430_i19
#ISCELL
  standard offpage *
  page430_i2
#CELL
  pure_quanta q_res *
  page430_i20
#CELL
  pure_quanta q_res *
  page430_i21
#CELL
  pure_quanta q_res *
  page430_i22
#ISCELL
  standard offpage *
  page430_i23
#ISCELL
  standard offpage *
  page430_i24
#ISCELL
  standard offpage *
  page430_i25
#ISCELL
  standard offpage *
  page430_i26
#ISCELL
  standard offpage *
  page430_i27
#ISCELL
  standard offpage *
  page430_i28
#ISCELL
  standard offpage *
  page430_i29
#ISCELL
  pure_quanta_power universal_gnd *
  page430_i3
#ISCELL
  standard offpage *
  page430_i30
#ISCELL
  standard offpage *
  page430_i31
#CELL
  pure_quanta q_res *
  page430_i32
#CELL
  pure_quanta q_res *
  page430_i33
#ISCELL
  standard offpage *
  page430_i34
#ISCELL
  standard offpage *
  page430_i35
#CELL
  pure_quanta q_res *
  page430_i36
#CELL
  pure_quanta q_res *
  page430_i37
#ISCELL
  pure_quanta_power universal_gnd *
  page430_i38
#CELL
  pure_quanta q_res *
  page430_i39
#CELL
  pure_quanta q_res *
  page430_i40
#CELL
  pure_quanta q_res *
  page430_i41
#CELL
  pure_quanta q_res *
  page430_i42
#ISCELL
  standard offpage *
  page430_i43
#ISCELL
  standard offpage *
  page430_i44
#ISCELL
  standard offpage *
  page430_i45
#ISCELL
  standard offpage *
  page430_i46
#ISCELL
  standard offpage *
  page430_i47
#ISCELL
  standard offpage *
  page430_i48
#ISCELL
  pure_quanta_power universal_gnd *
  page430_i49
#CELL
  pure_quanta q_res *
  page430_i5
#CELL
  pure_quanta q_res *
  page430_i50
#CELL
  pure_quanta q_res *
  page430_i51
#ISCELL
  standard offpage *
  page430_i52
#ISCELL
  pure_quanta_power p1v0 *
  page430_i53
#ISCELL
  pure_quanta_power universal_gnd *
  page430_i54
#CELL
  pure_quanta q_res *
  page430_i55
#CELL
  pure_quanta q_res *
  page430_i56
#ISCELL
  standard offpage *
  page430_i58
#ISCELL
  standard offpage *
  page430_i59
#ISCELL
  pure_quanta_power p1v0 *
  page430_i6
#ISCELL
  standard offpage *
  page430_i60
#ISCELL
  standard offpage *
  page430_i62
#ISCELL
  standard offpage *
  page430_i63
#ISCELL
  pure_quanta_power universal_gnd *
  page430_i64
#CELL
  pure_quanta q_res *
  page430_i65
#CELL
  pure_quanta q_res *
  page430_i66
#CELL
  pure_quanta q_res *
  page430_i67
#CELL
  pure_quanta q_res *
  page430_i68
#CELL
  pure_quanta q_res *
  page430_i69
#CELL
  pure_quanta q_res *
  page430_i7
#CELL
  pure_quanta q_res *
  page430_i70
#ISCELL
  pure_quanta_power p1v0 *
  page430_i71
#ISCELL
  pure_quanta_power gnd *
  page430_i72
#ISCELL
  pure_quanta_power gnd *
  page430_i73
#CELL
  pure_quanta q_res *
  page430_i74
#CELL
  pure_quanta q_res *
  page430_i75
#ISCELL
  standard offpage *
  page430_i76
#ISCELL
  standard offpage *
  page430_i77
#ISCELL
  standard offpage *
  page430_i78
#CELL
  pure_quanta q_res *
  page430_i79
#CELL
  pure_quanta q_res *
  page430_i8
#ISCELL
  standard offpage *
  page430_i80
#ISCELL
  standard offpage *
  page430_i81
#ISCELL
  pure_quanta_power p1v0 *
  page430_i82
#CELL
  pure_quanta pt5161lrs *
  page430_i83
#CELL
  pure_quanta q_res *
  page430_i85
#CELL
  pure_quanta q_res *
  page430_i9
#ISCELL
  pure_quanta_power universal_gnd *
  page430_i92
#ISCELL
  standard offpage *
  page430_i94
#ISCELL
  pure_quanta_power gnd *
  page430_i95
#CELL
  pure_quanta q_res *
  page430_i96
#CELL
  pure_quanta q_res *
  page430_i97
#ISCELL
  pure_quanta_power p1v0 *
  page430_i98
#ISCELL
  standard offpage *
  page430_i99
#ISCELL
  mstr_misc dns *
  *
#ISCELL
  pure_quanta quanta_title_block_c *
  *
#ISCELL
  pure_quanta_power p1v0 *
  page431_i1
#ISCELL
  pure_quanta_power vcc_core *
  page431_i10
#ISCELL
  pure_quanta_power universal_gnd *
  page431_i11
#ISCELL
  pure_quanta_power universal_gnd *
  page431_i12
#CELL
  pure_quanta q_res *
  page431_i13
#CELL
  pure_quanta q_res *
  page431_i14
#ISCELL
  pure_quanta_power universal_gnd *
  page431_i15
#ISCELL
  pure_quanta_power universal_gnd *
  page431_i16
#CELL
  pure_quanta pt5161lrs *
  page431_i17
#CELL
  pure_quanta q_res *
  page431_i18
#CELL
  pure_quanta q_res *
  page431_i19
#ISCELL
  pure_quanta_power p1v0 *
  page431_i3
#ISCELL
  pure_quanta_power universal_gnd *
  page431_i4
#CELL
  pure_quanta pt5161lrs *
  page431_i6
#ISCELL
  pure_quanta_power p1v0 *
  page431_i7
#ISCELL
  pure_quanta_power p1v0 *
  page431_i8
#ISCELL
  pure_quanta_power vcc_core *
  page431_i9
#ISCELL
  pure_quanta quanta_title_block_c *
  *
#ISCELL
  standard offpage *
  page432_i1
#CELL
  pure_quanta q_res *
  page432_i18
#ISCELL
  pure_quanta_power universal_gnd *
  page432_i19
#ISCELL
  standard offpage *
  page432_i2
#ISCELL
  pure_quanta_power universal_gnd *
  page432_i20
#ISCELL
  pure_quanta_power universal_gnd *
  page432_i21
#ISCELL
  pure_quanta_power p1v0 *
  page432_i22
#CELL
  pure_quanta q_cap *
  page432_i23
#ISCELL
  pure_quanta_power universal_gnd *
  page432_i24
#CELL
  pure_quanta q_res *
  page432_i3
#CELL
  pure_quanta q_res *
  page432_i4
#CELL
  pure_quanta m24m02drmn6tp *
  page432_i5
#ISCELL
  mstr_misc dns *
  *
#ISCELL
  pure_quanta quanta_title_block_c *
  *
#ISCELL
  pure_quanta_power cad_note *
  *
#CELL
  pure_quanta q_res *
  page433_i1
#CELL
  pure_quanta q_inductor *
  page433_i10
#ISCELL
  pure_quanta_power p1v0 *
  page433_i11
#CELL
  pure_quanta q_cap *
  page433_i12
#CELL
  pure_quanta q_cap *
  page433_i13
#ISCELL
  pure_quanta_power p1v0 *
  page433_i14
#CELL
  pure_quanta q_cap *
  page433_i15
#CELL
  pure_quanta q_cap *
  page433_i16
#CELL
  pure_quanta q_cap *
  page433_i17
#ISCELL
  pure_quanta_power universal_gnd *
  page433_i18
#CELL
  pure_quanta q_cap *
  page433_i19
#CELL
  pure_quanta q_res *
  page433_i2
#CELL
  pure_quanta q_cap *
  page433_i20
#CELL
  pure_quanta q_cap *
  page433_i21
#CELL
  pure_quanta q_cap *
  page433_i22
#ISCELL
  pure_quanta_power universal_gnd *
  page433_i23
#CELL
  pure_quanta q_cap *
  page433_i24
#CELL
  pure_quanta q_cap *
  page433_i25
#CELL
  pure_quanta q_cap *
  page433_i26
#CELL
  pure_quanta q_cap *
  page433_i27
#CELL
  pure_quanta q_cap *
  page433_i28
#ISCELL
  pure_quanta_power vcc_core *
  page433_i29
#ISCELL
  pure_quanta_power universal_gnd *
  page433_i3
#CELL
  pure_quanta q_cap *
  page433_i30
#ISCELL
  pure_quanta_power vcc_core *
  page433_i32
#ISCELL
  pure_quanta_power universal_gnd *
  page433_i34
#CELL
  pure_quanta q_cap *
  page433_i35
#CELL
  pure_quanta q_res *
  page433_i36
#CELL
  pure_quanta q_cap *
  page433_i37
#CELL
  pure_quanta q_cap *
  page433_i38
#CELL
  pure_quanta q_cap *
  page433_i39
#ISCELL
  pure_quanta_power p1v0 *
  page433_i4
#CELL
  pure_quanta q_cap *
  page433_i40
#CELL
  pure_quanta q_cap *
  page433_i41
#CELL
  pure_quanta q_cap *
  page433_i42
#CELL
  pure_quanta q_cap *
  page433_i43
#CELL
  pure_quanta q_cap *
  page433_i44
#CELL
  pure_quanta q_cap *
  page433_i45
#CELL
  pure_quanta q_cap *
  page433_i46
#CELL
  pure_quanta q_cap *
  page433_i47
#CELL
  pure_quanta q_cap *
  page433_i48
#CELL
  pure_quanta q_cap *
  page433_i49
#CELL
  pure_quanta q_cap *
  page433_i5
#CELL
  pure_quanta q_cap *
  page433_i50
#CELL
  pure_quanta q_cap *
  page433_i51
#CELL
  pure_quanta q_cap *
  page433_i52
#CELL
  pure_quanta q_cap *
  page433_i53
#CELL
  pure_quanta q_cap *
  page433_i54
#ISCELL
  pure_quanta_power universal_gnd *
  page433_i55
#CELL
  pure_quanta q_cap *
  page433_i56
#CELL
  pure_quanta q_cap *
  page433_i57
#CELL
  pure_quanta q_cap *
  page433_i59
#CELL
  pure_quanta q_cap *
  page433_i6
#CELL
  pure_quanta q_cap *
  page433_i60
#CELL
  pure_quanta q_cap *
  page433_i62
#CELL
  pure_quanta q_cap *
  page433_i63
#ISCELL
  pure_quanta_power universal_gnd *
  page433_i64
#CELL
  pure_quanta q_inductor *
  page433_i65
#CELL
  pure_quanta q_cap *
  page433_i66
#CELL
  pure_quanta q_cap *
  page433_i67
#ISCELL
  pure_quanta_power vcc_core *
  page433_i68
#CELL
  pure_quanta q_cap *
  page433_i69
#CELL
  pure_quanta q_res *
  page433_i7
#CELL
  pure_quanta q_cap *
  page433_i70
#CELL
  pure_quanta q_cap *
  page433_i71
#CELL
  pure_quanta q_cap *
  page433_i72
#CELL
  pure_quanta q_cap *
  page433_i73
#CELL
  pure_quanta q_cap *
  page433_i74
#CELL
  pure_quanta q_cap *
  page433_i75
#CELL
  pure_quanta q_cap *
  page433_i76
#CELL
  pure_quanta q_cap *
  page433_i77
#CELL
  pure_quanta q_cap *
  page433_i78
#CELL
  pure_quanta q_cap *
  page433_i79
#CELL
  pure_quanta q_cap *
  page433_i80
#CELL
  pure_quanta q_cap *
  page433_i81
#CELL
  pure_quanta q_cap *
  page433_i82
#ISCELL
  pure_quanta_power universal_gnd *
  page433_i83
#CELL
  pure_quanta q_cap *
  page433_i84
#CELL
  pure_quanta q_cap *
  page433_i85
#CELL
  pure_quanta q_cap *
  page433_i86
#CELL
  pure_quanta q_cap *
  page433_i87
#CELL
  pure_quanta q_inductor *
  page433_i88
#CELL
  pure_quanta q_res *
  page433_i89
#CELL
  pure_quanta q_cap *
  page433_i90
#CELL
  pure_quanta q_cap *
  page433_i91
#CELL
  pure_quanta q_cap *
  page433_i92
#CELL
  pure_quanta q_cap *
  page433_i93
#CELL
  pure_quanta q_capp *
  page433_i94
#CELL
  pure_quanta q_capp *
  page433_i95
#CELL
  pure_quanta q_cap *
  page433_i96
#ISCELL
  pure_quanta quanta_title_block_c *
  *
#ISCELL
  pure_quanta quanta_title_block_c *
  *
#ISCELL
  pure_quanta quanta_title_block_c *
  *
#ISCELL
  pure_quanta quanta_title_block_c *
  *
#CELL
  pure_quanta pt5161lrs *
  page437_i1
#ISCELL
  standard tap *
  page437_i10
#ISCELL
  standard tap *
  page437_i11
#ISCELL
  standard tap *
  page437_i12
#ISCELL
  standard tap *
  page437_i13
#ISCELL
  standard tap *
  page437_i14
#ISCELL
  standard tap *
  page437_i15
#ISCELL
  standard tap *
  page437_i16
#ISCELL
  standard tap *
  page437_i17
#ISCELL
  standard offpage *
  page437_i18
#ISCELL
  standard offpage *
  page437_i19
#ISCELL
  standard tap *
  page437_i2
#ISCELL
  standard tap *
  page437_i20
#ISCELL
  standard tap *
  page437_i21
#ISCELL
  standard tap *
  page437_i22
#ISCELL
  standard tap *
  page437_i23
#ISCELL
  standard tap *
  page437_i24
#ISCELL
  standard tap *
  page437_i25
#ISCELL
  standard tap *
  page437_i26
#ISCELL
  standard tap *
  page437_i27
#ISCELL
  standard tap *
  page437_i28
#ISCELL
  standard tap *
  page437_i29
#ISCELL
  standard tap *
  page437_i3
#ISCELL
  standard tap *
  page437_i30
#ISCELL
  standard tap *
  page437_i31
#ISCELL
  standard tap *
  page437_i32
#ISCELL
  standard tap *
  page437_i33
#ISCELL
  standard tap *
  page437_i34
#ISCELL
  standard tap *
  page437_i35
#ISCELL
  standard offpage *
  page437_i36
#ISCELL
  standard offpage *
  page437_i37
#CELL
  pure_quanta pt5161lrs *
  page437_i38
#ISCELL
  standard tap *
  page437_i4
#ISCELL
  standard tap *
  page437_i5
#ISCELL
  standard tap *
  page437_i6
#ISCELL
  standard tap *
  page437_i7
#ISCELL
  standard tap *
  page437_i8
#ISCELL
  standard tap *
  page437_i9
#ISCELL
  pure_quanta quanta_title_block_c *
  *
#CELL
  pure_quanta pt5161lrs *
  page438_i1
#ISCELL
  standard tap *
  page438_i10
#ISCELL
  standard tap *
  page438_i11
#ISCELL
  standard tap *
  page438_i12
#ISCELL
  standard tap *
  page438_i13
#ISCELL
  standard tap *
  page438_i14
#ISCELL
  standard tap *
  page438_i15
#ISCELL
  standard tap *
  page438_i16
#ISCELL
  standard tap *
  page438_i17
#ISCELL
  standard offpage *
  page438_i18
#ISCELL
  standard offpage *
  page438_i19
#ISCELL
  standard tap *
  page438_i2
#ISCELL
  standard tap *
  page438_i20
#ISCELL
  standard tap *
  page438_i21
#ISCELL
  standard tap *
  page438_i22
#ISCELL
  standard tap *
  page438_i23
#ISCELL
  standard tap *
  page438_i24
#ISCELL
  standard tap *
  page438_i25
#ISCELL
  standard tap *
  page438_i26
#ISCELL
  standard tap *
  page438_i27
#ISCELL
  standard tap *
  page438_i28
#ISCELL
  standard tap *
  page438_i29
#ISCELL
  standard tap *
  page438_i3
#ISCELL
  standard tap *
  page438_i30
#ISCELL
  standard tap *
  page438_i31
#ISCELL
  standard tap *
  page438_i32
#ISCELL
  standard tap *
  page438_i33
#ISCELL
  standard tap *
  page438_i34
#ISCELL
  standard tap *
  page438_i35
#ISCELL
  standard offpage *
  page438_i36
#ISCELL
  standard offpage *
  page438_i37
#CELL
  pure_quanta pt5161lrs *
  page438_i38
#ISCELL
  standard tap *
  page438_i4
#ISCELL
  standard tap *
  page438_i5
#ISCELL
  standard tap *
  page438_i6
#ISCELL
  standard tap *
  page438_i7
#ISCELL
  standard tap *
  page438_i8
#ISCELL
  standard tap *
  page438_i9
#ISCELL
  pure_quanta quanta_title_block_c *
  *
#CELL
  pure_quanta pt5161lrs *
  page402_i1
#ISCELL
  standard tap *
  page402_i10
#ISCELL
  standard tap *
  page402_i11
#ISCELL
  standard tap *
  page402_i12
#ISCELL
  standard tap *
  page402_i13
#ISCELL
  standard tap *
  page402_i14
#ISCELL
  standard tap *
  page402_i15
#ISCELL
  standard tap *
  page402_i16
#ISCELL
  standard tap *
  page402_i17
#ISCELL
  standard offpage *
  page402_i18
#ISCELL
  standard offpage *
  page402_i19
#ISCELL
  standard tap *
  page402_i2
#ISCELL
  standard tap *
  page402_i20
#ISCELL
  standard tap *
  page402_i21
#ISCELL
  standard tap *
  page402_i22
#ISCELL
  standard tap *
  page402_i23
#ISCELL
  standard tap *
  page402_i24
#ISCELL
  standard tap *
  page402_i25
#ISCELL
  standard tap *
  page402_i26
#ISCELL
  standard tap *
  page402_i27
#ISCELL
  standard tap *
  page402_i28
#ISCELL
  standard tap *
  page402_i29
#ISCELL
  standard tap *
  page402_i3
#ISCELL
  standard tap *
  page402_i30
#ISCELL
  standard tap *
  page402_i31
#ISCELL
  standard tap *
  page402_i32
#ISCELL
  standard tap *
  page402_i33
#ISCELL
  standard tap *
  page402_i34
#ISCELL
  standard offpage *
  page402_i35
#ISCELL
  standard offpage *
  page402_i36
#ISCELL
  standard tap *
  page402_i37
#CELL
  pure_quanta pt5161lrs *
  page402_i38
#ISCELL
  standard tap *
  page402_i4
#ISCELL
  standard tap *
  page402_i5
#ISCELL
  standard tap *
  page402_i6
#ISCELL
  standard tap *
  page402_i7
#ISCELL
  standard tap *
  page402_i8
#ISCELL
  standard tap *
  page402_i9
#ISCELL
  pure_quanta quanta_title_block_c *
  *
#ISCELL
  standard offpage *
  page439_i1
#ISCELL
  standard tap *
  page439_i10
#ISCELL
  standard tap *
  page439_i100
#ISCELL
  standard tap *
  page439_i101
#CELL
  pure_quanta q_cap_diffbus *
  page439_i102
#CELL
  pure_quanta q_cap_diffbus *
  page439_i103
#CELL
  pure_quanta q_cap_diffbus *
  page439_i104
#CELL
  pure_quanta q_cap_diffbus *
  page439_i105
#ISCELL
  standard tap *
  page439_i106
#ISCELL
  standard tap *
  page439_i107
#ISCELL
  standard tap *
  page439_i108
#ISCELL
  standard tap *
  page439_i109
#ISCELL
  standard tap *
  page439_i11
#ISCELL
  standard tap *
  page439_i110
#ISCELL
  standard tap *
  page439_i111
#ISCELL
  standard tap *
  page439_i112
#ISCELL
  standard tap *
  page439_i113
#ISCELL
  standard tap *
  page439_i114
#ISCELL
  standard tap *
  page439_i115
#ISCELL
  standard tap *
  page439_i116
#ISCELL
  standard tap *
  page439_i117
#ISCELL
  standard tap *
  page439_i118
#ISCELL
  standard tap *
  page439_i119
#ISCELL
  standard tap *
  page439_i12
#ISCELL
  standard tap *
  page439_i120
#ISCELL
  standard tap *
  page439_i121
#ISCELL
  standard tap *
  page439_i122
#ISCELL
  standard tap *
  page439_i123
#ISCELL
  standard tap *
  page439_i124
#ISCELL
  standard tap *
  page439_i125
#ISCELL
  standard offpage *
  page439_i126
#ISCELL
  standard offpage *
  page439_i127
#ISCELL
  standard tap *
  page439_i128
#ISCELL
  standard tap *
  page439_i129
#ISCELL
  standard tap *
  page439_i13
#ISCELL
  standard tap *
  page439_i130
#ISCELL
  standard tap *
  page439_i131
#ISCELL
  standard tap *
  page439_i132
#ISCELL
  standard tap *
  page439_i133
#ISCELL
  standard tap *
  page439_i134
#ISCELL
  standard tap *
  page439_i135
#ISCELL
  standard tap *
  page439_i136
#ISCELL
  standard tap *
  page439_i137
#ISCELL
  standard tap *
  page439_i138
#ISCELL
  standard tap *
  page439_i139
#ISCELL
  standard tap *
  page439_i14
#ISCELL
  standard offpage *
  page439_i140
#ISCELL
  standard offpage *
  page439_i141
#CELL
  pure_quanta pt5161lrs *
  page439_i142
#CELL
  pure_quanta q_cap_diffbus *
  page439_i15
#CELL
  pure_quanta q_cap_diffbus *
  page439_i16
#ISCELL
  standard tap *
  page439_i17
#CELL
  pure_quanta q_cap_diffbus *
  page439_i18
#CELL
  pure_quanta q_cap_diffbus *
  page439_i19
#ISCELL
  standard offpage *
  page439_i2
#CELL
  pure_quanta q_cap_diffbus *
  page439_i20
#CELL
  pure_quanta q_cap_diffbus *
  page439_i21
#CELL
  pure_quanta q_cap_diffbus *
  page439_i22
#CELL
  pure_quanta q_cap_diffbus *
  page439_i23
#CELL
  pure_quanta q_cap_diffbus *
  page439_i24
#CELL
  pure_quanta q_cap_diffbus *
  page439_i25
#CELL
  pure_quanta q_cap_diffbus *
  page439_i26
#CELL
  pure_quanta q_cap_diffbus *
  page439_i27
#ISCELL
  standard tap *
  page439_i28
#ISCELL
  standard tap *
  page439_i29
#ISCELL
  standard tap *
  page439_i3
#ISCELL
  standard tap *
  page439_i30
#ISCELL
  standard tap *
  page439_i31
#ISCELL
  standard tap *
  page439_i32
#ISCELL
  standard tap *
  page439_i33
#ISCELL
  standard tap *
  page439_i34
#ISCELL
  standard tap *
  page439_i35
#ISCELL
  standard tap *
  page439_i36
#ISCELL
  standard tap *
  page439_i37
#ISCELL
  standard tap *
  page439_i38
#ISCELL
  standard tap *
  page439_i39
#ISCELL
  standard tap *
  page439_i4
#ISCELL
  standard tap *
  page439_i40
#ISCELL
  standard tap *
  page439_i41
#ISCELL
  standard tap *
  page439_i42
#CELL
  pure_quanta pt5161lrs *
  page439_i43
#CELL
  pure_quanta q_cap_diffbus *
  page439_i44
#CELL
  pure_quanta q_cap_diffbus *
  page439_i45
#CELL
  pure_quanta q_cap_diffbus *
  page439_i46
#CELL
  pure_quanta q_cap_diffbus *
  page439_i47
#ISCELL
  standard tap *
  page439_i48
#ISCELL
  standard tap *
  page439_i49
#ISCELL
  standard tap *
  page439_i5
#ISCELL
  standard tap *
  page439_i50
#ISCELL
  standard tap *
  page439_i51
#ISCELL
  standard tap *
  page439_i52
#ISCELL
  standard tap *
  page439_i53
#ISCELL
  standard tap *
  page439_i54
#ISCELL
  standard tap *
  page439_i55
#ISCELL
  standard offpage *
  page439_i56
#ISCELL
  standard offpage *
  page439_i57
#ISCELL
  standard offpage *
  page439_i58
#ISCELL
  standard offpage *
  page439_i59
#ISCELL
  standard tap *
  page439_i6
#ISCELL
  standard tap *
  page439_i60
#ISCELL
  standard tap *
  page439_i61
#ISCELL
  standard tap *
  page439_i62
#ISCELL
  standard tap *
  page439_i63
#ISCELL
  standard tap *
  page439_i64
#ISCELL
  standard tap *
  page439_i65
#ISCELL
  standard tap *
  page439_i66
#ISCELL
  standard tap *
  page439_i67
#ISCELL
  standard tap *
  page439_i68
#ISCELL
  standard tap *
  page439_i69
#ISCELL
  standard tap *
  page439_i7
#ISCELL
  standard tap *
  page439_i70
#ISCELL
  standard tap *
  page439_i71
#ISCELL
  standard offpage *
  page439_i72
#ISCELL
  standard offpage *
  page439_i73
#ISCELL
  standard tap *
  page439_i74
#ISCELL
  standard tap *
  page439_i75
#ISCELL
  standard tap *
  page439_i76
#ISCELL
  standard tap *
  page439_i77
#ISCELL
  standard tap *
  page439_i78
#ISCELL
  standard tap *
  page439_i79
#ISCELL
  standard tap *
  page439_i8
#ISCELL
  standard tap *
  page439_i80
#ISCELL
  standard tap *
  page439_i81
#ISCELL
  standard tap *
  page439_i82
#ISCELL
  standard tap *
  page439_i83
#ISCELL
  standard tap *
  page439_i84
#ISCELL
  standard tap *
  page439_i85
#CELL
  pure_quanta q_cap_diffbus *
  page439_i86
#CELL
  pure_quanta q_cap_diffbus *
  page439_i87
#CELL
  pure_quanta q_cap_diffbus *
  page439_i88
#CELL
  pure_quanta q_cap_diffbus *
  page439_i89
#ISCELL
  standard tap *
  page439_i9
#CELL
  pure_quanta q_cap_diffbus *
  page439_i90
#CELL
  pure_quanta q_cap_diffbus *
  page439_i91
#CELL
  pure_quanta q_cap_diffbus *
  page439_i92
#CELL
  pure_quanta q_cap_diffbus *
  page439_i93
#CELL
  pure_quanta q_cap_diffbus *
  page439_i94
#CELL
  pure_quanta q_cap_diffbus *
  page439_i95
#CELL
  pure_quanta q_cap_diffbus *
  page439_i96
#CELL
  pure_quanta q_cap_diffbus *
  page439_i97
#ISCELL
  standard tap *
  page439_i98
#ISCELL
  standard tap *
  page439_i99
#ISCELL
  mstr_misc dns *
  *
#ISCELL
  pure_quanta quanta_title_block_c *
  *
#CELL
  pure_quanta pt5161lrs *
  page401_i1
#ISCELL
  pure_quanta_power p1v0 *
  page401_i100
#CELL
  pure_quanta q_res *
  page401_i101
#CELL
  pure_quanta q_res *
  page401_i102
#CELL
  pure_quanta q_res *
  page401_i103
#CELL
  pure_quanta q_res *
  page401_i104
#CELL
  pure_quanta q_res *
  page401_i105
#CELL
  pure_quanta q_res *
  page401_i106
#CELL
  pure_quanta q_res *
  page401_i107
#CELL
  pure_quanta q_res *
  page401_i108
#ISCELL
  standard offpage *
  page401_i109
#ISCELL
  standard offpage *
  page401_i11
#CELL
  pure_quanta q_res *
  page401_i112
#ISCELL
  pure_quanta_power universal_gnd *
  page401_i117
#ISCELL
  pure_quanta_power gnd *
  page401_i118
#ISCELL
  pure_quanta_power universal_gnd *
  page401_i119
#CELL
  pure_quanta q_res *
  page401_i124
#CELL
  pure_quanta q_res *
  page401_i125
#ISCELL
  standard offpage *
  page401_i126
#ISCELL
  pure_quanta_power p1v0 *
  page401_i127
#CELL
  pure_quanta q_res *
  page401_i128
#CELL
  pure_quanta q_res *
  page401_i13
#ISCELL
  standard offpage *
  page401_i130
#ISCELL
  standard offpage *
  page401_i131
#ISCELL
  standard offpage *
  page401_i132
#ISCELL
  standard offpage *
  page401_i133
#ISCELL
  standard offpage *
  page401_i14
#ISCELL
  pure_quanta_power gnd *
  page401_i143
#CELL
  pure_quanta q_res *
  page401_i144
#CELL
  pure_quanta q_res *
  page401_i145
#CELL
  pure_quanta q_res *
  page401_i146
#CELL
  pure_quanta q_res *
  page401_i147
#ISCELL
  pure_quanta_power p1v0 *
  page401_i148
#CELL
  pure_quanta q_res *
  page401_i149
#ISCELL
  standard offpage *
  page401_i151
#ISCELL
  standard offpage *
  page401_i152
#ISCELL
  standard offpage *
  page401_i153
#ISCELL
  standard offpage *
  page401_i154
#CELL
  pure_quanta q_res *
  page401_i155
#ISCELL
  standard offpage *
  page401_i17
#ISCELL
  standard offpage *
  page401_i18
#CELL
  pure_quanta q_res *
  page401_i19
#ISCELL
  standard offpage *
  page401_i2
#CELL
  pure_quanta q_res *
  page401_i20
#ISCELL
  standard offpage *
  page401_i21
#ISCELL
  standard offpage *
  page401_i22
#CELL
  pure_quanta q_res *
  page401_i23
#CELL
  pure_quanta q_res *
  page401_i24
#CELL
  pure_quanta q_res *
  page401_i25
#CELL
  pure_quanta q_res *
  page401_i26
#CELL
  pure_quanta q_res *
  page401_i27
#CELL
  pure_quanta q_res *
  page401_i29
#ISCELL
  standard offpage *
  page401_i3
#CELL
  pure_quanta q_res *
  page401_i32
#CELL
  pure_quanta q_res *
  page401_i33
#CELL
  pure_quanta q_res *
  page401_i34
#CELL
  pure_quanta q_res *
  page401_i35
#CELL
  pure_quanta q_res *
  page401_i36
#ISCELL
  pure_quanta_power p1v0 *
  page401_i39
#ISCELL
  pure_quanta_power universal_gnd *
  page401_i4
#ISCELL
  pure_quanta_power universal_gnd *
  page401_i40
#ISCELL
  standard offpage *
  page401_i43
#ISCELL
  standard offpage *
  page401_i44
#ISCELL
  standard offpage *
  page401_i45
#ISCELL
  standard offpage *
  page401_i46
#ISCELL
  standard offpage *
  page401_i47
#ISCELL
  standard offpage *
  page401_i48
#ISCELL
  standard offpage *
  page401_i49
#ISCELL
  pure_quanta_power universal_gnd *
  page401_i5
#ISCELL
  standard offpage *
  page401_i50
#ISCELL
  standard offpage *
  page401_i53
#CELL
  pure_quanta q_res *
  page401_i54
#CELL
  pure_quanta q_res *
  page401_i55
#ISCELL
  pure_quanta_power p1v0 *
  page401_i56
#ISCELL
  pure_quanta_power universal_gnd *
  page401_i57
#ISCELL
  standard offpage *
  page401_i58
#CELL
  pure_quanta q_res *
  page401_i62
#ISCELL
  standard offpage *
  page401_i63
#ISCELL
  standard offpage *
  page401_i64
#CELL
  pure_quanta q_res *
  page401_i65
#ISCELL
  pure_quanta_power universal_gnd *
  page401_i72
#ISCELL
  pure_quanta_power p1v0 *
  page401_i73
#ISCELL
  standard offpage *
  page401_i74
#ISCELL
  standard offpage *
  page401_i75
#ISCELL
  standard offpage *
  page401_i76
#ISCELL
  standard offpage *
  page401_i77
#ISCELL
  standard offpage *
  page401_i78
#ISCELL
  standard offpage *
  page401_i79
#CELL
  pure_quanta q_res *
  page401_i8
#ISCELL
  standard offpage *
  page401_i83
#CELL
  pure_quanta q_res *
  page401_i85
#ISCELL
  pure_quanta_power universal_gnd *
  page401_i86
#ISCELL
  pure_quanta_power p1v0 *
  page401_i87
#ISCELL
  standard offpage *
  page401_i88
#ISCELL
  standard offpage *
  page401_i89
#CELL
  pure_quanta q_res *
  page401_i9
#CELL
  pure_quanta q_res *
  page401_i90
#CELL
  pure_quanta q_res *
  page401_i91
#ISCELL
  standard offpage *
  page401_i92
#ISCELL
  pure_quanta_power universal_gnd *
  page401_i93
#ISCELL
  standard offpage *
  page401_i94
#ISCELL
  standard offpage *
  page401_i95
#CELL
  pure_quanta q_res *
  page401_i96
#CELL
  pure_quanta q_res *
  page401_i97
#ISCELL
  pure_quanta_power gnd *
  page401_i98
#ISCELL
  pure_quanta_power gnd *
  page401_i99
#ISCELL
  mstr_misc dns *
  *
#ISCELL
  pure_quanta quanta_title_block_c *
  *
#CELL
  pure_quanta pt5161lrs *
  page400_i1
#CELL
  pure_quanta q_res *
  page400_i102
#CELL
  pure_quanta q_res *
  page400_i103
#CELL
  pure_quanta q_res *
  page400_i105
#CELL
  pure_quanta q_res *
  page400_i106
#CELL
  pure_quanta pt5161lrs *
  page400_i2
#ISCELL
  pure_quanta_power p1v0 *
  page400_i21
#ISCELL
  pure_quanta_power universal_gnd *
  page400_i25
#ISCELL
  pure_quanta_power p1v0 *
  page400_i27
#ISCELL
  pure_quanta_power universal_gnd *
  page400_i3
#ISCELL
  pure_quanta_power universal_gnd *
  page400_i4
#ISCELL
  pure_quanta_power vcc_core *
  page400_i40
#ISCELL
  pure_quanta_power universal_gnd *
  page400_i6
#ISCELL
  pure_quanta_power p1v0 *
  page400_i61
#ISCELL
  pure_quanta_power universal_gnd *
  page400_i8
#ISCELL
  pure_quanta_power vcc_core *
  page400_i97
#ISCELL
  pure_quanta_power p1v0 *
  page400_i98
#ISCELL
  pure_quanta quanta_title_block_c *
  *
#ISCELL
  standard offpage *
  page399_i1
#ISCELL
  pure_quanta_power p1v0 *
  page399_i10
#CELL
  pure_quanta q_cap *
  page399_i11
#ISCELL
  pure_quanta_power universal_gnd *
  page399_i12
#CELL
  pure_quanta q_res *
  page399_i13
#ISCELL
  pure_quanta_power universal_gnd *
  page399_i14
#ISCELL
  pure_quanta_power universal_gnd *
  page399_i15
#ISCELL
  standard offpage *
  page399_i2
#CELL
  pure_quanta q_res *
  page399_i3
#CELL
  pure_quanta q_res *
  page399_i4
#CELL
  pure_quanta m24m02drmn6tp *
  page399_i5
#ISCELL
  pure_quanta_power universal_gnd *
  page399_i9
#ISCELL
  mstr_misc dns *
  *
#ISCELL
  pure_quanta quanta_title_block_c *
  *
#ISCELL
  pure_quanta_power cad_note *
  *
#ISCELL
  pure_quanta_power p1v0 *
  page398_i1
#ISCELL
  pure_quanta_power universal_gnd *
  page398_i10
#CELL
  pure_quanta q_cap *
  page398_i100
#CELL
  pure_quanta q_cap *
  page398_i101
#CELL
  pure_quanta q_cap *
  page398_i102
#CELL
  pure_quanta q_capp *
  page398_i103
#CELL
  pure_quanta q_capp *
  page398_i104
#CELL
  pure_quanta q_cap *
  page398_i105
#CELL
  pure_quanta q_cap *
  page398_i12
#CELL
  pure_quanta q_cap *
  page398_i14
#CELL
  pure_quanta q_cap *
  page398_i15
#ISCELL
  pure_quanta_power universal_gnd *
  page398_i17
#CELL
  pure_quanta q_cap *
  page398_i18
#CELL
  pure_quanta q_cap *
  page398_i19
#CELL
  pure_quanta q_cap *
  page398_i20
#CELL
  pure_quanta q_cap *
  page398_i21
#CELL
  pure_quanta q_inductor *
  page398_i22
#CELL
  pure_quanta q_cap *
  page398_i23
#CELL
  pure_quanta q_cap *
  page398_i24
#CELL
  pure_quanta q_cap *
  page398_i25
#CELL
  pure_quanta q_cap *
  page398_i26
#CELL
  pure_quanta q_cap *
  page398_i27
#ISCELL
  pure_quanta_power universal_gnd *
  page398_i28
#ISCELL
  pure_quanta_power p1v0 *
  page398_i29
#ISCELL
  pure_quanta_power p1v0 *
  page398_i3
#CELL
  pure_quanta q_res *
  page398_i32
#CELL
  pure_quanta q_res *
  page398_i33
#CELL
  pure_quanta q_cap *
  page398_i34
#CELL
  pure_quanta q_cap *
  page398_i35
#CELL
  pure_quanta q_cap *
  page398_i36
#ISCELL
  pure_quanta_power vcc_core *
  page398_i37
#CELL
  pure_quanta q_cap *
  page398_i39
#CELL
  pure_quanta q_cap *
  page398_i4
#CELL
  pure_quanta q_cap *
  page398_i40
#ISCELL
  pure_quanta_power universal_gnd *
  page398_i41
#CELL
  pure_quanta q_cap *
  page398_i42
#CELL
  pure_quanta q_cap *
  page398_i44
#CELL
  pure_quanta q_cap *
  page398_i46
#CELL
  pure_quanta q_cap *
  page398_i47
#CELL
  pure_quanta q_cap *
  page398_i48
#CELL
  pure_quanta q_cap *
  page398_i49
#CELL
  pure_quanta q_cap *
  page398_i5
#CELL
  pure_quanta q_cap *
  page398_i50
#CELL
  pure_quanta q_cap *
  page398_i51
#CELL
  pure_quanta q_cap *
  page398_i52
#CELL
  pure_quanta q_cap *
  page398_i53
#CELL
  pure_quanta q_cap *
  page398_i54
#CELL
  pure_quanta q_cap *
  page398_i55
#CELL
  pure_quanta q_cap *
  page398_i56
#CELL
  pure_quanta q_cap *
  page398_i57
#CELL
  pure_quanta q_cap *
  page398_i58
#CELL
  pure_quanta q_cap *
  page398_i59
#CELL
  pure_quanta q_cap *
  page398_i62
#CELL
  pure_quanta q_cap *
  page398_i63
#CELL
  pure_quanta q_cap *
  page398_i64
#CELL
  pure_quanta q_cap *
  page398_i65
#CELL
  pure_quanta q_cap *
  page398_i66
#CELL
  pure_quanta q_cap *
  page398_i67
#CELL
  pure_quanta q_cap *
  page398_i68
#ISCELL
  pure_quanta_power vcc_core *
  page398_i69
#CELL
  pure_quanta q_cap *
  page398_i7
#CELL
  pure_quanta q_cap *
  page398_i70
#CELL
  pure_quanta q_cap *
  page398_i71
#CELL
  pure_quanta q_cap *
  page398_i72
#CELL
  pure_quanta q_cap *
  page398_i73
#CELL
  pure_quanta q_inductor *
  page398_i74
#CELL
  pure_quanta q_cap *
  page398_i75
#CELL
  pure_quanta q_cap *
  page398_i76
#CELL
  pure_quanta q_cap *
  page398_i77
#CELL
  pure_quanta q_cap *
  page398_i78
#ISCELL
  pure_quanta_power universal_gnd *
  page398_i79
#CELL
  pure_quanta q_cap *
  page398_i80
#CELL
  pure_quanta q_cap *
  page398_i81
#CELL
  pure_quanta q_cap *
  page398_i82
#CELL
  pure_quanta q_cap *
  page398_i83
#CELL
  pure_quanta q_cap *
  page398_i84
#CELL
  pure_quanta q_cap *
  page398_i85
#CELL
  pure_quanta q_cap *
  page398_i86
#CELL
  pure_quanta q_cap *
  page398_i87
#ISCELL
  pure_quanta_power universal_gnd *
  page398_i88
#ISCELL
  pure_quanta_power vcc_core *
  page398_i89
#CELL
  pure_quanta q_cap *
  page398_i9
#ISCELL
  pure_quanta_power universal_gnd *
  page398_i91
#CELL
  pure_quanta q_cap *
  page398_i92
#CELL
  pure_quanta q_cap *
  page398_i93
#CELL
  pure_quanta q_res *
  page398_i95
#CELL
  pure_quanta q_res *
  page398_i96
#CELL
  pure_quanta q_inductor *
  page398_i97
#CELL
  pure_quanta q_res *
  page398_i98
#CELL
  pure_quanta q_cap *
  page398_i99
#ISCELL
  pure_quanta quanta_title_block_c *
  *
#ISCELL
  pure_quanta quanta_title_block_c *
  *
#ISCELL
  pure_quanta quanta_title_block_c *
  *
#ISCELL
  pure_quanta quanta_title_block_c *
  *
#CELL
  pure_quanta pt5161lrs *
  page396_i1
#ISCELL
  standard tap *
  page396_i10
#ISCELL
  standard tap *
  page396_i11
#ISCELL
  standard tap *
  page396_i12
#ISCELL
  standard tap *
  page396_i13
#ISCELL
  standard tap *
  page396_i14
#ISCELL
  standard tap *
  page396_i15
#ISCELL
  standard tap *
  page396_i16
#ISCELL
  standard tap *
  page396_i17
#ISCELL
  standard offpage *
  page396_i18
#ISCELL
  standard offpage *
  page396_i19
#ISCELL
  standard tap *
  page396_i2
#ISCELL
  standard tap *
  page396_i20
#ISCELL
  standard tap *
  page396_i21
#ISCELL
  standard tap *
  page396_i22
#ISCELL
  standard tap *
  page396_i23
#ISCELL
  standard tap *
  page396_i24
#ISCELL
  standard tap *
  page396_i25
#ISCELL
  standard tap *
  page396_i26
#ISCELL
  standard tap *
  page396_i27
#ISCELL
  standard tap *
  page396_i28
#ISCELL
  standard tap *
  page396_i29
#ISCELL
  standard tap *
  page396_i3
#ISCELL
  standard tap *
  page396_i30
#ISCELL
  standard tap *
  page396_i31
#ISCELL
  standard tap *
  page396_i32
#ISCELL
  standard tap *
  page396_i33
#ISCELL
  standard tap *
  page396_i34
#ISCELL
  standard tap *
  page396_i35
#ISCELL
  standard offpage *
  page396_i36
#ISCELL
  standard offpage *
  page396_i37
#CELL
  pure_quanta pt5161lrs *
  page396_i38
#ISCELL
  standard tap *
  page396_i4
#ISCELL
  standard tap *
  page396_i5
#ISCELL
  standard tap *
  page396_i6
#ISCELL
  standard tap *
  page396_i7
#ISCELL
  standard tap *
  page396_i8
#ISCELL
  standard tap *
  page396_i9
#ISCELL
  pure_quanta quanta_title_block_c *
  *
#CELL
  pure_quanta pt5161lrs *
  page395_i1
#ISCELL
  standard tap *
  page395_i10
#ISCELL
  standard tap *
  page395_i11
#ISCELL
  standard tap *
  page395_i12
#ISCELL
  standard tap *
  page395_i13
#ISCELL
  standard tap *
  page395_i14
#ISCELL
  standard tap *
  page395_i15
#ISCELL
  standard tap *
  page395_i16
#ISCELL
  standard tap *
  page395_i17
#ISCELL
  standard offpage *
  page395_i18
#ISCELL
  standard offpage *
  page395_i19
#ISCELL
  standard tap *
  page395_i2
#ISCELL
  standard tap *
  page395_i20
#ISCELL
  standard tap *
  page395_i21
#ISCELL
  standard tap *
  page395_i22
#ISCELL
  standard tap *
  page395_i23
#ISCELL
  standard tap *
  page395_i24
#ISCELL
  standard tap *
  page395_i25
#ISCELL
  standard tap *
  page395_i26
#ISCELL
  standard tap *
  page395_i27
#ISCELL
  standard tap *
  page395_i28
#ISCELL
  standard tap *
  page395_i29
#ISCELL
  standard tap *
  page395_i3
#ISCELL
  standard tap *
  page395_i30
#ISCELL
  standard tap *
  page395_i31
#ISCELL
  standard tap *
  page395_i32
#ISCELL
  standard tap *
  page395_i33
#ISCELL
  standard tap *
  page395_i34
#ISCELL
  standard tap *
  page395_i35
#ISCELL
  standard offpage *
  page395_i36
#ISCELL
  standard offpage *
  page395_i37
#CELL
  pure_quanta pt5161lrs *
  page395_i38
#ISCELL
  standard tap *
  page395_i4
#ISCELL
  standard tap *
  page395_i5
#ISCELL
  standard tap *
  page395_i6
#ISCELL
  standard tap *
  page395_i7
#ISCELL
  standard tap *
  page395_i8
#ISCELL
  standard tap *
  page395_i9
#ISCELL
  pure_quanta quanta_title_block_c *
  *
#CELL
  pure_quanta pt5161lrs *
  page394_i1
#ISCELL
  standard tap *
  page394_i10
#ISCELL
  standard tap *
  page394_i11
#ISCELL
  standard tap *
  page394_i12
#ISCELL
  standard tap *
  page394_i13
#ISCELL
  standard tap *
  page394_i14
#ISCELL
  standard tap *
  page394_i15
#ISCELL
  standard tap *
  page394_i16
#ISCELL
  standard tap *
  page394_i17
#ISCELL
  standard offpage *
  page394_i18
#ISCELL
  standard offpage *
  page394_i19
#ISCELL
  standard tap *
  page394_i2
#ISCELL
  standard tap *
  page394_i20
#ISCELL
  standard tap *
  page394_i21
#ISCELL
  standard tap *
  page394_i22
#ISCELL
  standard tap *
  page394_i23
#ISCELL
  standard tap *
  page394_i24
#ISCELL
  standard tap *
  page394_i25
#ISCELL
  standard tap *
  page394_i26
#ISCELL
  standard tap *
  page394_i27
#ISCELL
  standard tap *
  page394_i28
#ISCELL
  standard tap *
  page394_i29
#ISCELL
  standard tap *
  page394_i3
#ISCELL
  standard tap *
  page394_i30
#ISCELL
  standard tap *
  page394_i31
#ISCELL
  standard tap *
  page394_i32
#ISCELL
  standard tap *
  page394_i33
#ISCELL
  standard tap *
  page394_i34
#ISCELL
  standard tap *
  page394_i35
#ISCELL
  standard offpage *
  page394_i36
#ISCELL
  standard offpage *
  page394_i37
#CELL
  pure_quanta pt5161lrs *
  page394_i38
#ISCELL
  standard tap *
  page394_i4
#ISCELL
  standard tap *
  page394_i5
#ISCELL
  standard tap *
  page394_i6
#ISCELL
  standard tap *
  page394_i7
#ISCELL
  standard tap *
  page394_i8
#ISCELL
  standard tap *
  page394_i9
#ISCELL
  pure_quanta quanta_title_block_c *
  *
#ISCELL
  standard offpage *
  page393_i1
#ISCELL
  standard tap *
  page393_i10
#CELL
  pure_quanta q_cap_diffbus *
  page393_i100
#CELL
  pure_quanta q_cap_diffbus *
  page393_i101
#CELL
  pure_quanta q_cap_diffbus *
  page393_i102
#CELL
  pure_quanta q_cap_diffbus *
  page393_i103
#CELL
  pure_quanta q_cap_diffbus *
  page393_i104
#ISCELL
  standard tap *
  page393_i105
#ISCELL
  standard tap *
  page393_i106
#ISCELL
  standard tap *
  page393_i107
#ISCELL
  standard tap *
  page393_i108
#ISCELL
  standard tap *
  page393_i109
#ISCELL
  standard tap *
  page393_i11
#ISCELL
  standard tap *
  page393_i110
#ISCELL
  standard tap *
  page393_i111
#ISCELL
  standard tap *
  page393_i112
#ISCELL
  standard tap *
  page393_i113
#ISCELL
  standard tap *
  page393_i114
#ISCELL
  standard tap *
  page393_i115
#ISCELL
  standard tap *
  page393_i116
#ISCELL
  standard tap *
  page393_i117
#ISCELL
  standard tap *
  page393_i118
#ISCELL
  standard tap *
  page393_i119
#ISCELL
  standard tap *
  page393_i12
#ISCELL
  standard tap *
  page393_i120
#ISCELL
  standard offpage *
  page393_i121
#ISCELL
  standard offpage *
  page393_i122
#ISCELL
  standard tap *
  page393_i123
#ISCELL
  standard tap *
  page393_i124
#ISCELL
  standard tap *
  page393_i125
#ISCELL
  standard tap *
  page393_i126
#ISCELL
  standard tap *
  page393_i127
#ISCELL
  standard tap *
  page393_i128
#ISCELL
  standard tap *
  page393_i129
#ISCELL
  standard tap *
  page393_i13
#ISCELL
  standard tap *
  page393_i130
#ISCELL
  standard tap *
  page393_i131
#ISCELL
  standard tap *
  page393_i132
#ISCELL
  standard tap *
  page393_i133
#ISCELL
  standard tap *
  page393_i134
#ISCELL
  standard tap *
  page393_i135
#ISCELL
  standard tap *
  page393_i136
#ISCELL
  standard tap *
  page393_i137
#ISCELL
  standard tap *
  page393_i138
#ISCELL
  standard tap *
  page393_i139
#ISCELL
  standard tap *
  page393_i14
#ISCELL
  standard offpage *
  page393_i140
#ISCELL
  standard offpage *
  page393_i141
#CELL
  pure_quanta pt5161lrs *
  page393_i142
#ISCELL
  standard tap *
  page393_i15
#ISCELL
  standard tap *
  page393_i16
#CELL
  pure_quanta q_cap_diffbus *
  page393_i17
#CELL
  pure_quanta q_cap_diffbus *
  page393_i18
#CELL
  pure_quanta q_cap_diffbus *
  page393_i19
#ISCELL
  standard offpage *
  page393_i2
#CELL
  pure_quanta q_cap_diffbus *
  page393_i20
#ISCELL
  standard tap *
  page393_i21
#ISCELL
  standard tap *
  page393_i22
#CELL
  pure_quanta q_cap_diffbus *
  page393_i23
#CELL
  pure_quanta q_cap_diffbus *
  page393_i24
#CELL
  pure_quanta q_cap_diffbus *
  page393_i25
#CELL
  pure_quanta q_cap_diffbus *
  page393_i26
#CELL
  pure_quanta q_cap_diffbus *
  page393_i27
#CELL
  pure_quanta q_cap_diffbus *
  page393_i28
#CELL
  pure_quanta q_cap_diffbus *
  page393_i29
#ISCELL
  standard tap *
  page393_i3
#CELL
  pure_quanta q_cap_diffbus *
  page393_i30
#CELL
  pure_quanta q_cap_diffbus *
  page393_i31
#CELL
  pure_quanta q_cap_diffbus *
  page393_i32
#CELL
  pure_quanta q_cap_diffbus *
  page393_i33
#ISCELL
  standard tap *
  page393_i34
#ISCELL
  standard tap *
  page393_i35
#ISCELL
  standard tap *
  page393_i36
#ISCELL
  standard tap *
  page393_i37
#ISCELL
  standard tap *
  page393_i38
#ISCELL
  standard tap *
  page393_i39
#ISCELL
  standard tap *
  page393_i4
#ISCELL
  standard tap *
  page393_i40
#CELL
  pure_quanta pt5161lrs *
  page393_i41
#CELL
  pure_quanta q_cap_diffbus *
  page393_i42
#ISCELL
  standard tap *
  page393_i43
#ISCELL
  standard tap *
  page393_i44
#ISCELL
  standard tap *
  page393_i45
#ISCELL
  standard tap *
  page393_i46
#ISCELL
  standard tap *
  page393_i47
#ISCELL
  standard tap *
  page393_i48
#ISCELL
  standard tap *
  page393_i49
#ISCELL
  standard tap *
  page393_i5
#ISCELL
  standard tap *
  page393_i50
#ISCELL
  standard tap *
  page393_i51
#ISCELL
  standard tap *
  page393_i52
#ISCELL
  standard tap *
  page393_i53
#ISCELL
  standard tap *
  page393_i54
#ISCELL
  standard tap *
  page393_i55
#ISCELL
  standard tap *
  page393_i56
#ISCELL
  standard offpage *
  page393_i57
#ISCELL
  standard offpage *
  page393_i58
#ISCELL
  standard offpage *
  page393_i59
#ISCELL
  standard tap *
  page393_i6
#ISCELL
  standard tap *
  page393_i60
#ISCELL
  standard offpage *
  page393_i61
#ISCELL
  standard tap *
  page393_i62
#ISCELL
  standard tap *
  page393_i63
#ISCELL
  standard tap *
  page393_i64
#ISCELL
  standard tap *
  page393_i65
#ISCELL
  standard tap *
  page393_i66
#ISCELL
  standard tap *
  page393_i67
#ISCELL
  standard tap *
  page393_i68
#ISCELL
  standard tap *
  page393_i69
#ISCELL
  standard tap *
  page393_i7
#ISCELL
  standard tap *
  page393_i70
#ISCELL
  standard tap *
  page393_i71
#ISCELL
  standard offpage *
  page393_i72
#ISCELL
  standard offpage *
  page393_i73
#ISCELL
  standard tap *
  page393_i74
#ISCELL
  standard tap *
  page393_i75
#ISCELL
  standard tap *
  page393_i76
#ISCELL
  standard tap *
  page393_i77
#ISCELL
  standard tap *
  page393_i78
#ISCELL
  standard tap *
  page393_i79
#ISCELL
  standard tap *
  page393_i8
#ISCELL
  standard tap *
  page393_i80
#ISCELL
  standard tap *
  page393_i81
#ISCELL
  standard tap *
  page393_i82
#ISCELL
  standard tap *
  page393_i83
#CELL
  pure_quanta q_cap_diffbus *
  page393_i84
#CELL
  pure_quanta q_cap_diffbus *
  page393_i85
#CELL
  pure_quanta q_cap_diffbus *
  page393_i86
#CELL
  pure_quanta q_cap_diffbus *
  page393_i87
#CELL
  pure_quanta q_cap_diffbus *
  page393_i88
#CELL
  pure_quanta q_cap_diffbus *
  page393_i89
#ISCELL
  standard tap *
  page393_i9
#ISCELL
  standard tap *
  page393_i90
#ISCELL
  standard tap *
  page393_i91
#ISCELL
  standard tap *
  page393_i92
#ISCELL
  standard tap *
  page393_i93
#ISCELL
  standard tap *
  page393_i94
#CELL
  pure_quanta q_cap_diffbus *
  page393_i95
#CELL
  pure_quanta q_cap_diffbus *
  page393_i96
#CELL
  pure_quanta q_cap_diffbus *
  page393_i97
#CELL
  pure_quanta q_cap_diffbus *
  page393_i98
#CELL
  pure_quanta q_cap_diffbus *
  page393_i99
#ISCELL
  mstr_misc dns *
  *
#ISCELL
  pure_quanta quanta_title_block_c *
  *
#ISCELL
  pure_quanta_power universal_gnd *
  page392_i100
#CELL
  pure_quanta q_res *
  page392_i101
#CELL
  pure_quanta q_res *
  page392_i102
#CELL
  pure_quanta q_res *
  page392_i103
#CELL
  pure_quanta q_res *
  page392_i104
#CELL
  pure_quanta q_res *
  page392_i105
#ISCELL
  pure_quanta_power p1v0 *
  page392_i106
#ISCELL
  standard offpage *
  page392_i107
#ISCELL
  standard offpage *
  page392_i108
#ISCELL
  standard offpage *
  page392_i109
#CELL
  pure_quanta q_res *
  page392_i110
#CELL
  pure_quanta q_res *
  page392_i111
#ISCELL
  standard offpage *
  page392_i112
#CELL
  pure_quanta q_res *
  page392_i115
#ISCELL
  pure_quanta_power universal_gnd *
  page392_i121
#CELL
  pure_quanta q_res *
  page392_i125
#CELL
  pure_quanta q_res *
  page392_i126
#ISCELL
  pure_quanta_power gnd *
  page392_i127
#ISCELL
  standard offpage *
  page392_i128
#ISCELL
  pure_quanta_power p1v0 *
  page392_i129
#ISCELL
  pure_quanta_power universal_gnd *
  page392_i130
#CELL
  pure_quanta q_res *
  page392_i132
#ISCELL
  standard offpage *
  page392_i133
#ISCELL
  standard offpage *
  page392_i135
#ISCELL
  standard offpage *
  page392_i136
#ISCELL
  standard offpage *
  page392_i137
#CELL
  pure_quanta q_res *
  page392_i145
#CELL
  pure_quanta q_res *
  page392_i146
#ISCELL
  pure_quanta_power gnd *
  page392_i148
#ISCELL
  standard offpage *
  page392_i15
#CELL
  pure_quanta q_res *
  page392_i150
#CELL
  pure_quanta q_res *
  page392_i151
#ISCELL
  pure_quanta_power p1v0 *
  page392_i152
#CELL
  pure_quanta q_res *
  page392_i153
#ISCELL
  standard offpage *
  page392_i155
#ISCELL
  standard offpage *
  page392_i156
#ISCELL
  standard offpage *
  page392_i157
#ISCELL
  standard offpage *
  page392_i158
#ISCELL
  standard offpage *
  page392_i16
#ISCELL
  pure_quanta_power universal_gnd *
  page392_i17
#CELL
  pure_quanta q_res *
  page392_i19
#ISCELL
  pure_quanta_power p1v0 *
  page392_i20
#CELL
  pure_quanta q_res *
  page392_i21
#CELL
  pure_quanta q_res *
  page392_i22
#CELL
  pure_quanta q_res *
  page392_i23
#CELL
  pure_quanta q_res *
  page392_i24
#CELL
  pure_quanta q_res *
  page392_i25
#ISCELL
  pure_quanta_power p1v0 *
  page392_i26
#ISCELL
  standard offpage *
  page392_i27
#ISCELL
  standard offpage *
  page392_i28
#ISCELL
  pure_quanta_power universal_gnd *
  page392_i29
#ISCELL
  pure_quanta_power universal_gnd *
  page392_i30
#CELL
  pure_quanta q_res *
  page392_i31
#CELL
  pure_quanta q_res *
  page392_i32
#CELL
  pure_quanta q_res *
  page392_i33
#CELL
  pure_quanta q_res *
  page392_i34
#CELL
  pure_quanta q_res *
  page392_i35
#CELL
  pure_quanta q_res *
  page392_i36
#ISCELL
  standard offpage *
  page392_i37
#ISCELL
  standard offpage *
  page392_i38
#ISCELL
  standard offpage *
  page392_i39
#ISCELL
  standard offpage *
  page392_i40
#ISCELL
  standard offpage *
  page392_i41
#ISCELL
  standard offpage *
  page392_i42
#CELL
  pure_quanta q_res *
  page392_i43
#CELL
  pure_quanta q_res *
  page392_i44
#ISCELL
  standard offpage *
  page392_i45
#ISCELL
  standard offpage *
  page392_i46
#CELL
  pure_quanta pt5161lrs *
  page392_i47
#ISCELL
  standard offpage *
  page392_i48
#ISCELL
  standard offpage *
  page392_i49
#ISCELL
  standard offpage *
  page392_i50
#CELL
  pure_quanta q_res *
  page392_i51
#CELL
  pure_quanta q_res *
  page392_i52
#ISCELL
  pure_quanta_power universal_gnd *
  page392_i53
#CELL
  pure_quanta q_res *
  page392_i54
#CELL
  pure_quanta q_res *
  page392_i55
#CELL
  pure_quanta q_res *
  page392_i56
#CELL
  pure_quanta q_res *
  page392_i57
#ISCELL
  standard offpage *
  page392_i58
#ISCELL
  standard offpage *
  page392_i59
#ISCELL
  standard offpage *
  page392_i60
#ISCELL
  standard offpage *
  page392_i61
#ISCELL
  standard offpage *
  page392_i62
#ISCELL
  standard offpage *
  page392_i63
#ISCELL
  pure_quanta_power universal_gnd *
  page392_i64
#CELL
  pure_quanta q_res *
  page392_i65
#CELL
  pure_quanta q_res *
  page392_i66
#ISCELL
  standard offpage *
  page392_i67
#ISCELL
  pure_quanta_power p1v0 *
  page392_i68
#ISCELL
  pure_quanta_power universal_gnd *
  page392_i69
#CELL
  pure_quanta q_res *
  page392_i70
#CELL
  pure_quanta q_res *
  page392_i71
#ISCELL
  standard offpage *
  page392_i73
#ISCELL
  standard offpage *
  page392_i74
#ISCELL
  standard offpage *
  page392_i76
#ISCELL
  standard offpage *
  page392_i77
#ISCELL
  standard offpage *
  page392_i78
#ISCELL
  pure_quanta_power gnd *
  page392_i87
#ISCELL
  pure_quanta_power gnd *
  page392_i88
#CELL
  pure_quanta q_res *
  page392_i92
#CELL
  pure_quanta q_res *
  page392_i93
#CELL
  pure_quanta q_res *
  page392_i94
#ISCELL
  standard offpage *
  page392_i95
#ISCELL
  standard offpage *
  page392_i96
#ISCELL
  pure_quanta_power p1v0 *
  page392_i97
#ISCELL
  mstr_misc dns *
  *
#ISCELL
  pure_quanta quanta_title_block_c *
  *
#ISCELL
  pure_quanta_power vcc_core *
  page391_i10
#ISCELL
  pure_quanta_power vcc_core *
  page391_i11
#ISCELL
  pure_quanta_power universal_gnd *
  page391_i12
#ISCELL
  pure_quanta_power p1v0 *
  page391_i13
#ISCELL
  pure_quanta_power universal_gnd *
  page391_i14
#CELL
  pure_quanta q_res *
  page391_i15
#CELL
  pure_quanta q_res *
  page391_i16
#ISCELL
  pure_quanta_power universal_gnd *
  page391_i17
#ISCELL
  pure_quanta_power universal_gnd *
  page391_i18
#CELL
  pure_quanta pt5161lrs *
  page391_i19
#CELL
  pure_quanta q_res *
  page391_i20
#CELL
  pure_quanta q_res *
  page391_i21
#ISCELL
  pure_quanta_power universal_gnd *
  page391_i3
#CELL
  pure_quanta pt5161lrs *
  page391_i5
#ISCELL
  pure_quanta_power p1v0 *
  page391_i7
#ISCELL
  pure_quanta_power p1v0 *
  page391_i8
#ISCELL
  pure_quanta_power p1v0 *
  page391_i9
#ISCELL
  pure_quanta quanta_title_block_c *
  *
#ISCELL
  standard offpage *
  page442_i1
#ISCELL
  pure_quanta_power universal_gnd *
  page442_i18
#CELL
  pure_quanta q_res *
  page442_i19
#ISCELL
  standard offpage *
  page442_i2
#ISCELL
  pure_quanta_power universal_gnd *
  page442_i20
#ISCELL
  pure_quanta_power p1v0 *
  page442_i21
#CELL
  pure_quanta q_cap *
  page442_i22
#ISCELL
  pure_quanta_power universal_gnd *
  page442_i23
#ISCELL
  pure_quanta_power universal_gnd *
  page442_i24
#CELL
  pure_quanta q_res *
  page442_i3
#CELL
  pure_quanta q_res *
  page442_i4
#CELL
  pure_quanta m24m02drmn6tp *
  page442_i5
#ISCELL
  mstr_misc dns *
  *
#ISCELL
  pure_quanta quanta_title_block_c *
  *
#ISCELL
  pure_quanta_power cad_note *
  *
#CELL
  pure_quanta q_res *
  page443_i10
#CELL
  pure_quanta q_res *
  page443_i11
#CELL
  pure_quanta q_inductor *
  page443_i12
#CELL
  pure_quanta q_cap *
  page443_i13
#CELL
  pure_quanta q_cap *
  page443_i14
#ISCELL
  pure_quanta_power p1v0 *
  page443_i15
#CELL
  pure_quanta q_cap *
  page443_i16
#CELL
  pure_quanta q_cap *
  page443_i17
#CELL
  pure_quanta q_cap *
  page443_i18
#ISCELL
  pure_quanta_power universal_gnd *
  page443_i19
#CELL
  pure_quanta q_cap *
  page443_i20
#ISCELL
  pure_quanta_power universal_gnd *
  page443_i21
#CELL
  pure_quanta q_cap *
  page443_i22
#CELL
  pure_quanta q_cap *
  page443_i23
#CELL
  pure_quanta q_cap *
  page443_i24
#CELL
  pure_quanta q_cap *
  page443_i25
#CELL
  pure_quanta q_cap *
  page443_i26
#CELL
  pure_quanta q_cap *
  page443_i27
#CELL
  pure_quanta q_cap *
  page443_i28
#CELL
  pure_quanta q_cap *
  page443_i29
#ISCELL
  pure_quanta_power p1v0 *
  page443_i3
#CELL
  pure_quanta q_inductor *
  page443_i30
#ISCELL
  pure_quanta_power vcc_core *
  page443_i31
#ISCELL
  pure_quanta_power vcc_core *
  page443_i33
#CELL
  pure_quanta q_cap *
  page443_i34
#ISCELL
  pure_quanta_power universal_gnd *
  page443_i35
#CELL
  pure_quanta q_cap *
  page443_i37
#CELL
  pure_quanta q_cap *
  page443_i38
#CELL
  pure_quanta q_cap *
  page443_i39
#CELL
  pure_quanta q_res *
  page443_i4
#CELL
  pure_quanta q_cap *
  page443_i40
#CELL
  pure_quanta q_cap *
  page443_i41
#CELL
  pure_quanta q_cap *
  page443_i42
#CELL
  pure_quanta q_cap *
  page443_i43
#CELL
  pure_quanta q_cap *
  page443_i44
#CELL
  pure_quanta q_cap *
  page443_i45
#CELL
  pure_quanta q_cap *
  page443_i46
#CELL
  pure_quanta q_cap *
  page443_i47
#CELL
  pure_quanta q_cap *
  page443_i48
#CELL
  pure_quanta q_cap *
  page443_i49
#CELL
  pure_quanta q_res *
  page443_i5
#CELL
  pure_quanta q_cap *
  page443_i50
#CELL
  pure_quanta q_cap *
  page443_i51
#CELL
  pure_quanta q_cap *
  page443_i52
#CELL
  pure_quanta q_cap *
  page443_i53
#CELL
  pure_quanta q_cap *
  page443_i54
#CELL
  pure_quanta q_cap *
  page443_i55
#CELL
  pure_quanta q_cap *
  page443_i57
#CELL
  pure_quanta q_cap *
  page443_i58
#CELL
  pure_quanta q_cap *
  page443_i59
#ISCELL
  pure_quanta_power p1v0 *
  page443_i6
#CELL
  pure_quanta q_cap *
  page443_i60
#ISCELL
  pure_quanta_power universal_gnd *
  page443_i61
#CELL
  pure_quanta q_cap *
  page443_i62
#ISCELL
  pure_quanta_power universal_gnd *
  page443_i63
#CELL
  pure_quanta q_cap *
  page443_i65
#CELL
  pure_quanta q_cap *
  page443_i66
#CELL
  pure_quanta q_cap *
  page443_i67
#ISCELL
  pure_quanta_power vcc_core *
  page443_i68
#CELL
  pure_quanta q_cap *
  page443_i69
#ISCELL
  pure_quanta_power universal_gnd *
  page443_i7
#CELL
  pure_quanta q_cap *
  page443_i70
#CELL
  pure_quanta q_cap *
  page443_i71
#CELL
  pure_quanta q_cap *
  page443_i72
#CELL
  pure_quanta q_cap *
  page443_i73
#CELL
  pure_quanta q_cap *
  page443_i74
#CELL
  pure_quanta q_cap *
  page443_i75
#CELL
  pure_quanta q_cap *
  page443_i76
#CELL
  pure_quanta q_cap *
  page443_i77
#CELL
  pure_quanta q_cap *
  page443_i78
#CELL
  pure_quanta q_cap *
  page443_i79
#CELL
  pure_quanta q_cap *
  page443_i8
#CELL
  pure_quanta q_cap *
  page443_i80
#CELL
  pure_quanta q_cap *
  page443_i81
#CELL
  pure_quanta q_cap *
  page443_i82
#ISCELL
  pure_quanta_power universal_gnd *
  page443_i83
#CELL
  pure_quanta q_cap *
  page443_i84
#CELL
  pure_quanta q_cap *
  page443_i85
#CELL
  pure_quanta q_cap *
  page443_i86
#CELL
  pure_quanta q_cap *
  page443_i87
#CELL
  pure_quanta q_inductor *
  page443_i88
#CELL
  pure_quanta q_res *
  page443_i89
#CELL
  pure_quanta q_cap *
  page443_i9
#CELL
  pure_quanta q_cap *
  page443_i90
#CELL
  pure_quanta q_cap *
  page443_i91
#CELL
  pure_quanta q_cap *
  page443_i92
#CELL
  pure_quanta q_cap *
  page443_i93
#CELL
  pure_quanta q_capp *
  page443_i94
#CELL
  pure_quanta q_capp *
  page443_i95
#CELL
  pure_quanta q_cap *
  page443_i96
#ISCELL
  pure_quanta quanta_title_block_c *
  *
#ISCELL
  pure_quanta quanta_title_block_c *
  *
#ISCELL
  pure_quanta quanta_title_block_c *
  *
#ISCELL
  pure_quanta quanta_title_block_c *
  *
#CELL
  pure_quanta pt5161lrs *
  page447_i1
#ISCELL
  standard tap *
  page447_i10
#ISCELL
  standard tap *
  page447_i11
#ISCELL
  standard tap *
  page447_i12
#ISCELL
  standard tap *
  page447_i13
#ISCELL
  standard tap *
  page447_i14
#ISCELL
  standard tap *
  page447_i15
#ISCELL
  standard tap *
  page447_i16
#ISCELL
  standard tap *
  page447_i17
#ISCELL
  standard offpage *
  page447_i18
#ISCELL
  standard offpage *
  page447_i19
#ISCELL
  standard tap *
  page447_i2
#ISCELL
  standard tap *
  page447_i20
#ISCELL
  standard tap *
  page447_i21
#ISCELL
  standard tap *
  page447_i22
#ISCELL
  standard tap *
  page447_i23
#ISCELL
  standard tap *
  page447_i24
#ISCELL
  standard tap *
  page447_i25
#ISCELL
  standard tap *
  page447_i26
#ISCELL
  standard tap *
  page447_i27
#ISCELL
  standard tap *
  page447_i28
#ISCELL
  standard tap *
  page447_i29
#ISCELL
  standard tap *
  page447_i3
#ISCELL
  standard tap *
  page447_i30
#ISCELL
  standard tap *
  page447_i31
#ISCELL
  standard tap *
  page447_i32
#ISCELL
  standard tap *
  page447_i33
#ISCELL
  standard tap *
  page447_i34
#ISCELL
  standard tap *
  page447_i35
#ISCELL
  standard offpage *
  page447_i36
#ISCELL
  standard offpage *
  page447_i37
#CELL
  pure_quanta pt5161lrs *
  page447_i38
#ISCELL
  standard tap *
  page447_i4
#ISCELL
  standard tap *
  page447_i5
#ISCELL
  standard tap *
  page447_i6
#ISCELL
  standard tap *
  page447_i7
#ISCELL
  standard tap *
  page447_i8
#ISCELL
  standard tap *
  page447_i9
#ISCELL
  pure_quanta quanta_title_block_c *
  *
#CELL
  pure_quanta pt5161lrs *
  page448_i1
#ISCELL
  standard tap *
  page448_i10
#ISCELL
  standard tap *
  page448_i11
#ISCELL
  standard tap *
  page448_i12
#ISCELL
  standard tap *
  page448_i13
#ISCELL
  standard tap *
  page448_i14
#ISCELL
  standard tap *
  page448_i15
#ISCELL
  standard tap *
  page448_i16
#ISCELL
  standard tap *
  page448_i17
#ISCELL
  standard offpage *
  page448_i18
#ISCELL
  standard offpage *
  page448_i19
#ISCELL
  standard tap *
  page448_i2
#ISCELL
  standard tap *
  page448_i20
#ISCELL
  standard tap *
  page448_i21
#ISCELL
  standard tap *
  page448_i22
#ISCELL
  standard tap *
  page448_i23
#ISCELL
  standard tap *
  page448_i24
#ISCELL
  standard tap *
  page448_i25
#ISCELL
  standard tap *
  page448_i26
#ISCELL
  standard tap *
  page448_i27
#ISCELL
  standard tap *
  page448_i28
#ISCELL
  standard tap *
  page448_i29
#ISCELL
  standard tap *
  page448_i3
#ISCELL
  standard tap *
  page448_i30
#ISCELL
  standard tap *
  page448_i31
#ISCELL
  standard tap *
  page448_i32
#ISCELL
  standard tap *
  page448_i33
#ISCELL
  standard tap *
  page448_i34
#ISCELL
  standard offpage *
  page448_i35
#ISCELL
  standard offpage *
  page448_i36
#ISCELL
  standard tap *
  page448_i37
#CELL
  pure_quanta pt5161lrs *
  page448_i38
#ISCELL
  standard tap *
  page448_i4
#ISCELL
  standard tap *
  page448_i5
#ISCELL
  standard tap *
  page448_i6
#ISCELL
  standard tap *
  page448_i7
#ISCELL
  standard tap *
  page448_i8
#ISCELL
  standard tap *
  page448_i9
#ISCELL
  pure_quanta quanta_title_block_c *
  *
#CELL
  pure_quanta pt5161lrs *
  page449_i1
#ISCELL
  standard tap *
  page449_i10
#ISCELL
  standard tap *
  page449_i11
#ISCELL
  standard tap *
  page449_i12
#ISCELL
  standard tap *
  page449_i13
#ISCELL
  standard tap *
  page449_i14
#ISCELL
  standard tap *
  page449_i15
#ISCELL
  standard tap *
  page449_i16
#ISCELL
  standard tap *
  page449_i17
#ISCELL
  standard offpage *
  page449_i18
#ISCELL
  standard offpage *
  page449_i19
#ISCELL
  standard tap *
  page449_i2
#ISCELL
  standard tap *
  page449_i20
#ISCELL
  standard tap *
  page449_i21
#ISCELL
  standard tap *
  page449_i22
#ISCELL
  standard tap *
  page449_i23
#ISCELL
  standard tap *
  page449_i24
#ISCELL
  standard tap *
  page449_i25
#ISCELL
  standard tap *
  page449_i26
#ISCELL
  standard tap *
  page449_i27
#ISCELL
  standard tap *
  page449_i28
#ISCELL
  standard tap *
  page449_i29
#ISCELL
  standard tap *
  page449_i3
#ISCELL
  standard tap *
  page449_i30
#ISCELL
  standard tap *
  page449_i31
#ISCELL
  standard tap *
  page449_i32
#ISCELL
  standard tap *
  page449_i33
#ISCELL
  standard tap *
  page449_i34
#ISCELL
  standard tap *
  page449_i35
#ISCELL
  standard offpage *
  page449_i36
#ISCELL
  standard offpage *
  page449_i37
#CELL
  pure_quanta pt5161lrs *
  page449_i38
#ISCELL
  standard tap *
  page449_i4
#ISCELL
  standard tap *
  page449_i5
#ISCELL
  standard tap *
  page449_i6
#ISCELL
  standard tap *
  page449_i7
#ISCELL
  standard tap *
  page449_i8
#ISCELL
  standard tap *
  page449_i9
#ISCELL
  pure_quanta quanta_title_block_c *
  *
#ISCELL
  standard offpage *
  page450_i1
#ISCELL
  standard tap *
  page450_i10
#ISCELL
  standard tap *
  page450_i100
#ISCELL
  standard tap *
  page450_i101
#CELL
  pure_quanta q_cap_diffbus *
  page450_i102
#CELL
  pure_quanta q_cap_diffbus *
  page450_i103
#ISCELL
  standard tap *
  page450_i104
#ISCELL
  standard tap *
  page450_i105
#ISCELL
  standard tap *
  page450_i106
#ISCELL
  standard tap *
  page450_i107
#ISCELL
  standard tap *
  page450_i108
#ISCELL
  standard tap *
  page450_i109
#ISCELL
  standard tap *
  page450_i11
#ISCELL
  standard tap *
  page450_i110
#ISCELL
  standard tap *
  page450_i111
#ISCELL
  standard tap *
  page450_i112
#ISCELL
  standard tap *
  page450_i113
#ISCELL
  standard tap *
  page450_i114
#ISCELL
  standard tap *
  page450_i115
#ISCELL
  standard tap *
  page450_i116
#ISCELL
  standard tap *
  page450_i117
#ISCELL
  standard tap *
  page450_i118
#ISCELL
  standard tap *
  page450_i119
#ISCELL
  standard tap *
  page450_i12
#ISCELL
  standard tap *
  page450_i120
#ISCELL
  standard tap *
  page450_i121
#ISCELL
  standard tap *
  page450_i122
#ISCELL
  standard tap *
  page450_i123
#ISCELL
  standard tap *
  page450_i124
#ISCELL
  standard tap *
  page450_i125
#ISCELL
  standard offpage *
  page450_i126
#ISCELL
  standard offpage *
  page450_i127
#ISCELL
  standard tap *
  page450_i128
#ISCELL
  standard tap *
  page450_i129
#ISCELL
  standard tap *
  page450_i13
#ISCELL
  standard tap *
  page450_i130
#ISCELL
  standard tap *
  page450_i131
#ISCELL
  standard tap *
  page450_i132
#ISCELL
  standard tap *
  page450_i133
#ISCELL
  standard tap *
  page450_i134
#ISCELL
  standard tap *
  page450_i135
#ISCELL
  standard tap *
  page450_i136
#ISCELL
  standard tap *
  page450_i137
#ISCELL
  standard offpage *
  page450_i138
#ISCELL
  standard offpage *
  page450_i139
#ISCELL
  standard tap *
  page450_i14
#ISCELL
  standard tap *
  page450_i140
#ISCELL
  standard tap *
  page450_i141
#CELL
  pure_quanta pt5161lrs *
  page450_i142
#ISCELL
  standard tap *
  page450_i15
#ISCELL
  standard tap *
  page450_i16
#CELL
  pure_quanta q_cap_diffbus *
  page450_i17
#CELL
  pure_quanta q_cap_diffbus *
  page450_i18
#CELL
  pure_quanta q_cap_diffbus *
  page450_i19
#ISCELL
  standard offpage *
  page450_i2
#CELL
  pure_quanta q_cap_diffbus *
  page450_i20
#CELL
  pure_quanta q_cap_diffbus *
  page450_i21
#CELL
  pure_quanta q_cap_diffbus *
  page450_i22
#CELL
  pure_quanta q_cap_diffbus *
  page450_i23
#CELL
  pure_quanta q_cap_diffbus *
  page450_i24
#CELL
  pure_quanta q_cap_diffbus *
  page450_i25
#CELL
  pure_quanta q_cap_diffbus *
  page450_i26
#CELL
  pure_quanta q_cap_diffbus *
  page450_i27
#CELL
  pure_quanta q_cap_diffbus *
  page450_i28
#CELL
  pure_quanta q_cap_diffbus *
  page450_i29
#ISCELL
  standard tap *
  page450_i3
#CELL
  pure_quanta q_cap_diffbus *
  page450_i30
#ISCELL
  standard tap *
  page450_i31
#ISCELL
  standard tap *
  page450_i32
#CELL
  pure_quanta pt5161lrs *
  page450_i33
#CELL
  pure_quanta q_cap_diffbus *
  page450_i34
#CELL
  pure_quanta q_cap_diffbus *
  page450_i35
#ISCELL
  standard tap *
  page450_i36
#ISCELL
  standard tap *
  page450_i37
#ISCELL
  standard tap *
  page450_i38
#ISCELL
  standard tap *
  page450_i39
#ISCELL
  standard tap *
  page450_i4
#ISCELL
  standard tap *
  page450_i40
#ISCELL
  standard tap *
  page450_i41
#ISCELL
  standard tap *
  page450_i42
#ISCELL
  standard tap *
  page450_i43
#ISCELL
  standard tap *
  page450_i44
#ISCELL
  standard tap *
  page450_i45
#ISCELL
  standard tap *
  page450_i46
#ISCELL
  standard tap *
  page450_i47
#ISCELL
  standard tap *
  page450_i48
#ISCELL
  standard tap *
  page450_i49
#ISCELL
  standard tap *
  page450_i5
#ISCELL
  standard tap *
  page450_i50
#ISCELL
  standard tap *
  page450_i51
#ISCELL
  standard tap *
  page450_i52
#ISCELL
  standard tap *
  page450_i53
#ISCELL
  standard tap *
  page450_i54
#ISCELL
  standard tap *
  page450_i55
#ISCELL
  standard tap *
  page450_i56
#ISCELL
  standard tap *
  page450_i57
#ISCELL
  standard offpage *
  page450_i58
#ISCELL
  standard offpage *
  page450_i59
#ISCELL
  standard tap *
  page450_i6
#ISCELL
  standard offpage *
  page450_i60
#ISCELL
  standard offpage *
  page450_i61
#ISCELL
  standard tap *
  page450_i62
#ISCELL
  standard tap *
  page450_i63
#ISCELL
  standard tap *
  page450_i64
#ISCELL
  standard tap *
  page450_i65
#ISCELL
  standard tap *
  page450_i66
#ISCELL
  standard tap *
  page450_i67
#ISCELL
  standard tap *
  page450_i68
#ISCELL
  standard tap *
  page450_i69
#ISCELL
  standard tap *
  page450_i7
#ISCELL
  standard tap *
  page450_i70
#ISCELL
  standard tap *
  page450_i71
#ISCELL
  standard offpage *
  page450_i72
#ISCELL
  standard offpage *
  page450_i73
#ISCELL
  standard tap *
  page450_i74
#ISCELL
  standard tap *
  page450_i75
#ISCELL
  standard tap *
  page450_i76
#ISCELL
  standard tap *
  page450_i77
#ISCELL
  standard tap *
  page450_i78
#ISCELL
  standard tap *
  page450_i79
#ISCELL
  standard tap *
  page450_i8
#ISCELL
  standard tap *
  page450_i80
#CELL
  pure_quanta q_cap_diffbus *
  page450_i81
#CELL
  pure_quanta q_cap_diffbus *
  page450_i82
#CELL
  pure_quanta q_cap_diffbus *
  page450_i83
#CELL
  pure_quanta q_cap_diffbus *
  page450_i84
#ISCELL
  standard tap *
  page450_i85
#ISCELL
  standard tap *
  page450_i86
#ISCELL
  standard tap *
  page450_i87
#ISCELL
  standard tap *
  page450_i88
#ISCELL
  standard tap *
  page450_i89
#ISCELL
  standard tap *
  page450_i9
#CELL
  pure_quanta q_cap_diffbus *
  page450_i90
#CELL
  pure_quanta q_cap_diffbus *
  page450_i91
#CELL
  pure_quanta q_cap_diffbus *
  page450_i92
#CELL
  pure_quanta q_cap_diffbus *
  page450_i93
#CELL
  pure_quanta q_cap_diffbus *
  page450_i94
#CELL
  pure_quanta q_cap_diffbus *
  page450_i95
#CELL
  pure_quanta q_cap_diffbus *
  page450_i96
#CELL
  pure_quanta q_cap_diffbus *
  page450_i97
#CELL
  pure_quanta q_cap_diffbus *
  page450_i98
#CELL
  pure_quanta q_cap_diffbus *
  page450_i99
#ISCELL
  mstr_misc dns *
  *
#ISCELL
  pure_quanta quanta_title_block_c *
  *
#ISCELL
  standard offpage *
  page451_i100
#CELL
  pure_quanta q_res *
  page451_i102
#ISCELL
  pure_quanta_power universal_gnd *
  page451_i107
#ISCELL
  pure_quanta_power gnd *
  page451_i108
#ISCELL
  pure_quanta_power universal_gnd *
  page451_i109
#CELL
  pure_quanta q_res *
  page451_i113
#CELL
  pure_quanta q_res *
  page451_i114
#ISCELL
  pure_quanta_power p1v0 *
  page451_i115
#ISCELL
  standard offpage *
  page451_i116
#CELL
  pure_quanta q_res *
  page451_i119
#ISCELL
  standard offpage *
  page451_i121
#ISCELL
  standard offpage *
  page451_i122
#ISCELL
  standard offpage *
  page451_i123
#ISCELL
  standard offpage *
  page451_i124
#CELL
  pure_quanta q_res *
  page451_i132
#ISCELL
  pure_quanta_power gnd *
  page451_i134
#CELL
  pure_quanta q_res *
  page451_i136
#CELL
  pure_quanta q_res *
  page451_i137
#ISCELL
  pure_quanta_power p1v0 *
  page451_i138
#CELL
  pure_quanta q_res *
  page451_i139
#CELL
  pure_quanta q_res *
  page451_i140
#ISCELL
  standard offpage *
  page451_i142
#ISCELL
  standard offpage *
  page451_i143
#ISCELL
  standard offpage *
  page451_i144
#ISCELL
  standard offpage *
  page451_i145
#ISCELL
  pure_quanta_power universal_gnd *
  page451_i15
#CELL
  pure_quanta q_res *
  page451_i17
#ISCELL
  pure_quanta_power p1v0 *
  page451_i18
#CELL
  pure_quanta q_res *
  page451_i19
#CELL
  pure_quanta q_res *
  page451_i20
#CELL
  pure_quanta q_res *
  page451_i21
#ISCELL
  pure_quanta_power p1v0 *
  page451_i22
#ISCELL
  standard offpage *
  page451_i23
#ISCELL
  standard offpage *
  page451_i24
#ISCELL
  standard offpage *
  page451_i25
#ISCELL
  standard offpage *
  page451_i26
#CELL
  pure_quanta q_res *
  page451_i27
#CELL
  pure_quanta q_res *
  page451_i28
#CELL
  pure_quanta q_res *
  page451_i29
#CELL
  pure_quanta q_res *
  page451_i30
#ISCELL
  standard offpage *
  page451_i31
#ISCELL
  standard offpage *
  page451_i32
#ISCELL
  standard offpage *
  page451_i33
#CELL
  pure_quanta q_res *
  page451_i34
#CELL
  pure_quanta q_res *
  page451_i35
#CELL
  pure_quanta q_res *
  page451_i36
#ISCELL
  standard offpage *
  page451_i37
#ISCELL
  standard offpage *
  page451_i38
#ISCELL
  standard offpage *
  page451_i39
#ISCELL
  standard offpage *
  page451_i40
#ISCELL
  standard offpage *
  page451_i41
#CELL
  pure_quanta q_res *
  page451_i42
#CELL
  pure_quanta q_res *
  page451_i43
#ISCELL
  pure_quanta_power universal_gnd *
  page451_i44
#CELL
  pure_quanta q_res *
  page451_i45
#CELL
  pure_quanta q_res *
  page451_i46
#CELL
  pure_quanta q_res *
  page451_i47
#CELL
  pure_quanta q_res *
  page451_i48
#CELL
  pure_quanta q_res *
  page451_i49
#CELL
  pure_quanta q_res *
  page451_i50
#ISCELL
  standard offpage *
  page451_i51
#ISCELL
  standard offpage *
  page451_i52
#ISCELL
  standard offpage *
  page451_i53
#ISCELL
  standard offpage *
  page451_i54
#ISCELL
  standard offpage *
  page451_i55
#ISCELL
  standard offpage *
  page451_i56
#ISCELL
  pure_quanta_power universal_gnd *
  page451_i57
#CELL
  pure_quanta q_res *
  page451_i58
#CELL
  pure_quanta q_res *
  page451_i59
#ISCELL
  pure_quanta_power p1v0 *
  page451_i60
#ISCELL
  pure_quanta_power universal_gnd *
  page451_i61
#CELL
  pure_quanta q_res *
  page451_i62
#CELL
  pure_quanta q_res *
  page451_i63
#ISCELL
  standard offpage *
  page451_i65
#ISCELL
  standard offpage *
  page451_i66
#ISCELL
  standard offpage *
  page451_i67
#ISCELL
  standard offpage *
  page451_i69
#ISCELL
  standard offpage *
  page451_i70
#CELL
  pure_quanta q_res *
  page451_i71
#CELL
  pure_quanta q_res *
  page451_i72
#ISCELL
  standard offpage *
  page451_i73
#CELL
  pure_quanta q_res *
  page451_i74
#CELL
  pure_quanta q_res *
  page451_i75
#CELL
  pure_quanta q_res *
  page451_i76
#CELL
  pure_quanta q_res *
  page451_i77
#ISCELL
  pure_quanta_power p1v0 *
  page451_i78
#ISCELL
  pure_quanta_power gnd *
  page451_i79
#CELL
  pure_quanta q_res *
  page451_i80
#ISCELL
  pure_quanta_power gnd *
  page451_i81
#CELL
  pure_quanta q_res *
  page451_i82
#ISCELL
  standard offpage *
  page451_i83
#ISCELL
  standard offpage *
  page451_i84
#ISCELL
  standard offpage *
  page451_i85
#CELL
  pure_quanta q_res *
  page451_i86
#ISCELL
  pure_quanta_power p1v0 *
  page451_i87
#ISCELL
  standard offpage *
  page451_i88
#ISCELL
  standard offpage *
  page451_i89
#ISCELL
  pure_quanta_power universal_gnd *
  page451_i90
#ISCELL
  pure_quanta_power universal_gnd *
  page451_i91
#CELL
  pure_quanta q_res *
  page451_i92
#ISCELL
  standard offpage *
  page451_i93
#ISCELL
  standard offpage *
  page451_i94
#ISCELL
  standard offpage *
  page451_i95
#ISCELL
  pure_quanta_power universal_gnd *
  page451_i96
#CELL
  pure_quanta pt5161lrs *
  page451_i97
#CELL
  pure_quanta q_res *
  page451_i98
#ISCELL
  mstr_misc dns *
  *
#ISCELL
  pure_quanta quanta_title_block_c *
  *
#ISCELL
  pure_quanta_power p1v0 *
  page452_i10
#ISCELL
  pure_quanta_power vcc_core *
  page452_i11
#ISCELL
  pure_quanta_power vcc_core *
  page452_i12
#ISCELL
  pure_quanta_power universal_gnd *
  page452_i13
#ISCELL
  pure_quanta_power universal_gnd *
  page452_i14
#CELL
  pure_quanta q_res *
  page452_i15
#ISCELL
  pure_quanta_power universal_gnd *
  page452_i16
#ISCELL
  pure_quanta_power universal_gnd *
  page452_i17
#CELL
  pure_quanta q_res *
  page452_i18
#CELL
  pure_quanta pt5161lrs *
  page452_i19
#CELL
  pure_quanta q_res *
  page452_i20
#CELL
  pure_quanta q_res *
  page452_i21
#ISCELL
  pure_quanta_power p1v0 *
  page452_i4
#ISCELL
  pure_quanta_power universal_gnd *
  page452_i5
#CELL
  pure_quanta pt5161lrs *
  page452_i7
#ISCELL
  pure_quanta_power p1v0 *
  page452_i8
#ISCELL
  pure_quanta_power p1v0 *
  page452_i9
#ISCELL
  pure_quanta quanta_title_block_c *
  *
#ISCELL
  standard offpage *
  page453_i1
#ISCELL
  pure_quanta_power universal_gnd *
  page453_i18
#CELL
  pure_quanta q_res *
  page453_i19
#ISCELL
  standard offpage *
  page453_i2
#ISCELL
  pure_quanta_power universal_gnd *
  page453_i20
#ISCELL
  pure_quanta_power universal_gnd *
  page453_i21
#ISCELL
  pure_quanta_power p1v0 *
  page453_i22
#CELL
  pure_quanta q_cap *
  page453_i23
#ISCELL
  pure_quanta_power universal_gnd *
  page453_i24
#CELL
  pure_quanta q_res *
  page453_i3
#CELL
  pure_quanta q_res *
  page453_i4
#CELL
  pure_quanta m24m02drmn6tp *
  page453_i5
#ISCELL
  mstr_misc dns *
  *
#ISCELL
  pure_quanta quanta_title_block_c *
  *
#ISCELL
  pure_quanta_power cad_note *
  *
#CELL
  pure_quanta q_cap *
  page454_i10
#CELL
  pure_quanta q_cap *
  page454_i100
#CELL
  pure_quanta q_capp *
  page454_i101
#CELL
  pure_quanta q_cap *
  page454_i102
#CELL
  pure_quanta q_cap *
  page454_i103
#CELL
  pure_quanta q_cap *
  page454_i104
#CELL
  pure_quanta q_cap *
  page454_i105
#CELL
  pure_quanta q_cap *
  page454_i11
#CELL
  pure_quanta q_cap *
  page454_i12
#CELL
  pure_quanta q_cap *
  page454_i13
#ISCELL
  pure_quanta_power universal_gnd *
  page454_i14
#CELL
  pure_quanta q_cap *
  page454_i15
#CELL
  pure_quanta q_cap *
  page454_i16
#CELL
  pure_quanta q_cap *
  page454_i17
#CELL
  pure_quanta q_cap *
  page454_i18
#CELL
  pure_quanta q_cap *
  page454_i19
#CELL
  pure_quanta q_res *
  page454_i2
#CELL
  pure_quanta q_res *
  page454_i20
#CELL
  pure_quanta q_inductor *
  page454_i21
#ISCELL
  pure_quanta_power p1v0 *
  page454_i22
#ISCELL
  pure_quanta_power p1v0 *
  page454_i23
#CELL
  pure_quanta q_cap *
  page454_i24
#CELL
  pure_quanta q_cap *
  page454_i25
#ISCELL
  pure_quanta_power universal_gnd *
  page454_i26
#CELL
  pure_quanta q_cap *
  page454_i27
#CELL
  pure_quanta q_cap *
  page454_i28
#ISCELL
  pure_quanta_power vcc_core *
  page454_i29
#CELL
  pure_quanta q_res *
  page454_i3
#ISCELL
  pure_quanta_power vcc_core *
  page454_i30
#CELL
  pure_quanta q_cap *
  page454_i31
#ISCELL
  pure_quanta_power universal_gnd *
  page454_i34
#CELL
  pure_quanta q_cap *
  page454_i35
#CELL
  pure_quanta q_cap *
  page454_i36
#CELL
  pure_quanta q_cap *
  page454_i37
#CELL
  pure_quanta q_cap *
  page454_i38
#CELL
  pure_quanta q_cap *
  page454_i39
#CELL
  pure_quanta q_cap *
  page454_i40
#CELL
  pure_quanta q_res *
  page454_i41
#CELL
  pure_quanta q_cap *
  page454_i42
#CELL
  pure_quanta q_cap *
  page454_i43
#CELL
  pure_quanta q_cap *
  page454_i44
#CELL
  pure_quanta q_cap *
  page454_i45
#CELL
  pure_quanta q_cap *
  page454_i46
#CELL
  pure_quanta q_cap *
  page454_i47
#CELL
  pure_quanta q_cap *
  page454_i48
#CELL
  pure_quanta q_cap *
  page454_i49
#CELL
  pure_quanta q_cap *
  page454_i5
#CELL
  pure_quanta q_cap *
  page454_i50
#CELL
  pure_quanta q_cap *
  page454_i51
#CELL
  pure_quanta q_cap *
  page454_i52
#CELL
  pure_quanta q_cap *
  page454_i53
#CELL
  pure_quanta q_cap *
  page454_i54
#CELL
  pure_quanta q_cap *
  page454_i55
#CELL
  pure_quanta q_cap *
  page454_i56
#CELL
  pure_quanta q_cap *
  page454_i57
#CELL
  pure_quanta q_cap *
  page454_i58
#CELL
  pure_quanta q_cap *
  page454_i59
#CELL
  pure_quanta q_cap *
  page454_i6
#CELL
  pure_quanta q_cap *
  page454_i60
#CELL
  pure_quanta q_cap *
  page454_i61
#CELL
  pure_quanta q_cap *
  page454_i62
#ISCELL
  pure_quanta_power universal_gnd *
  page454_i63
#CELL
  pure_quanta q_cap *
  page454_i64
#CELL
  pure_quanta q_cap *
  page454_i67
#CELL
  pure_quanta q_cap *
  page454_i68
#CELL
  pure_quanta q_cap *
  page454_i69
#ISCELL
  pure_quanta_power universal_gnd *
  page454_i7
#CELL
  pure_quanta q_cap *
  page454_i70
#CELL
  pure_quanta q_cap *
  page454_i71
#CELL
  pure_quanta q_cap *
  page454_i72
#ISCELL
  pure_quanta_power universal_gnd *
  page454_i73
#CELL
  pure_quanta q_inductor *
  page454_i74
#ISCELL
  pure_quanta_power vcc_core *
  page454_i75
#CELL
  pure_quanta q_cap *
  page454_i76
#CELL
  pure_quanta q_cap *
  page454_i77
#CELL
  pure_quanta q_cap *
  page454_i78
#CELL
  pure_quanta q_cap *
  page454_i79
#CELL
  pure_quanta q_cap *
  page454_i8
#CELL
  pure_quanta q_cap *
  page454_i80
#ISCELL
  pure_quanta_power universal_gnd *
  page454_i81
#CELL
  pure_quanta q_cap *
  page454_i82
#CELL
  pure_quanta q_cap *
  page454_i83
#CELL
  pure_quanta q_cap *
  page454_i84
#CELL
  pure_quanta q_cap *
  page454_i85
#CELL
  pure_quanta q_cap *
  page454_i86
#CELL
  pure_quanta q_cap *
  page454_i87
#CELL
  pure_quanta q_inductor *
  page454_i88
#CELL
  pure_quanta q_res *
  page454_i89
#ISCELL
  pure_quanta_power p1v0 *
  page454_i9
#CELL
  pure_quanta q_cap *
  page454_i90
#CELL
  pure_quanta q_cap *
  page454_i91
#CELL
  pure_quanta q_cap *
  page454_i92
#CELL
  pure_quanta q_cap *
  page454_i93
#CELL
  pure_quanta q_capp *
  page454_i94
#CELL
  pure_quanta q_capp *
  page454_i95
#CELL
  pure_quanta q_cap *
  page454_i96
#CELL
  pure_quanta q_cap *
  page454_i97
#CELL
  pure_quanta q_capp *
  page454_i98
#CELL
  pure_quanta q_capp *
  page454_i99
#ISCELL
  pure_quanta quanta_title_block_c *
  *
#ISCELL
  pure_quanta quanta_title_block_c *
  *
#ISCELL
  pure_quanta quanta_title_block_c *
  *
#ISCELL
  pure_quanta quanta_title_block_c *
  *
#CELL
  pure_quanta pt5161lrs *
  page458_i1
#ISCELL
  standard tap *
  page458_i10
#ISCELL
  standard tap *
  page458_i11
#ISCELL
  standard tap *
  page458_i12
#ISCELL
  standard tap *
  page458_i13
#ISCELL
  standard tap *
  page458_i14
#ISCELL
  standard tap *
  page458_i15
#ISCELL
  standard tap *
  page458_i16
#ISCELL
  standard tap *
  page458_i17
#ISCELL
  standard offpage *
  page458_i18
#ISCELL
  standard offpage *
  page458_i19
#ISCELL
  standard tap *
  page458_i2
#ISCELL
  standard tap *
  page458_i20
#ISCELL
  standard tap *
  page458_i21
#ISCELL
  standard tap *
  page458_i22
#ISCELL
  standard tap *
  page458_i23
#ISCELL
  standard tap *
  page458_i24
#ISCELL
  standard tap *
  page458_i25
#ISCELL
  standard tap *
  page458_i26
#ISCELL
  standard tap *
  page458_i27
#ISCELL
  standard tap *
  page458_i28
#ISCELL
  standard tap *
  page458_i29
#ISCELL
  standard tap *
  page458_i3
#ISCELL
  standard tap *
  page458_i30
#ISCELL
  standard tap *
  page458_i31
#ISCELL
  standard tap *
  page458_i32
#ISCELL
  standard tap *
  page458_i33
#ISCELL
  standard tap *
  page458_i34
#ISCELL
  standard tap *
  page458_i35
#ISCELL
  standard offpage *
  page458_i36
#ISCELL
  standard offpage *
  page458_i37
#CELL
  pure_quanta pt5161lrs *
  page458_i38
#ISCELL
  standard tap *
  page458_i4
#ISCELL
  standard tap *
  page458_i5
#ISCELL
  standard tap *
  page458_i6
#ISCELL
  standard tap *
  page458_i7
#ISCELL
  standard tap *
  page458_i8
#ISCELL
  standard tap *
  page458_i9
#ISCELL
  pure_quanta quanta_title_block_c *
  *
#CELL
  pure_quanta pt5161lrs *
  page459_i1
#ISCELL
  standard tap *
  page459_i10
#ISCELL
  standard tap *
  page459_i11
#ISCELL
  standard tap *
  page459_i12
#ISCELL
  standard tap *
  page459_i13
#ISCELL
  standard tap *
  page459_i14
#ISCELL
  standard tap *
  page459_i15
#ISCELL
  standard tap *
  page459_i16
#ISCELL
  standard tap *
  page459_i17
#ISCELL
  standard offpage *
  page459_i18
#ISCELL
  standard offpage *
  page459_i19
#ISCELL
  standard tap *
  page459_i2
#ISCELL
  standard tap *
  page459_i20
#ISCELL
  standard tap *
  page459_i21
#ISCELL
  standard tap *
  page459_i22
#ISCELL
  standard tap *
  page459_i23
#ISCELL
  standard tap *
  page459_i24
#ISCELL
  standard tap *
  page459_i25
#ISCELL
  standard tap *
  page459_i26
#ISCELL
  standard tap *
  page459_i27
#ISCELL
  standard tap *
  page459_i28
#ISCELL
  standard tap *
  page459_i29
#ISCELL
  standard tap *
  page459_i3
#ISCELL
  standard tap *
  page459_i30
#ISCELL
  standard tap *
  page459_i31
#ISCELL
  standard tap *
  page459_i32
#ISCELL
  standard tap *
  page459_i33
#ISCELL
  standard tap *
  page459_i34
#ISCELL
  standard offpage *
  page459_i35
#ISCELL
  standard offpage *
  page459_i36
#ISCELL
  standard tap *
  page459_i37
#CELL
  pure_quanta pt5161lrs *
  page459_i38
#ISCELL
  standard tap *
  page459_i4
#ISCELL
  standard tap *
  page459_i5
#ISCELL
  standard tap *
  page459_i6
#ISCELL
  standard tap *
  page459_i7
#ISCELL
  standard tap *
  page459_i8
#ISCELL
  standard tap *
  page459_i9
#ISCELL
  pure_quanta quanta_title_block_c *
  *
#CELL
  pure_quanta pt5161lrs *
  page460_i1
#ISCELL
  standard tap *
  page460_i10
#ISCELL
  standard tap *
  page460_i11
#ISCELL
  standard tap *
  page460_i12
#ISCELL
  standard tap *
  page460_i13
#ISCELL
  standard tap *
  page460_i14
#ISCELL
  standard tap *
  page460_i15
#ISCELL
  standard tap *
  page460_i16
#ISCELL
  standard tap *
  page460_i17
#ISCELL
  standard offpage *
  page460_i18
#ISCELL
  standard offpage *
  page460_i19
#ISCELL
  standard tap *
  page460_i2
#ISCELL
  standard tap *
  page460_i20
#ISCELL
  standard tap *
  page460_i21
#ISCELL
  standard tap *
  page460_i22
#ISCELL
  standard tap *
  page460_i23
#ISCELL
  standard tap *
  page460_i24
#ISCELL
  standard tap *
  page460_i25
#ISCELL
  standard tap *
  page460_i26
#ISCELL
  standard tap *
  page460_i27
#ISCELL
  standard tap *
  page460_i28
#ISCELL
  standard tap *
  page460_i29
#ISCELL
  standard tap *
  page460_i3
#ISCELL
  standard tap *
  page460_i30
#ISCELL
  standard tap *
  page460_i31
#ISCELL
  standard tap *
  page460_i32
#ISCELL
  standard tap *
  page460_i33
#ISCELL
  standard tap *
  page460_i34
#ISCELL
  standard tap *
  page460_i35
#ISCELL
  standard offpage *
  page460_i36
#ISCELL
  standard offpage *
  page460_i37
#CELL
  pure_quanta pt5161lrs *
  page460_i38
#ISCELL
  standard tap *
  page460_i4
#ISCELL
  standard tap *
  page460_i5
#ISCELL
  standard tap *
  page460_i6
#ISCELL
  standard tap *
  page460_i7
#ISCELL
  standard tap *
  page460_i8
#ISCELL
  standard tap *
  page460_i9
#ISCELL
  pure_quanta quanta_title_block_c *
  *
#ISCELL
  standard offpage *
  page461_i1
#ISCELL
  standard tap *
  page461_i10
#CELL
  pure_quanta q_cap_diffbus *
  page461_i100
#CELL
  pure_quanta q_cap_diffbus *
  page461_i101
#ISCELL
  standard tap *
  page461_i102
#ISCELL
  standard tap *
  page461_i103
#CELL
  pure_quanta q_cap_diffbus *
  page461_i104
#CELL
  pure_quanta q_cap_diffbus *
  page461_i105
#ISCELL
  standard tap *
  page461_i106
#ISCELL
  standard tap *
  page461_i107
#ISCELL
  standard tap *
  page461_i108
#ISCELL
  standard tap *
  page461_i109
#ISCELL
  standard tap *
  page461_i11
#ISCELL
  standard tap *
  page461_i110
#ISCELL
  standard tap *
  page461_i111
#ISCELL
  standard tap *
  page461_i112
#ISCELL
  standard tap *
  page461_i113
#ISCELL
  standard tap *
  page461_i114
#ISCELL
  standard tap *
  page461_i115
#ISCELL
  standard tap *
  page461_i116
#ISCELL
  standard tap *
  page461_i117
#ISCELL
  standard tap *
  page461_i118
#ISCELL
  standard tap *
  page461_i119
#ISCELL
  standard tap *
  page461_i12
#ISCELL
  standard tap *
  page461_i120
#ISCELL
  standard tap *
  page461_i121
#ISCELL
  standard tap *
  page461_i122
#ISCELL
  standard tap *
  page461_i123
#ISCELL
  standard tap *
  page461_i124
#ISCELL
  standard tap *
  page461_i125
#ISCELL
  standard tap *
  page461_i126
#ISCELL
  standard offpage *
  page461_i127
#ISCELL
  standard offpage *
  page461_i128
#ISCELL
  standard tap *
  page461_i129
#ISCELL
  standard tap *
  page461_i13
#ISCELL
  standard tap *
  page461_i130
#ISCELL
  standard tap *
  page461_i131
#ISCELL
  standard tap *
  page461_i132
#ISCELL
  standard tap *
  page461_i133
#ISCELL
  standard tap *
  page461_i134
#ISCELL
  standard tap *
  page461_i135
#ISCELL
  standard tap *
  page461_i136
#ISCELL
  standard tap *
  page461_i137
#ISCELL
  standard tap *
  page461_i138
#ISCELL
  standard offpage *
  page461_i139
#ISCELL
  standard tap *
  page461_i14
#ISCELL
  standard offpage *
  page461_i140
#ISCELL
  standard tap *
  page461_i141
#CELL
  pure_quanta pt5161lrs *
  page461_i142
#ISCELL
  standard tap *
  page461_i15
#CELL
  pure_quanta q_cap_diffbus *
  page461_i16
#CELL
  pure_quanta q_cap_diffbus *
  page461_i17
#CELL
  pure_quanta q_cap_diffbus *
  page461_i18
#ISCELL
  standard tap *
  page461_i19
#ISCELL
  standard offpage *
  page461_i2
#ISCELL
  standard tap *
  page461_i20
#ISCELL
  standard tap *
  page461_i21
#CELL
  pure_quanta q_cap_diffbus *
  page461_i22
#CELL
  pure_quanta q_cap_diffbus *
  page461_i23
#CELL
  pure_quanta q_cap_diffbus *
  page461_i24
#CELL
  pure_quanta q_cap_diffbus *
  page461_i25
#CELL
  pure_quanta q_cap_diffbus *
  page461_i26
#CELL
  pure_quanta q_cap_diffbus *
  page461_i27
#CELL
  pure_quanta q_cap_diffbus *
  page461_i28
#CELL
  pure_quanta q_cap_diffbus *
  page461_i29
#ISCELL
  standard tap *
  page461_i3
#CELL
  pure_quanta q_cap_diffbus *
  page461_i30
#CELL
  pure_quanta q_cap_diffbus *
  page461_i31
#CELL
  pure_quanta q_cap_diffbus *
  page461_i32
#ISCELL
  standard tap *
  page461_i33
#ISCELL
  standard tap *
  page461_i34
#ISCELL
  standard tap *
  page461_i35
#ISCELL
  standard tap *
  page461_i36
#ISCELL
  standard tap *
  page461_i37
#ISCELL
  standard tap *
  page461_i38
#ISCELL
  standard tap *
  page461_i39
#ISCELL
  standard tap *
  page461_i4
#ISCELL
  standard tap *
  page461_i40
#ISCELL
  standard tap *
  page461_i41
#ISCELL
  standard tap *
  page461_i42
#ISCELL
  standard tap *
  page461_i43
#ISCELL
  standard tap *
  page461_i44
#ISCELL
  standard tap *
  page461_i45
#CELL
  pure_quanta pt5161lrs *
  page461_i46
#CELL
  pure_quanta q_cap_diffbus *
  page461_i47
#CELL
  pure_quanta q_cap_diffbus *
  page461_i48
#ISCELL
  standard tap *
  page461_i49
#ISCELL
  standard tap *
  page461_i5
#ISCELL
  standard tap *
  page461_i50
#ISCELL
  standard tap *
  page461_i51
#ISCELL
  standard tap *
  page461_i52
#ISCELL
  standard tap *
  page461_i53
#ISCELL
  standard tap *
  page461_i54
#ISCELL
  standard tap *
  page461_i55
#ISCELL
  standard tap *
  page461_i56
#ISCELL
  standard offpage *
  page461_i57
#ISCELL
  standard offpage *
  page461_i58
#ISCELL
  standard offpage *
  page461_i59
#ISCELL
  standard tap *
  page461_i6
#ISCELL
  standard offpage *
  page461_i60
#ISCELL
  standard tap *
  page461_i61
#ISCELL
  standard tap *
  page461_i62
#ISCELL
  standard tap *
  page461_i63
#ISCELL
  standard tap *
  page461_i64
#ISCELL
  standard tap *
  page461_i65
#ISCELL
  standard tap *
  page461_i66
#ISCELL
  standard tap *
  page461_i67
#ISCELL
  standard tap *
  page461_i68
#ISCELL
  standard tap *
  page461_i69
#ISCELL
  standard tap *
  page461_i7
#ISCELL
  standard tap *
  page461_i70
#ISCELL
  standard tap *
  page461_i71
#ISCELL
  standard offpage *
  page461_i72
#ISCELL
  standard offpage *
  page461_i73
#ISCELL
  standard tap *
  page461_i74
#ISCELL
  standard tap *
  page461_i75
#ISCELL
  standard tap *
  page461_i76
#ISCELL
  standard tap *
  page461_i77
#ISCELL
  standard tap *
  page461_i78
#ISCELL
  standard tap *
  page461_i79
#ISCELL
  standard tap *
  page461_i8
#ISCELL
  standard tap *
  page461_i80
#ISCELL
  standard tap *
  page461_i81
#ISCELL
  standard tap *
  page461_i82
#ISCELL
  standard tap *
  page461_i83
#ISCELL
  standard tap *
  page461_i84
#ISCELL
  standard tap *
  page461_i85
#ISCELL
  standard tap *
  page461_i86
#ISCELL
  standard tap *
  page461_i87
#CELL
  pure_quanta q_cap_diffbus *
  page461_i88
#CELL
  pure_quanta q_cap_diffbus *
  page461_i89
#ISCELL
  standard tap *
  page461_i9
#CELL
  pure_quanta q_cap_diffbus *
  page461_i90
#CELL
  pure_quanta q_cap_diffbus *
  page461_i91
#CELL
  pure_quanta q_cap_diffbus *
  page461_i92
#CELL
  pure_quanta q_cap_diffbus *
  page461_i93
#CELL
  pure_quanta q_cap_diffbus *
  page461_i94
#CELL
  pure_quanta q_cap_diffbus *
  page461_i95
#CELL
  pure_quanta q_cap_diffbus *
  page461_i96
#CELL
  pure_quanta q_cap_diffbus *
  page461_i97
#CELL
  pure_quanta q_cap_diffbus *
  page461_i98
#CELL
  pure_quanta q_cap_diffbus *
  page461_i99
#ISCELL
  mstr_misc dns *
  *
#ISCELL
  pure_quanta quanta_title_block_c *
  *
#ISCELL
  standard offpage *
  page462_i100
#CELL
  pure_quanta q_res *
  page462_i103
#ISCELL
  pure_quanta_power universal_gnd *
  page462_i107
#ISCELL
  pure_quanta_power gnd *
  page462_i108
#ISCELL
  pure_quanta_power universal_gnd *
  page462_i110
#CELL
  pure_quanta q_res *
  page462_i114
#CELL
  pure_quanta q_res *
  page462_i115
#ISCELL
  standard offpage *
  page462_i116
#ISCELL
  pure_quanta_power p1v0 *
  page462_i117
#CELL
  pure_quanta q_res *
  page462_i119
#ISCELL
  standard offpage *
  page462_i121
#ISCELL
  standard offpage *
  page462_i122
#ISCELL
  standard offpage *
  page462_i123
#ISCELL
  standard offpage *
  page462_i124
#CELL
  pure_quanta q_res *
  page462_i132
#ISCELL
  pure_quanta_power gnd *
  page462_i134
#CELL
  pure_quanta q_res *
  page462_i136
#CELL
  pure_quanta q_res *
  page462_i137
#ISCELL
  pure_quanta_power p1v0 *
  page462_i138
#CELL
  pure_quanta q_res *
  page462_i139
#CELL
  pure_quanta q_res *
  page462_i140
#ISCELL
  standard offpage *
  page462_i142
#ISCELL
  standard offpage *
  page462_i143
#ISCELL
  standard offpage *
  page462_i144
#ISCELL
  standard offpage *
  page462_i145
#CELL
  pure_quanta q_res *
  page462_i146
#ISCELL
  pure_quanta_power universal_gnd *
  page462_i15
#CELL
  pure_quanta q_res *
  page462_i17
#ISCELL
  pure_quanta_power p1v0 *
  page462_i18
#CELL
  pure_quanta q_res *
  page462_i19
#CELL
  pure_quanta q_res *
  page462_i20
#CELL
  pure_quanta q_res *
  page462_i21
#CELL
  pure_quanta q_res *
  page462_i22
#CELL
  pure_quanta q_res *
  page462_i23
#ISCELL
  pure_quanta_power p1v0 *
  page462_i24
#ISCELL
  standard offpage *
  page462_i25
#ISCELL
  standard offpage *
  page462_i26
#ISCELL
  standard offpage *
  page462_i27
#ISCELL
  standard offpage *
  page462_i28
#ISCELL
  pure_quanta_power universal_gnd *
  page462_i29
#CELL
  pure_quanta q_res *
  page462_i30
#CELL
  pure_quanta q_res *
  page462_i31
#CELL
  pure_quanta q_res *
  page462_i32
#CELL
  pure_quanta q_res *
  page462_i33
#ISCELL
  standard offpage *
  page462_i35
#ISCELL
  standard offpage *
  page462_i36
#ISCELL
  standard offpage *
  page462_i37
#ISCELL
  standard offpage *
  page462_i38
#ISCELL
  standard offpage *
  page462_i39
#ISCELL
  standard offpage *
  page462_i40
#CELL
  pure_quanta q_res *
  page462_i41
#CELL
  pure_quanta q_res *
  page462_i42
#ISCELL
  standard offpage *
  page462_i43
#ISCELL
  standard offpage *
  page462_i44
#ISCELL
  pure_quanta_power universal_gnd *
  page462_i45
#CELL
  pure_quanta q_res *
  page462_i46
#ISCELL
  standard offpage *
  page462_i47
#ISCELL
  standard offpage *
  page462_i48
#ISCELL
  standard offpage *
  page462_i49
#CELL
  pure_quanta q_res *
  page462_i50
#CELL
  pure_quanta q_res *
  page462_i51
#ISCELL
  pure_quanta_power universal_gnd *
  page462_i52
#CELL
  pure_quanta q_res *
  page462_i53
#CELL
  pure_quanta q_res *
  page462_i54
#CELL
  pure_quanta q_res *
  page462_i55
#CELL
  pure_quanta q_res *
  page462_i56
#ISCELL
  standard offpage *
  page462_i57
#ISCELL
  standard offpage *
  page462_i58
#ISCELL
  standard offpage *
  page462_i59
#ISCELL
  standard offpage *
  page462_i60
#ISCELL
  standard offpage *
  page462_i61
#ISCELL
  standard offpage *
  page462_i62
#ISCELL
  pure_quanta_power universal_gnd *
  page462_i63
#CELL
  pure_quanta q_res *
  page462_i64
#CELL
  pure_quanta q_res *
  page462_i65
#ISCELL
  standard offpage *
  page462_i66
#ISCELL
  pure_quanta_power p1v0 *
  page462_i67
#ISCELL
  pure_quanta_power universal_gnd *
  page462_i68
#CELL
  pure_quanta q_res *
  page462_i69
#CELL
  pure_quanta q_res *
  page462_i70
#ISCELL
  standard offpage *
  page462_i72
#ISCELL
  standard offpage *
  page462_i73
#ISCELL
  standard offpage *
  page462_i74
#ISCELL
  standard offpage *
  page462_i76
#ISCELL
  standard offpage *
  page462_i77
#ISCELL
  pure_quanta_power universal_gnd *
  page462_i78
#CELL
  pure_quanta q_res *
  page462_i79
#CELL
  pure_quanta q_res *
  page462_i80
#CELL
  pure_quanta q_res *
  page462_i81
#CELL
  pure_quanta q_res *
  page462_i82
#CELL
  pure_quanta q_res *
  page462_i83
#CELL
  pure_quanta q_res *
  page462_i84
#ISCELL
  standard offpage *
  page462_i85
#ISCELL
  standard offpage *
  page462_i86
#ISCELL
  standard offpage *
  page462_i87
#ISCELL
  pure_quanta_power p1v0 *
  page462_i88
#ISCELL
  pure_quanta_power gnd *
  page462_i89
#CELL
  pure_quanta q_res *
  page462_i90
#ISCELL
  pure_quanta_power gnd *
  page462_i91
#CELL
  pure_quanta q_res *
  page462_i92
#CELL
  pure_quanta q_res *
  page462_i93
#ISCELL
  standard offpage *
  page462_i94
#ISCELL
  standard offpage *
  page462_i95
#ISCELL
  pure_quanta_power p1v0 *
  page462_i96
#CELL
  pure_quanta pt5161lrs *
  page462_i97
#CELL
  pure_quanta q_res *
  page462_i98
#ISCELL
  mstr_misc dns *
  *
#ISCELL
  pure_quanta quanta_title_block_c *
  *
#ISCELL
  pure_quanta_power vcc_core *
  page463_i10
#ISCELL
  pure_quanta_power universal_gnd *
  page463_i11
#ISCELL
  pure_quanta_power universal_gnd *
  page463_i12
#CELL
  pure_quanta q_res *
  page463_i13
#ISCELL
  pure_quanta_power universal_gnd *
  page463_i14
#CELL
  pure_quanta q_res *
  page463_i15
#ISCELL
  pure_quanta_power universal_gnd *
  page463_i16
#CELL
  pure_quanta pt5161lrs *
  page463_i17
#CELL
  pure_quanta q_res *
  page463_i18
#CELL
  pure_quanta q_res *
  page463_i19
#ISCELL
  pure_quanta_power p1v0 *
  page463_i2
#ISCELL
  pure_quanta_power universal_gnd *
  page463_i3
#CELL
  pure_quanta pt5161lrs *
  page463_i5
#ISCELL
  pure_quanta_power p1v0 *
  page463_i6
#ISCELL
  pure_quanta_power p1v0 *
  page463_i7
#ISCELL
  pure_quanta_power p1v0 *
  page463_i8
#ISCELL
  pure_quanta_power vcc_core *
  page463_i9
#ISCELL
  pure_quanta quanta_title_block_c *
  *
#ISCELL
  standard offpage *
  page464_i1
#ISCELL
  pure_quanta_power p1v0 *
  page464_i18
#CELL
  pure_quanta q_cap *
  page464_i19
#ISCELL
  standard offpage *
  page464_i2
#ISCELL
  pure_quanta_power universal_gnd *
  page464_i20
#ISCELL
  pure_quanta_power universal_gnd *
  page464_i21
#CELL
  pure_quanta q_res *
  page464_i22
#ISCELL
  pure_quanta_power universal_gnd *
  page464_i23
#ISCELL
  pure_quanta_power universal_gnd *
  page464_i24
#CELL
  pure_quanta q_res *
  page464_i25
#CELL
  pure_quanta q_res *
  page464_i4
#CELL
  pure_quanta m24m02drmn6tp *
  page464_i5
#ISCELL
  mstr_misc dns *
  *
#ISCELL
  pure_quanta quanta_title_block_c *
  *
#ISCELL
  pure_quanta_power cad_note *
  *
#CELL
  pure_quanta q_res *
  page465_i1
#CELL
  pure_quanta q_inductor *
  page465_i11
#ISCELL
  pure_quanta_power p1v0 *
  page465_i12
#ISCELL
  pure_quanta_power p1v0 *
  page465_i13
#CELL
  pure_quanta q_cap *
  page465_i14
#CELL
  pure_quanta q_cap *
  page465_i15
#CELL
  pure_quanta q_cap *
  page465_i16
#CELL
  pure_quanta q_cap *
  page465_i17
#CELL
  pure_quanta q_cap *
  page465_i18
#CELL
  pure_quanta q_cap *
  page465_i19
#CELL
  pure_quanta q_res *
  page465_i2
#CELL
  pure_quanta q_cap *
  page465_i20
#CELL
  pure_quanta q_cap *
  page465_i21
#ISCELL
  pure_quanta_power universal_gnd *
  page465_i22
#CELL
  pure_quanta q_cap *
  page465_i23
#CELL
  pure_quanta q_cap *
  page465_i24
#CELL
  pure_quanta q_cap *
  page465_i25
#CELL
  pure_quanta q_cap *
  page465_i26
#CELL
  pure_quanta q_cap *
  page465_i27
#CELL
  pure_quanta q_cap *
  page465_i28
#ISCELL
  pure_quanta_power vcc_core *
  page465_i29
#ISCELL
  pure_quanta_power universal_gnd *
  page465_i3
#ISCELL
  pure_quanta_power vcc_core *
  page465_i30
#ISCELL
  pure_quanta_power universal_gnd *
  page465_i31
#CELL
  pure_quanta q_cap *
  page465_i34
#CELL
  pure_quanta q_cap *
  page465_i35
#CELL
  pure_quanta q_res *
  page465_i36
#CELL
  pure_quanta q_cap *
  page465_i37
#CELL
  pure_quanta q_cap *
  page465_i38
#CELL
  pure_quanta q_cap *
  page465_i39
#CELL
  pure_quanta q_cap *
  page465_i4
#CELL
  pure_quanta q_cap *
  page465_i40
#CELL
  pure_quanta q_cap *
  page465_i41
#CELL
  pure_quanta q_cap *
  page465_i42
#CELL
  pure_quanta q_cap *
  page465_i43
#CELL
  pure_quanta q_cap *
  page465_i44
#CELL
  pure_quanta q_cap *
  page465_i45
#CELL
  pure_quanta q_cap *
  page465_i46
#CELL
  pure_quanta q_cap *
  page465_i47
#CELL
  pure_quanta q_cap *
  page465_i48
#CELL
  pure_quanta q_cap *
  page465_i49
#ISCELL
  pure_quanta_power p1v0 *
  page465_i5
#CELL
  pure_quanta q_cap *
  page465_i50
#CELL
  pure_quanta q_cap *
  page465_i51
#CELL
  pure_quanta q_cap *
  page465_i52
#CELL
  pure_quanta q_cap *
  page465_i53
#CELL
  pure_quanta q_cap *
  page465_i54
#ISCELL
  pure_quanta_power universal_gnd *
  page465_i55
#CELL
  pure_quanta q_cap *
  page465_i56
#CELL
  pure_quanta q_cap *
  page465_i57
#CELL
  pure_quanta q_cap *
  page465_i6
#CELL
  pure_quanta q_cap *
  page465_i60
#CELL
  pure_quanta q_cap *
  page465_i61
#ISCELL
  pure_quanta_power universal_gnd *
  page465_i62
#CELL
  pure_quanta q_inductor *
  page465_i63
#CELL
  pure_quanta q_cap *
  page465_i64
#CELL
  pure_quanta q_cap *
  page465_i65
#ISCELL
  pure_quanta_power vcc_core *
  page465_i66
#CELL
  pure_quanta q_cap *
  page465_i67
#CELL
  pure_quanta q_cap *
  page465_i68
#CELL
  pure_quanta q_cap *
  page465_i69
#ISCELL
  pure_quanta_power universal_gnd *
  page465_i7
#CELL
  pure_quanta q_cap *
  page465_i70
#CELL
  pure_quanta q_cap *
  page465_i71
#CELL
  pure_quanta q_cap *
  page465_i72
#CELL
  pure_quanta q_cap *
  page465_i73
#CELL
  pure_quanta q_cap *
  page465_i74
#CELL
  pure_quanta q_cap *
  page465_i75
#CELL
  pure_quanta q_cap *
  page465_i76
#CELL
  pure_quanta q_cap *
  page465_i77
#CELL
  pure_quanta q_cap *
  page465_i78
#CELL
  pure_quanta q_cap *
  page465_i79
#CELL
  pure_quanta q_res *
  page465_i8
#CELL
  pure_quanta q_cap *
  page465_i80
#ISCELL
  pure_quanta_power universal_gnd *
  page465_i81
#CELL
  pure_quanta q_cap *
  page465_i82
#CELL
  pure_quanta q_cap *
  page465_i83
#CELL
  pure_quanta q_cap *
  page465_i84
#CELL
  pure_quanta q_cap *
  page465_i85
#CELL
  pure_quanta q_cap *
  page465_i86
#CELL
  pure_quanta q_cap *
  page465_i87
#CELL
  pure_quanta q_inductor *
  page465_i88
#CELL
  pure_quanta q_res *
  page465_i89
#CELL
  pure_quanta q_cap *
  page465_i90
#CELL
  pure_quanta q_cap *
  page465_i91
#CELL
  pure_quanta q_cap *
  page465_i92
#CELL
  pure_quanta q_cap *
  page465_i93
#CELL
  pure_quanta q_capp *
  page465_i94
#CELL
  pure_quanta q_capp *
  page465_i95
#CELL
  pure_quanta q_cap *
  page465_i96
#ISCELL
  mstr_misc dns *
  *
#ISCELL
  pure_quanta quanta_title_block_c *
  *
#ISCELL
  pure_quanta_power bom_note *
  *
#ISCELL
  pure_quanta_power universal_power *
  page466_i1
#CELL
  pure_quanta q_res *
  page466_i10
#CELL
  pure_quanta q_res *
  page466_i11
#CELL
  pure_quanta q_res *
  page466_i12
#CELL
  pure_quanta q_res *
  page466_i13
#CELL
  pure_quanta q_res *
  page466_i14
#CELL
  pure_quanta q_cap *
  page466_i15
#CELL
  pure_quanta q_res *
  page466_i17
#ISCELL
  pure_quanta_power universal_gnd *
  page466_i18
#CELL
  pure_quanta q_cap *
  page466_i19
#CELL
  pure_quanta q_res *
  page466_i2
#ISCELL
  pure_quanta_power universal_power *
  page466_i20
#ISCELL
  pure_quanta_power universal_power *
  page466_i21
#ISCELL
  pure_quanta_power universal_gnd *
  page466_i22
#CELL
  pure_quanta q_res *
  page466_i23
#ISCELL
  standard offpage *
  page466_i25
#CELL
  pure_quanta q_res *
  page466_i27
#CELL
  pure_quanta isl28022frzt *
  page466_i28
#CELL
  pure_quanta isl28022frzt *
  page466_i29
#ISCELL
  pure_quanta_power universal_power *
  page466_i3
#ISCELL
  standard offpage *
  page466_i30
#CELL
  pure_quanta q_res *
  page466_i33
#ISCELL
  pure_quanta_power universal_gnd *
  page466_i34
#ISCELL
  pure_quanta_power universal_power *
  page466_i35
#CELL
  pure_quanta q_cap *
  page466_i36
#ISCELL
  pure_quanta_power universal_gnd *
  page466_i37
#ISCELL
  pure_quanta_power universal_power *
  page466_i38
#CELL
  pure_quanta q_res *
  page466_i39
#ISCELL
  pure_quanta_power universal_gnd *
  page466_i4
#CELL
  pure_quanta q_res *
  page466_i41
#CELL
  pure_quanta q_res *
  page466_i42
#CELL
  pure_quanta q_res *
  page466_i43
#CELL
  pure_quanta q_res *
  page466_i44
#CELL
  pure_quanta q_res *
  page466_i45
#ISCELL
  pure_quanta_power universal_power *
  page466_i46
#ISCELL
  pure_quanta_power universal_gnd *
  page466_i47
#ISCELL
  standard offpage *
  page466_i48
#ISCELL
  standard offpage *
  page466_i49
#CELL
  pure_quanta q_cap *
  page466_i5
#ISCELL
  pure_quanta_power universal_power *
  page466_i50
#CELL
  pure_quanta q_cap *
  page466_i51
#ISCELL
  pure_quanta_power universal_gnd *
  page466_i52
#CELL
  pure_quanta q_res *
  page466_i53
#CELL
  pure_quanta q_cap *
  page466_i54
#CELL
  pure_quanta q_res *
  page466_i55
#ISCELL
  pure_quanta_power universal_power *
  page466_i56
#CELL
  pure_quanta isl28022frzt *
  page466_i57
#ISCELL
  pure_quanta_power universal_gnd *
  page466_i58
#ISCELL
  standard offpage *
  page466_i6
#ISCELL
  pure_quanta_power universal_power *
  page466_i60
#ISCELL
  standard offpage *
  page466_i61
#CELL
  pure_quanta q_res *
  page466_i62
#ISCELL
  pure_quanta_power universal_gnd *
  page466_i64
#ISCELL
  pure_quanta_power universal_power *
  page466_i65
#CELL
  pure_quanta q_cap *
  page466_i66
#CELL
  pure_quanta q_cap *
  page466_i68
#ISCELL
  standard offpage *
  page466_i7
#CELL
  pure_quanta q_res *
  page466_i70
#CELL
  pure_quanta q_res *
  page466_i71
#CELL
  pure_quanta q_res *
  page466_i72
#CELL
  pure_quanta q_res *
  page466_i74
#CELL
  pure_quanta q_res *
  page466_i75
#ISCELL
  pure_quanta_power universal_gnd *
  page466_i76
#ISCELL
  standard offpage *
  page466_i77
#ISCELL
  standard offpage *
  page466_i78
#ISCELL
  pure_quanta_power universal_power *
  page466_i79
#ISCELL
  pure_quanta_power universal_gnd *
  page466_i8
#ISCELL
  pure_quanta_power universal_power *
  page466_i80
#CELL
  pure_quanta q_cap *
  page466_i81
#ISCELL
  pure_quanta_power universal_gnd *
  page466_i82
#ISCELL
  pure_quanta_power universal_power *
  page466_i83
#CELL
  pure_quanta q_res *
  page466_i84
#CELL
  pure_quanta q_res *
  page466_i85
#ISCELL
  pure_quanta_power universal_power *
  page466_i86
#CELL
  pure_quanta q_res *
  page466_i87
#ISCELL
  pure_quanta_power universal_power *
  page466_i88
#ISCELL
  pure_quanta_power universal_power *
  page466_i89
#ISCELL
  pure_quanta_power universal_power *
  page466_i9
#CELL
  pure_quanta q_res *
  page466_i90
#CELL
  pure_quanta q_res *
  page466_i92
#CELL
  pure_quanta q_res *
  page466_i93
#CELL
  pure_quanta q_res *
  page466_i94
#CELL
  pure_quanta q_res *
  page466_i95
#CELL
  pure_quanta q_res *
  page466_i96
#ISCELL
  mstr_misc dns *
  *
#ISCELL
  pure_quanta quanta_title_block_c *
  *
#ISCELL
  pure_quanta_power universal_gnd *
  page467_i1
#ISCELL
  pure_quanta_power universal_power *
  page467_i10
#ISCELL
  standard offpage *
  page467_i12
#ISCELL
  standard offpage *
  page467_i13
#CELL
  pure_quanta q_res *
  page467_i2
#ISCELL
  pure_quanta_power universal_gnd *
  page467_i3
#CELL
  pure_quanta q_res *
  page467_i4
#CELL
  pure_quanta q_res *
  page467_i5
#CELL
  pure_quanta q_res *
  page467_i6
#ISCELL
  pure_quanta quanta_title_block_c *
  *
#ISCELL
  mstr_misc dns *
  *
#ISCELL
  pure_quanta quanta_title_block_c *
  *
#ISCELL
  pure_quanta_power universal_gnd *
  page469_i1
#ISCELL
  pure_quanta_power universal_gnd *
  page469_i10
#ISCELL
  pure_quanta_power universal_gnd *
  page469_i11
#CELL
  pure_quanta q_cap *
  page469_i12
#CELL
  pure_quanta q_res *
  page469_i13
#ISCELL
  mstr_symbols universal_power *
  page469_i14
#ISCELL
  pure_quanta_power universal_gnd *
  page469_i15
#CELL
  pure_quanta q_cap *
  page469_i16
#CELL
  pure_quanta q_cap *
  page469_i17
#CELL
  pure_quanta q_cap *
  page469_i18
#ISCELL
  pure_quanta_power universal_gnd *
  page469_i19
#ISCELL
  standard offpage *
  page469_i2
#CELL
  pure_quanta q_res *
  page469_i20
#CELL
  pure_quanta q_res *
  page469_i21
#CELL
  pure_quanta q_cap *
  page469_i22
#CELL
  pure_quanta q_cap *
  page469_i23
#ISCELL
  pure_quanta_power universal_gnd *
  page469_i24
#ISCELL
  pure_quanta_power universal_gnd *
  page469_i25
#CELL
  pure_quanta q_cap *
  page469_i26
#ISCELL
  pure_quanta_power universal_gnd *
  page469_i27
#CELL
  pure_quanta q_res *
  page469_i28
#CELL
  pure_quanta q_res *
  page469_i29
#ISCELL
  pure_quanta_power universal_gnd *
  page469_i3
#ISCELL
  mstr_symbols universal_power *
  page469_i30
#ISCELL
  pure_quanta_power universal_gnd *
  page469_i31
#CELL
  pure_quanta q_cap *
  page469_i32
#CELL
  pure_quanta q_res *
  page469_i33
#CELL
  pure_quanta q_cap *
  page469_i34
#CELL
  pure_quanta q_res *
  page469_i35
#CELL
  pure_quanta q_inductor *
  page469_i36
#CELL
  pure_quanta q_res *
  page469_i37
#CELL
  pure_quanta q_cap *
  page469_i38
#CELL
  pure_quanta q_cap *
  page469_i39
#CELL
  pure_quanta q_cap *
  page469_i4
#CELL
  pure_quanta q_cap *
  page469_i40
#ISCELL
  pure_quanta_power universal_gnd *
  page469_i41
#CELL
  pure_quanta q_cap *
  page469_i42
#ISCELL
  standard offpage *
  page469_i43
#CELL
  pure_quanta q_cap *
  page469_i44
#CELL
  pure_quanta q_capp *
  page469_i46
#ISCELL
  pure_quanta_power universal_gnd *
  page469_i47
#CELL
  pure_quanta q_capp *
  page469_i48
#CELL
  pure_quanta q_cap *
  page469_i49
#CELL
  pure_quanta q_cap *
  page469_i5
#ISCELL
  pure_quanta_power p1v0 *
  page469_i50
#CELL
  pure_quanta mpq8633bglec838z *
  page469_i51
#CELL
  pure_quanta q_cap *
  page469_i52
#CELL
  pure_quanta q_cap *
  page469_i56
#CELL
  pure_quanta q_cap *
  page469_i57
#CELL
  pure_quanta q_cap *
  page469_i58
#CELL
  pure_quanta q_capp *
  page469_i6
#CELL
  pure_quanta q_cap *
  page469_i7
#ISCELL
  mstr_symbols p1v0_aux *
  page469_i8
#CELL
  pure_quanta q_inductor *
  page469_i9
#ISCELL
  mstr_misc dns *
  *
#ISCELL
  pure_quanta quanta_title_block_c *
  *
#ISCELL
  standard offpage *
  page470_i1
#ISCELL
  pure_quanta_power universal_gnd *
  page470_i10
#ISCELL
  pure_quanta_power universal_gnd *
  page470_i11
#CELL
  pure_quanta q_cap *
  page470_i12
#CELL
  pure_quanta q_res *
  page470_i13
#ISCELL
  mstr_symbols universal_power *
  page470_i14
#ISCELL
  pure_quanta_power universal_gnd *
  page470_i15
#CELL
  pure_quanta q_cap *
  page470_i16
#CELL
  pure_quanta q_cap *
  page470_i17
#CELL
  pure_quanta q_cap *
  page470_i18
#ISCELL
  pure_quanta_power universal_gnd *
  page470_i19
#ISCELL
  pure_quanta_power universal_gnd *
  page470_i2
#CELL
  pure_quanta q_res *
  page470_i20
#CELL
  pure_quanta q_res *
  page470_i21
#CELL
  pure_quanta q_cap *
  page470_i22
#CELL
  pure_quanta q_cap *
  page470_i23
#ISCELL
  pure_quanta_power universal_gnd *
  page470_i24
#CELL
  pure_quanta q_cap *
  page470_i25
#ISCELL
  pure_quanta_power universal_gnd *
  page470_i26
#ISCELL
  pure_quanta_power universal_gnd *
  page470_i27
#CELL
  pure_quanta q_res *
  page470_i28
#CELL
  pure_quanta q_res *
  page470_i29
#CELL
  pure_quanta q_cap *
  page470_i3
#ISCELL
  mstr_symbols universal_power *
  page470_i30
#ISCELL
  pure_quanta_power universal_gnd *
  page470_i31
#CELL
  pure_quanta q_res *
  page470_i32
#CELL
  pure_quanta q_cap *
  page470_i33
#CELL
  pure_quanta q_res *
  page470_i34
#CELL
  pure_quanta q_cap *
  page470_i35
#CELL
  pure_quanta q_res *
  page470_i36
#CELL
  pure_quanta q_inductor *
  page470_i37
#CELL
  pure_quanta q_cap *
  page470_i38
#CELL
  pure_quanta q_cap *
  page470_i39
#ISCELL
  pure_quanta_power universal_gnd *
  page470_i4
#ISCELL
  pure_quanta_power universal_gnd *
  page470_i40
#CELL
  pure_quanta q_cap *
  page470_i41
#CELL
  pure_quanta q_cap *
  page470_i42
#ISCELL
  standard offpage *
  page470_i43
#CELL
  pure_quanta q_cap *
  page470_i44
#CELL
  pure_quanta q_cap *
  page470_i45
#CELL
  pure_quanta q_capp *
  page470_i46
#CELL
  pure_quanta q_capp *
  page470_i47
#ISCELL
  pure_quanta_power universal_gnd *
  page470_i48
#CELL
  pure_quanta q_cap *
  page470_i49
#CELL
  pure_quanta q_cap *
  page470_i5
#ISCELL
  pure_quanta_power p1v0 *
  page470_i50
#CELL
  pure_quanta mpq8633bglec838z *
  page470_i51
#CELL
  pure_quanta q_cap *
  page470_i55
#CELL
  pure_quanta q_cap *
  page470_i56
#CELL
  pure_quanta q_cap *
  page470_i57
#CELL
  pure_quanta q_capp *
  page470_i6
#CELL
  pure_quanta q_cap *
  page470_i7
#ISCELL
  mstr_symbols p1v0_aux *
  page470_i8
#CELL
  pure_quanta q_inductor *
  page470_i9
#ISCELL
  mstr_misc dns *
  *
#ISCELL
  pure_quanta quanta_title_block_c *
  *
#ISCELL
  pure_quanta_power universal_gnd *
  page475_i10
#CELL
  pure_quanta q_res *
  page475_i105
#CELL
  pure_quanta q_cap *
  page475_i118
#CELL
  pure_quanta q_res *
  page475_i119
#CELL
  pure_quanta q_res *
  page475_i120
#CELL
  pure_quanta q_cap *
  page475_i121
#CELL
  pure_quanta q_cap *
  page475_i123
#CELL
  pure_quanta q_res *
  page475_i125
#CELL
  pure_quanta q_res *
  page475_i127
#CELL
  pure_quanta q_res *
  page475_i128
#CELL
  pure_quanta q_res *
  page475_i131
#CELL
  pure_quanta q_cap *
  page475_i132
#CELL
  pure_quanta q_res *
  page475_i135
#CELL
  pure_quanta q_res *
  page475_i136
#CELL
  pure_quanta q_res *
  page475_i138
#CELL
  pure_quanta q_cap *
  page475_i144
#CELL
  pure_quanta q_cap *
  page475_i145
#CELL
  pure_quanta q_cap *
  page475_i146
#CELL
  pure_quanta q_cap *
  page475_i148
#CELL
  pure_quanta q_res *
  page475_i150
#CELL
  pure_quanta q_cap *
  page475_i151
#ISCELL
  pure_quanta_power universal_gnd *
  page475_i154
#CELL
  pure_quanta q_res *
  page475_i158
#ISCELL
  pure_quanta_power vcc15 *
  page475_i159
#ISCELL
  standard offpage *
  page475_i16
#CELL
  pure_quanta q_res *
  page475_i160
#CELL
  pure_quanta q_res *
  page475_i161
#ISCELL
  pure_quanta_power universal_gnd *
  page475_i162
#ISCELL
  pure_quanta_power vcc15 *
  page475_i164
#CELL
  pure_quanta q_res *
  page475_i165
#CELL
  pure_quanta q_res *
  page475_i166
#CELL
  pure_quanta q_res *
  page475_i167
#CELL
  pure_quanta q_res *
  page475_i168
#CELL
  pure_quanta q_res *
  page475_i169
#ISCELL
  standard offpage *
  page475_i17
#ISCELL
  pure_quanta_power universal_gnd *
  page475_i172
#ISCELL
  pure_quanta_power vcc15 *
  page475_i176
#CELL
  pure_quanta q_res *
  page475_i178
#CELL
  pure_quanta q_res *
  page475_i183
#ISCELL
  standard offpage *
  page475_i186
#ISCELL
  standard offpage *
  page475_i187
#CELL
  pure_quanta q_res *
  page475_i188
#ISCELL
  pure_quanta_power universal_gnd *
  page475_i189
#CELL
  pure_quanta q_res *
  page475_i190
#CELL
  pure_quanta q_res *
  page475_i191
#CELL
  pure_quanta q_res *
  page475_i192
#CELL
  pure_quanta q_res *
  page475_i193
#ISCELL
  pure_quanta_power universal_gnd *
  page475_i194
#ISCELL
  pure_quanta_power universal_gnd *
  page475_i195
#ISCELL
  pure_quanta_power universal_gnd *
  page475_i196
#ISCELL
  pure_quanta_power universal_gnd *
  page475_i197
#CELL
  pure_quanta q_res *
  page475_i198
#ISCELL
  pure_quanta_power universal_gnd *
  page475_i199
#ISCELL
  pure_quanta_power universal_gnd *
  page475_i2
#ISCELL
  pure_quanta_power vcc15 *
  page475_i200
#ISCELL
  pure_quanta_power universal_gnd *
  page475_i202
#ISCELL
  pure_quanta_power universal_gnd *
  page475_i203
#CELL
  pure_quanta q_res *
  page475_i204
#ISCELL
  pure_quanta_power universal_gnd *
  page475_i205
#CELL
  pure_quanta q_res *
  page475_i207
#CELL
  pure_quanta q_res *
  page475_i208
#ISCELL
  pure_quanta_power universal_gnd *
  page475_i209
#CELL
  pure_quanta q_res *
  page475_i210
#ISCELL
  pure_quanta_power vcc15 *
  page475_i211
#CELL
  pure_quanta q_res *
  page475_i212
#CELL
  pure_quanta q_res *
  page475_i213
#CELL
  pure_quanta q_short *
  page475_i214
#CELL
  pure_quanta q_short *
  page475_i215
#ISCELL
  standard offpage *
  page475_i23
#ISCELL
  standard offpage *
  page475_i24
#CELL
  pure_quanta q_res *
  page475_i32
#CELL
  pure_quanta q_res *
  page475_i34
#ISCELL
  pure_quanta_power universal_gnd *
  page475_i35
#ISCELL
  pure_quanta_power vcc15 *
  page475_i36
#ISCELL
  pure_quanta_power vcc15 *
  page475_i37
#ISCELL
  pure_quanta_power universal_gnd *
  page475_i41
#CELL
  pure_quanta isl69260irazt *
  page475_i42
#ISCELL
  pure_quanta_power universal_gnd *
  page475_i5
#ISCELL
  pure_quanta_power vcc15 *
  page475_i51
#ISCELL
  pure_quanta_power universal_gnd *
  page475_i55
#ISCELL
  pure_quanta_power universal_gnd *
  page475_i56
#ISCELL
  pure_quanta_power universal_gnd *
  page475_i58
#ISCELL
  standard offpage *
  page475_i69
#ISCELL
  pure_quanta_power vcc15 *
  page475_i74
#ISCELL
  standard offpage *
  page475_i86
#ISCELL
  standard offpage *
  page475_i88
#ISCELL
  pure_quanta_power universal_gnd *
  page475_i89
#ISCELL
  standard offpage *
  page475_i90
#ISCELL
  pure_quanta_power universal_gnd *
  page475_i91
#ISCELL
  pure_quanta_power vcc15 *
  page475_i93
#CELL
  pure_quanta q_res *
  page475_i94
#CELL
  pure_quanta q_res *
  page475_i95
#ISCELL
  mstr_misc dns *
  *
#ISCELL
  pure_quanta quanta_title_block_c *
  *
#ISCELL
  pure_quanta_power vcc15 *
  page476_i1
#CELL
  pure_quanta q_inductor *
  page476_i182
#CELL
  pure_quanta q_res *
  page476_i183
#ISCELL
  pure_quanta_power universal_power *
  page476_i184
#CELL
  pure_quanta q_res *
  page476_i185
#ISCELL
  pure_quanta_power universal_power *
  page476_i186
#CELL
  pure_quanta q_res *
  page476_i187
#ISCELL
  pure_quanta_power universal_gnd *
  page476_i188
#ISCELL
  pure_quanta_power universal_gnd *
  page476_i189
#ISCELL
  pure_quanta_power universal_gnd *
  page476_i190
#ISCELL
  pure_quanta_power universal_gnd *
  page476_i191
#ISCELL
  pure_quanta_power universal_gnd *
  page476_i192
#ISCELL
  pure_quanta_power universal_gnd *
  page476_i193
#ISCELL
  pure_quanta_power universal_gnd *
  page476_i194
#ISCELL
  pure_quanta_power universal_gnd *
  page476_i195
#ISCELL
  pure_quanta_power universal_gnd *
  page476_i196
#ISCELL
  pure_quanta_power universal_gnd *
  page476_i197
#ISCELL
  pure_quanta_power universal_gnd *
  page476_i198
#ISCELL
  pure_quanta_power universal_gnd *
  page476_i199
#CELL
  pure_quanta q_cap *
  page476_i202
#CELL
  pure_quanta q_capp *
  page476_i209
#CELL
  pure_quanta q_cap *
  page476_i21
#CELL
  pure_quanta q_cap *
  page476_i210
#ISCELL
  pure_quanta_power universal_gnd *
  page476_i211
#ISCELL
  pure_quanta_power universal_gnd *
  page476_i214
#ISCELL
  pure_quanta_power universal_gnd *
  page476_i215
#CELL
  pure_quanta q_cap *
  page476_i216
#CELL
  pure_quanta q_cap *
  page476_i217
#CELL
  pure_quanta q_res *
  page476_i220
#CELL
  pure_quanta q_res *
  page476_i221
#CELL
  pure_quanta q_capp *
  page476_i222
#CELL
  pure_quanta q_cap *
  page476_i223
#CELL
  pure_quanta q_capp *
  page476_i224
#CELL
  pure_quanta q_capp *
  page476_i225
#CELL
  pure_quanta q_capp *
  page476_i226
#CELL
  pure_quanta q_capp *
  page476_i227
#ISCELL
  pure_quanta_power vcc15 *
  page476_i23
#ISCELL
  pure_quanta_power vcc15 *
  page476_i230
#CELL
  pure_quanta q_capp *
  page476_i231
#CELL
  pure_quanta q_cap *
  page476_i232
#ISCELL
  pure_quanta_power vcc15 *
  page476_i233
#ISCELL
  pure_quanta_power universal_gnd *
  page476_i234
#CELL
  pure_quanta q_capp *
  page476_i236
#ISCELL
  pure_quanta_power universal_gnd *
  page476_i237
#CELL
  pure_quanta q_capp *
  page476_i238
#CELL
  pure_quanta q_capp *
  page476_i239
#CELL
  pure_quanta q_cap *
  page476_i24
#ISCELL
  pure_quanta_power universal_gnd *
  page476_i240
#CELL
  pure_quanta q_cap *
  page476_i241
#CELL
  pure_quanta q_cap *
  page476_i242
#CELL
  pure_quanta q_cap *
  page476_i243
#CELL
  pure_quanta q_cap *
  page476_i244
#CELL
  pure_quanta q_cap *
  page476_i245
#ISCELL
  pure_quanta_power universal_gnd *
  page476_i246
#CELL
  pure_quanta q_capp *
  page476_i247
#CELL
  pure_quanta q_capp *
  page476_i248
#ISCELL
  pure_quanta_power universal_gnd *
  page476_i249
#CELL
  pure_quanta q_cap *
  page476_i250
#CELL
  pure_quanta q_cap *
  page476_i251
#ISCELL
  pure_quanta_power universal_gnd *
  page476_i252
#CELL
  pure_quanta q_cap *
  page476_i253
#ISCELL
  pure_quanta_power universal_gnd *
  page476_i254
#CELL
  pure_quanta q_cap *
  page476_i255
#ISCELL
  pure_quanta_power universal_gnd *
  page476_i256
#CELL
  pure_quanta q_inductor *
  page476_i257
#CELL
  pure_quanta q_cap *
  page476_i258
#CELL
  pure_quanta q_cap *
  page476_i259
#ISCELL
  pure_quanta_power universal_gnd *
  page476_i260
#ISCELL
  pure_quanta_power universal_gnd *
  page476_i261
#CELL
  pure_quanta q_res *
  page476_i262
#CELL
  pure_quanta q_res *
  page476_i263
#ISCELL
  pure_quanta_power universal_gnd *
  page476_i264
#ISCELL
  pure_quanta_power universal_power *
  page476_i265
#CELL
  pure_quanta q_cap *
  page476_i267
#ISCELL
  pure_quanta_power universal_gnd *
  page476_i268
#CELL
  pure_quanta q_res *
  page476_i269
#CELL
  pure_quanta q_cap *
  page476_i27
#CELL
  pure_quanta isl99390frztr5935 *
  page476_i270
#CELL
  pure_quanta q_cap *
  page476_i271
#ISCELL
  pure_quanta_power universal_gnd *
  page476_i272
#ISCELL
  standard offpage *
  page476_i273
#ISCELL
  standard offpage *
  page476_i274
#ISCELL
  standard offpage *
  page476_i275
#CELL
  pure_quanta q_res *
  page476_i276
#ISCELL
  pure_quanta_power universal_gnd *
  page476_i277
#ISCELL
  standard offpage *
  page476_i280
#CELL
  pure_quanta q_cap *
  page476_i281
#ISCELL
  pure_quanta_power universal_gnd *
  page476_i282
#CELL
  pure_quanta q_res *
  page476_i283
#ISCELL
  pure_quanta_power universal_gnd *
  page476_i284
#CELL
  pure_quanta q_cap *
  page476_i285
#CELL
  pure_quanta q_res *
  page476_i286
#ISCELL
  pure_quanta_power universal_gnd *
  page476_i287
#CELL
  pure_quanta q_cap *
  page476_i288
#ISCELL
  pure_quanta_power universal_power *
  page476_i289
#CELL
  pure_quanta q_cap *
  page476_i29
#ISCELL
  pure_quanta_power universal_gnd *
  page476_i290
#CELL
  pure_quanta q_cap *
  page476_i291
#CELL
  pure_quanta q_cap *
  page476_i30
#CELL
  pure_quanta q_cap *
  page476_i33
#CELL
  pure_quanta q_inductor *
  page476_i34
#ISCELL
  pure_quanta_power universal_power *
  page476_i4
#CELL
  pure_quanta q_res *
  page476_i42
#CELL
  pure_quanta q_cap *
  page476_i47
#CELL
  pure_quanta q_cap *
  page476_i48
#CELL
  pure_quanta isl99390frztr5935 *
  page476_i53
#CELL
  pure_quanta q_res *
  page476_i58
#ISCELL
  standard offpage *
  page476_i59
#CELL
  pure_quanta q_cap *
  page476_i6
#ISCELL
  standard offpage *
  page476_i60
#ISCELL
  standard offpage *
  page476_i61
#ISCELL
  standard offpage *
  page476_i62
#CELL
  pure_quanta q_cap *
  page476_i68
#ISCELL
  mstr_misc dns *
  *
#ISCELL
  pure_quanta quanta_title_block_c *
  *
#ISCELL
  pure_quanta_power universal_gnd *
  page477_i1
#CELL
  pure_quanta q_res *
  page477_i10
#CELL
  pure_quanta q_res *
  page477_i11
#ISCELL
  pure_quanta_power universal_gnd *
  page477_i12
#CELL
  pure_quanta q_res *
  page477_i13
#CELL
  pure_quanta q_res *
  page477_i14
#CELL
  pure_quanta q_res *
  page477_i15
#ISCELL
  pure_quanta_power universal_gnd *
  page477_i16
#ISCELL
  pure_quanta_power vcc15 *
  page477_i17
#CELL
  pure_quanta q_res *
  page477_i2
#ISCELL
  standard offpage *
  page477_i20
#ISCELL
  standard offpage *
  page477_i21
#CELL
  pure_quanta q_res *
  page477_i22
#CELL
  pure_quanta q_res *
  page477_i23
#ISCELL
  pure_quanta_power universal_gnd *
  page477_i24
#ISCELL
  pure_quanta_power vcc15 *
  page477_i25
#ISCELL
  pure_quanta_power vcc15 *
  page477_i26
#CELL
  pure_quanta q_res *
  page477_i27
#CELL
  pure_quanta q_cap *
  page477_i28
#ISCELL
  standard offpage *
  page477_i29
#CELL
  pure_quanta q_res *
  page477_i3
#ISCELL
  standard offpage *
  page477_i30
#CELL
  pure_quanta q_res *
  page477_i31
#CELL
  pure_quanta q_res *
  page477_i32
#CELL
  pure_quanta q_res *
  page477_i33
#ISCELL
  pure_quanta_power vcc15 *
  page477_i34
#ISCELL
  pure_quanta_power vcc15 *
  page477_i35
#CELL
  pure_quanta q_res *
  page477_i36
#CELL
  pure_quanta q_res *
  page477_i37
#CELL
  pure_quanta q_res *
  page477_i38
#CELL
  pure_quanta q_res *
  page477_i39
#ISCELL
  pure_quanta_power universal_gnd *
  page477_i4
#ISCELL
  pure_quanta_power universal_gnd *
  page477_i41
#CELL
  pure_quanta q_res *
  page477_i42
#CELL
  pure_quanta q_res *
  page477_i43
#CELL
  pure_quanta q_res *
  page477_i44
#CELL
  pure_quanta q_cap *
  page477_i45
#CELL
  pure_quanta q_res *
  page477_i46
#ISCELL
  pure_quanta_power universal_gnd *
  page477_i47
#CELL
  pure_quanta q_cap *
  page477_i48
#ISCELL
  pure_quanta_power universal_gnd *
  page477_i49
#CELL
  pure_quanta q_cap *
  page477_i5
#ISCELL
  pure_quanta_power universal_gnd *
  page477_i50
#CELL
  pure_quanta q_cap *
  page477_i51
#CELL
  pure_quanta q_res *
  page477_i52
#ISCELL
  pure_quanta_power universal_gnd *
  page477_i53
#CELL
  pure_quanta q_res *
  page477_i54
#ISCELL
  pure_quanta_power universal_gnd *
  page477_i55
#CELL
  pure_quanta q_res *
  page477_i56
#CELL
  pure_quanta q_res *
  page477_i57
#CELL
  pure_quanta q_res *
  page477_i58
#ISCELL
  pure_quanta_power universal_gnd *
  page477_i59
#ISCELL
  pure_quanta_power vcc15 *
  page477_i6
#ISCELL
  pure_quanta_power universal_gnd *
  page477_i60
#ISCELL
  pure_quanta_power universal_gnd *
  page477_i61
#ISCELL
  pure_quanta_power universal_gnd *
  page477_i62
#ISCELL
  pure_quanta_power universal_gnd *
  page477_i63
#CELL
  pure_quanta q_res *
  page477_i64
#CELL
  pure_quanta q_res *
  page477_i65
#ISCELL
  pure_quanta_power universal_gnd *
  page477_i66
#ISCELL
  pure_quanta_power universal_gnd *
  page477_i67
#CELL
  pure_quanta q_res *
  page477_i68
#CELL
  pure_quanta q_res *
  page477_i69
#CELL
  pure_quanta q_res *
  page477_i7
#ISCELL
  pure_quanta_power universal_gnd *
  page477_i70
#ISCELL
  pure_quanta_power universal_gnd *
  page477_i71
#CELL
  pure_quanta q_cap *
  page477_i72
#CELL
  pure_quanta q_cap *
  page477_i73
#CELL
  pure_quanta q_cap *
  page477_i74
#CELL
  pure_quanta q_cap *
  page477_i75
#ISCELL
  standard offpage *
  page477_i76
#ISCELL
  standard offpage *
  page477_i77
#ISCELL
  standard offpage *
  page477_i78
#ISCELL
  standard offpage *
  page477_i79
#ISCELL
  pure_quanta_power vcc15 *
  page477_i8
#ISCELL
  pure_quanta_power universal_gnd *
  page477_i80
#ISCELL
  pure_quanta_power universal_gnd *
  page477_i81
#ISCELL
  standard offpage *
  page477_i82
#CELL
  pure_quanta q_res *
  page477_i83
#ISCELL
  pure_quanta_power vcc15 *
  page477_i84
#ISCELL
  standard offpage *
  page477_i85
#CELL
  pure_quanta q_res *
  page477_i86
#ISCELL
  pure_quanta_power vcc15 *
  page477_i87
#CELL
  pure_quanta isl69260irazt *
  page477_i88
#CELL
  pure_quanta q_res *
  page477_i89
#CELL
  pure_quanta q_res *
  page477_i90
#ISCELL
  pure_quanta_power universal_gnd *
  page477_i91
#CELL
  pure_quanta q_res *
  page477_i92
#CELL
  pure_quanta q_res *
  page477_i93
#ISCELL
  pure_quanta_power vcc15 *
  page477_i94
#CELL
  pure_quanta q_short *
  page477_i95
#CELL
  pure_quanta q_short *
  page477_i96
#ISCELL
  mstr_misc dns *
  *
#ISCELL
  pure_quanta quanta_title_block_c *
  *
#ISCELL
  pure_quanta_power universal_gnd *
  page478_i1
#CELL
  pure_quanta q_cap *
  page478_i10
#CELL
  pure_quanta q_cap *
  page478_i100
#ISCELL
  pure_quanta_power universal_gnd *
  page478_i101
#CELL
  pure_quanta q_capp *
  page478_i102
#ISCELL
  pure_quanta_power vcc15 *
  page478_i103
#CELL
  pure_quanta q_inductor *
  page478_i104
#ISCELL
  pure_quanta_power universal_power *
  page478_i105
#CELL
  pure_quanta q_res *
  page478_i106
#ISCELL
  pure_quanta_power universal_gnd *
  page478_i107
#CELL
  pure_quanta q_cap *
  page478_i108
#CELL
  pure_quanta q_cap *
  page478_i109
#CELL
  pure_quanta q_res *
  page478_i11
#CELL
  pure_quanta q_res *
  page478_i110
#ISCELL
  pure_quanta_power universal_gnd *
  page478_i111
#ISCELL
  pure_quanta_power universal_power *
  page478_i112
#ISCELL
  pure_quanta_power universal_gnd *
  page478_i113
#CELL
  pure_quanta q_cap *
  page478_i114
#CELL
  pure_quanta isl99390frztr5935 *
  page478_i12
#ISCELL
  pure_quanta_power universal_gnd *
  page478_i13
#CELL
  pure_quanta q_cap *
  page478_i14
#ISCELL
  pure_quanta_power universal_gnd *
  page478_i15
#CELL
  pure_quanta q_res *
  page478_i16
#ISCELL
  pure_quanta_power universal_gnd *
  page478_i17
#CELL
  pure_quanta q_cap *
  page478_i18
#CELL
  pure_quanta q_res *
  page478_i19
#CELL
  pure_quanta q_cap *
  page478_i2
#ISCELL
  pure_quanta_power universal_gnd *
  page478_i20
#CELL
  pure_quanta q_cap *
  page478_i21
#CELL
  pure_quanta q_inductor *
  page478_i22
#CELL
  pure_quanta q_cap *
  page478_i23
#ISCELL
  pure_quanta_power universal_gnd *
  page478_i24
#CELL
  pure_quanta q_cap *
  page478_i25
#CELL
  pure_quanta q_cap *
  page478_i26
#ISCELL
  pure_quanta_power universal_gnd *
  page478_i27
#CELL
  pure_quanta q_cap *
  page478_i28
#CELL
  pure_quanta q_cap *
  page478_i29
#ISCELL
  standard offpage *
  page478_i3
#CELL
  pure_quanta q_cap *
  page478_i30
#CELL
  pure_quanta q_capp *
  page478_i31
#CELL
  pure_quanta q_capp *
  page478_i32
#ISCELL
  pure_quanta_power universal_gnd *
  page478_i33
#ISCELL
  pure_quanta_power universal_gnd *
  page478_i34
#CELL
  pure_quanta q_cap *
  page478_i35
#CELL
  pure_quanta q_cap *
  page478_i36
#ISCELL
  pure_quanta_power universal_gnd *
  page478_i37
#CELL
  pure_quanta q_cap *
  page478_i38
#CELL
  pure_quanta q_cap *
  page478_i39
#ISCELL
  pure_quanta_power universal_gnd *
  page478_i4
#ISCELL
  pure_quanta_power universal_gnd *
  page478_i40
#ISCELL
  standard offpage *
  page478_i41
#CELL
  pure_quanta q_res *
  page478_i42
#ISCELL
  pure_quanta_power universal_power *
  page478_i43
#ISCELL
  pure_quanta_power universal_power *
  page478_i44
#ISCELL
  pure_quanta_power universal_gnd *
  page478_i45
#CELL
  pure_quanta q_res *
  page478_i46
#ISCELL
  standard offpage *
  page478_i47
#ISCELL
  pure_quanta_power universal_gnd *
  page478_i48
#ISCELL
  standard offpage *
  page478_i49
#CELL
  pure_quanta q_res *
  page478_i5
#ISCELL
  standard offpage *
  page478_i50
#CELL
  pure_quanta isl99390frztr5935 *
  page478_i51
#CELL
  pure_quanta q_cap *
  page478_i52
#CELL
  pure_quanta q_res *
  page478_i53
#ISCELL
  pure_quanta_power universal_gnd *
  page478_i54
#CELL
  pure_quanta q_cap *
  page478_i55
#CELL
  pure_quanta q_res *
  page478_i56
#ISCELL
  pure_quanta_power universal_power *
  page478_i57
#ISCELL
  pure_quanta_power universal_gnd *
  page478_i58
#CELL
  pure_quanta q_res *
  page478_i59
#ISCELL
  standard offpage *
  page478_i6
#ISCELL
  pure_quanta_power universal_gnd *
  page478_i60
#CELL
  pure_quanta q_cap *
  page478_i61
#CELL
  pure_quanta q_res *
  page478_i62
#ISCELL
  pure_quanta_power universal_gnd *
  page478_i63
#CELL
  pure_quanta q_cap *
  page478_i64
#CELL
  pure_quanta q_inductor *
  page478_i65
#CELL
  pure_quanta q_cap *
  page478_i66
#CELL
  pure_quanta q_cap *
  page478_i67
#CELL
  pure_quanta q_cap *
  page478_i68
#CELL
  pure_quanta q_capp *
  page478_i69
#ISCELL
  standard offpage *
  page478_i7
#CELL
  pure_quanta q_capp *
  page478_i70
#ISCELL
  pure_quanta_power universal_gnd *
  page478_i71
#CELL
  pure_quanta q_cap *
  page478_i72
#ISCELL
  pure_quanta_power universal_gnd *
  page478_i73
#CELL
  pure_quanta q_cap *
  page478_i74
#ISCELL
  pure_quanta_power universal_gnd *
  page478_i75
#CELL
  pure_quanta q_cap *
  page478_i76
#CELL
  pure_quanta q_cap *
  page478_i77
#ISCELL
  pure_quanta_power universal_gnd *
  page478_i78
#CELL
  pure_quanta q_cap *
  page478_i79
#ISCELL
  standard offpage *
  page478_i8
#CELL
  pure_quanta q_cap *
  page478_i80
#ISCELL
  pure_quanta_power universal_gnd *
  page478_i81
#CELL
  pure_quanta q_capp *
  page478_i82
#CELL
  pure_quanta q_capp *
  page478_i83
#CELL
  pure_quanta q_capp *
  page478_i84
#ISCELL
  pure_quanta_power universal_gnd *
  page478_i85
#CELL
  pure_quanta q_cap *
  page478_i86
#ISCELL
  pure_quanta_power universal_gnd *
  page478_i87
#CELL
  pure_quanta q_capp *
  page478_i88
#ISCELL
  pure_quanta_power vcc15 *
  page478_i89
#ISCELL
  pure_quanta_power universal_gnd *
  page478_i9
#ISCELL
  pure_quanta_power universal_gnd *
  page478_i90
#ISCELL
  pure_quanta_power vcc15 *
  page478_i92
#CELL
  pure_quanta q_capp *
  page478_i93
#CELL
  pure_quanta q_capp *
  page478_i94
#CELL
  pure_quanta q_capp *
  page478_i95
#ISCELL
  pure_quanta_power universal_gnd *
  page478_i96
#CELL
  pure_quanta q_res *
  page478_i97
#ISCELL
  pure_quanta_power vcc15 *
  page478_i98
#ISCELL
  pure_quanta_power universal_gnd *
  page478_i99
